G04 ================== begin FILE IDENTIFICATION RECORD ==================*
G04 Layout Name:  15968-1a.brd*
G04 Film Name:    15968-1a_X_Y*
G04 File Format:  Gerber RS274X*
G04 File Origin:  Cadence Allegro 16.5-S058*
G04 Origin Date:  Fri Oct 14 10:23:20 2016*
G04 *
G04 Layer:  BOARD GEOMETRY/PANEL_DRAWING*
G04 *
G04 Offset:    (0.00 0.00)*
G04 Mirror:    No*
G04 Mode:      Positive*
G04 Rotation:  0*
G04 FullContactRelief:  No*
G04 UndefLineWidth:     6.00*
G04 ================== end FILE IDENTIFICATION RECORD ====================*
%FSLAX35Y35*MOIN*%
%IR0*IPPOS*OFA0.00000B0.00000*MIA0B0*SFA1.00000B1.00000*%
%ADD10C,.006*%
G75*
%LPD*%
G75*
G36*
G01X109007Y-455045D02*
X105939Y-465007D01*
X109852Y-465435D01*
X109007Y-455045D01*
G37*
G36*
G01X402648Y-377363D02*
X412312Y-381271D01*
X404787Y-374057D01*
X402648Y-377363D01*
G37*
G36*
G01X472890Y-392306D02*
X462767Y-394790D01*
X473090Y-396238D01*
X472890Y-392306D01*
G37*
G36*
G01X462767Y-334670D02*
X473003Y-336638D01*
Y-332701D01*
X462767Y-334670D01*
G37*
G36*
G01X460995D02*
X450759Y-332701D01*
Y-336638D01*
X460995Y-334670D01*
G37*
G36*
G01X1527996Y54454D02*
X1533694Y63183D01*
X1530050Y64674D01*
X1527996Y54454D01*
G37*
G54D10*
G01X-214289Y-578426D02*
X1719570D01*
G01X-231611Y-595749D02*
X1736892D01*
G01X-214289Y764881D02*
Y-578426D01*
G01X-231611Y782204D02*
Y-595749D01*
G01X-227088Y-519417D02*
Y-513117D01*
X-224112D01*
G01X-225208Y-516162D02*
X-227088D01*
G01X-231611Y-398899D02*
X-214289D01*
G01X-224033Y-283196D02*
X-227167D01*
Y-276896D01*
X-224033D01*
G01X-225287Y-279941D02*
X-227167D01*
G01X-231611Y-162678D02*
X-214289D01*
G01X-227323Y-46976D02*
Y-40676D01*
X-225757D01*
X-225130Y-40991D01*
X-224660Y-41411D01*
X-224268Y-42041D01*
X-223955Y-42776D01*
X-223877Y-43826D01*
X-223955Y-44876D01*
X-224268Y-45611D01*
X-224660Y-46241D01*
X-225130Y-46661D01*
X-225757Y-46976D01*
X-227323D01*
G01X-231611Y73542D02*
X-214289D01*
G01X-223877Y195020D02*
X-224347Y195335D01*
X-224895Y195545D01*
X-225522D01*
X-226227Y195230D01*
X-226775Y194705D01*
X-227167Y194075D01*
X-227480Y193025D01*
X-227558Y192080D01*
X-227402Y191135D01*
X-227167Y190505D01*
X-226697Y189875D01*
X-226148Y189455D01*
X-225600Y189245D01*
X-225052D01*
X-224503Y189455D01*
X-224033Y189770D01*
X-223642Y190190D01*
G01X-231611Y309763D02*
X-214289D01*
G01X-224973Y428825D02*
X-224660Y429140D01*
X-224425Y429665D01*
X-224268Y430400D01*
X-224425Y431030D01*
X-224738Y431450D01*
X-225287Y431765D01*
X-227402D01*
Y425465D01*
X-224817D01*
X-224268Y425885D01*
X-223955Y426515D01*
X-223798Y427250D01*
X-223955Y427985D01*
X-224425Y428615D01*
X-224973Y428825D01*
X-227402D01*
G01X-231611Y545983D02*
X-214289D01*
G01X-227558Y661686D02*
X-225600Y667986D01*
X-223642Y661686D01*
G01X-224347Y663891D02*
X-226853D01*
G01X-214289Y764881D02*
X1719570D01*
G01X-231611Y782204D02*
X1736892D01*
G01X-147647Y-589495D02*
Y-583195D01*
X-148587Y-584455D01*
G01Y-589495D02*
X-146707D01*
G01X-140907Y260526D02*
X-139529Y260788D01*
X-137954Y261576D01*
X-136969Y262888D01*
X-136576Y264726D01*
X-136969Y266562D01*
X-138151Y268137D01*
X-139922Y268925D01*
X-141891D01*
X-143072Y269450D01*
X-144056Y270762D01*
X-144450Y272599D01*
X-143859Y274437D01*
X-142482Y275749D01*
X-140907Y276274D01*
X-139332Y275749D01*
X-137954Y274437D01*
X-137363Y272599D01*
X-137757Y270762D01*
X-138741Y269450D01*
X-139922Y268925D01*
X-141891D01*
X-143662Y268137D01*
X-144844Y266562D01*
X-145237Y264726D01*
X-144844Y262888D01*
X-143859Y261576D01*
X-142284Y260788D01*
X-140907Y260526D01*
G01X-128899Y273649D02*
X-127718Y275224D01*
X-126340Y276012D01*
X-124765Y276274D01*
X-122796Y275749D01*
X-121418Y274437D01*
X-121025Y272862D01*
X-121221Y271287D01*
X-122009Y269975D01*
X-125946Y267350D01*
X-127718Y265513D01*
X-128899Y262888D01*
X-129292Y260526D01*
X-121025D01*
G01X-109411Y260001D02*
X-109804Y260264D01*
Y260788D01*
X-109411Y261051D01*
X-109017Y260788D01*
Y260264D01*
X-109411Y260001D01*
G01X-93663Y276274D02*
X-95238Y275749D01*
X-96418Y274437D01*
X-97206Y272862D01*
X-97796Y270762D01*
X-97993Y268400D01*
X-97796Y266038D01*
X-97206Y263938D01*
X-96418Y262363D01*
X-95238Y261051D01*
X-93663Y260526D01*
X-92088Y261051D01*
X-90907Y262363D01*
X-90119Y263938D01*
X-89529Y266038D01*
X-89332Y268400D01*
X-89529Y270762D01*
X-90119Y272862D01*
X-90907Y274437D01*
X-92088Y275749D01*
X-93663Y276274D01*
G01X-81261Y262363D02*
X-79883Y261051D01*
X-78308Y260526D01*
X-76733Y261051D01*
X-75355Y262625D01*
X-74371Y264988D01*
X-73977Y267350D01*
Y270237D01*
X-74371Y272599D01*
X-75355Y274699D01*
X-76537Y275749D01*
X-77915Y276274D01*
X-79490Y275749D01*
X-80670Y274699D01*
X-81458Y273125D01*
X-81852Y271024D01*
X-81458Y269187D01*
X-80474Y267350D01*
X-79292Y266300D01*
X-77915Y266038D01*
X-76340Y266562D01*
X-75159Y267875D01*
X-73977Y270237D01*
G01X-138282Y234114D02*
X-136904Y234376D01*
X-135329Y235164D01*
X-134344Y236476D01*
X-133951Y238314D01*
X-134344Y240150D01*
X-135526Y241725D01*
X-137297Y242513D01*
X-139266D01*
X-140447Y243038D01*
X-141431Y244350D01*
X-141825Y246187D01*
X-141234Y248025D01*
X-139857Y249337D01*
X-138282Y249862D01*
X-136707Y249337D01*
X-135329Y248025D01*
X-134738Y246187D01*
X-135132Y244350D01*
X-136116Y243038D01*
X-137297Y242513D01*
X-139266D01*
X-141037Y241725D01*
X-142219Y240150D01*
X-142612Y238314D01*
X-142219Y236476D01*
X-141234Y235164D01*
X-139659Y234376D01*
X-138282Y234114D01*
G01X-122534Y249862D02*
X-124109Y249337D01*
X-125289Y248025D01*
X-126077Y246450D01*
X-126667Y244350D01*
X-126864Y241988D01*
X-126667Y239626D01*
X-126077Y237526D01*
X-125289Y235951D01*
X-124109Y234639D01*
X-122534Y234114D01*
X-120959Y234639D01*
X-119778Y235951D01*
X-118990Y237526D01*
X-118400Y239626D01*
X-118203Y241988D01*
X-118400Y244350D01*
X-118990Y246450D01*
X-119778Y248025D01*
X-120959Y249337D01*
X-122534Y249862D01*
G01X-106786Y233589D02*
X-107179Y233852D01*
Y234376D01*
X-106786Y234639D01*
X-106392Y234376D01*
Y233852D01*
X-106786Y233589D01*
G01X-91038Y249862D02*
X-92613Y249337D01*
X-93793Y248025D01*
X-94581Y246450D01*
X-95171Y244350D01*
X-95368Y241988D01*
X-95171Y239626D01*
X-94581Y237526D01*
X-93793Y235951D01*
X-92613Y234639D01*
X-91038Y234114D01*
X-89463Y234639D01*
X-88282Y235951D01*
X-87494Y237526D01*
X-86904Y239626D01*
X-86707Y241988D01*
X-86904Y244350D01*
X-87494Y246450D01*
X-88282Y248025D01*
X-89463Y249337D01*
X-91038Y249862D01*
G01X-78636Y235951D02*
X-77258Y234639D01*
X-75683Y234114D01*
X-74108Y234639D01*
X-72730Y236213D01*
X-71746Y238576D01*
X-71352Y240938D01*
Y243825D01*
X-71746Y246187D01*
X-72730Y248287D01*
X-73912Y249337D01*
X-75290Y249862D01*
X-76865Y249337D01*
X-78045Y248287D01*
X-78833Y246713D01*
X-79227Y244612D01*
X-78833Y242775D01*
X-77849Y240938D01*
X-76667Y239888D01*
X-75290Y239626D01*
X-73715Y240150D01*
X-72534Y241463D01*
X-71352Y243825D01*
G01X-148781Y555100D02*
Y570848D01*
X-151143Y567699D01*
G01Y555100D02*
X-146419D01*
G01X-136773Y561661D02*
X-135395Y563499D01*
X-134214Y564549D01*
X-132639Y565074D01*
X-131261Y564549D01*
X-130277Y563499D01*
X-129489Y561924D01*
X-129292Y560087D01*
X-129489Y558512D01*
X-130277Y556937D01*
X-131458Y555625D01*
X-132836Y555100D01*
X-134410Y555625D01*
X-135788Y557199D01*
X-136576Y559562D01*
X-136773Y562187D01*
X-136379Y565598D01*
X-135788Y567436D01*
X-134804Y569273D01*
X-133426Y570586D01*
X-132048Y570848D01*
X-130670Y570323D01*
X-129686Y569011D01*
G01X-121025Y568223D02*
X-119844Y569798D01*
X-118466Y570586D01*
X-116891Y570848D01*
X-114922Y570323D01*
X-113544Y569011D01*
X-113151Y567436D01*
X-113347Y565861D01*
X-114135Y564549D01*
X-118072Y561924D01*
X-119844Y560087D01*
X-121025Y557462D01*
X-121418Y555100D01*
X-113151D01*
G01X-101537Y554575D02*
X-101930Y554838D01*
Y555362D01*
X-101537Y555625D01*
X-101143Y555362D01*
Y554838D01*
X-101537Y554575D01*
G01X-85789Y555100D02*
Y570848D01*
X-88151Y567699D01*
G01Y555100D02*
X-83427D01*
G01X-73387Y556937D02*
X-72009Y555625D01*
X-70434Y555100D01*
X-68859Y555625D01*
X-67481Y557199D01*
X-66497Y559562D01*
X-66103Y561924D01*
Y564811D01*
X-66497Y567173D01*
X-67481Y569273D01*
X-68663Y570323D01*
X-70041Y570848D01*
X-71616Y570323D01*
X-72796Y569273D01*
X-73584Y567699D01*
X-73978Y565598D01*
X-73584Y563761D01*
X-72600Y561924D01*
X-71418Y560874D01*
X-70041Y560612D01*
X-68466Y561136D01*
X-67285Y562449D01*
X-66103Y564811D01*
G01X-147647Y771135D02*
Y777435D01*
X-148587Y776175D01*
G01Y771135D02*
X-146707D01*
G01X-58383Y-578426D02*
Y-595749D01*
G01X-119909Y-65472D02*
X-121484Y-65997D01*
X-122664Y-67309D01*
X-123452Y-68884D01*
X-124042Y-70984D01*
X-124239Y-73346D01*
X-124042Y-75708D01*
X-123452Y-77808D01*
X-122664Y-79383D01*
X-121484Y-80695D01*
X-119909Y-81220D01*
X-118334Y-80695D01*
X-117153Y-79383D01*
X-116365Y-77808D01*
X-115775Y-75708D01*
X-115578Y-73346D01*
X-115775Y-70984D01*
X-116365Y-68884D01*
X-117153Y-67309D01*
X-118334Y-65997D01*
X-119909Y-65472D01*
G01X-104161Y-81745D02*
X-104554Y-81482D01*
Y-80958D01*
X-104161Y-80695D01*
X-103767Y-80958D01*
Y-81482D01*
X-104161Y-81745D01*
G01X-88413Y-65472D02*
X-89988Y-65997D01*
X-91168Y-67309D01*
X-91956Y-68884D01*
X-92546Y-70984D01*
X-92743Y-73346D01*
X-92546Y-75708D01*
X-91956Y-77808D01*
X-91168Y-79383D01*
X-89988Y-80695D01*
X-88413Y-81220D01*
X-86838Y-80695D01*
X-85657Y-79383D01*
X-84869Y-77808D01*
X-84279Y-75708D01*
X-84082Y-73346D01*
X-84279Y-70984D01*
X-84869Y-68884D01*
X-85657Y-67309D01*
X-86838Y-65997D01*
X-88413Y-65472D01*
G01X-72665D02*
X-74240Y-65997D01*
X-75420Y-67309D01*
X-76208Y-68884D01*
X-76798Y-70984D01*
X-76995Y-73346D01*
X-76798Y-75708D01*
X-76208Y-77808D01*
X-75420Y-79383D01*
X-74240Y-80695D01*
X-72665Y-81220D01*
X-71090Y-80695D01*
X-69909Y-79383D01*
X-69121Y-77808D01*
X-68531Y-75708D01*
X-68334Y-73346D01*
X-68531Y-70984D01*
X-69121Y-68884D01*
X-69909Y-67309D01*
X-71090Y-65997D01*
X-72665Y-65472D01*
G01X-4380Y-73346D02*
X-86090D01*
G01X24220Y241988D02*
X-86090D01*
G01X-83255Y249862D02*
X-84673Y268400D01*
G01X18323Y249862D02*
X-83255D01*
G01X-84673Y268400D02*
X-86090D01*
G01X-84673Y562974D02*
X-86090D01*
G01X-83255Y565196D02*
X-84673Y562974D01*
G01X6993Y565196D02*
X-83255D01*
G01X-58383Y782204D02*
Y764881D01*
G01X9555Y-485894D02*
X13452D01*
G01X9555Y-494555D02*
Y-485894D01*
G01X13452Y-494555D02*
X9555D01*
G01X1759Y-485894D02*
X5657D01*
G01X1759Y-494555D02*
Y-485894D01*
G01X5657Y-494555D02*
X1759D01*
G01X25145Y-485894D02*
X27094D01*
G01X-5549Y-493833D02*
X-6523Y-492390D01*
G01X-4574Y-494555D02*
X-5549Y-493833D01*
G01X-3600Y-494555D02*
X-4574D01*
G01X-2626Y-493833D02*
X-3600Y-494555D01*
G01X-2138Y-493112D02*
X-2626Y-493833D01*
G01X-2138Y-491668D02*
Y-493112D01*
G01X-2626Y-490946D02*
X-2138Y-491668D01*
G01X-6036Y-488059D02*
X-5549Y-488781D01*
G01X-6036Y-487337D02*
Y-488059D01*
G01X-5549Y-486616D02*
X-6036Y-487337D01*
G01X-4574Y-485894D02*
X-5549Y-486616D01*
G01X-3600Y-485894D02*
X-4574D01*
G01X-2626Y-486616D02*
X-3600Y-485894D01*
G01X-2138Y-487337D02*
X-2626Y-486616D01*
G01X25145Y-494555D02*
Y-485894D01*
G01X27094Y-494555D02*
X25145D01*
G01X-5549Y-488781D02*
X-2626Y-490946D01*
G01X9555Y-490225D02*
X11991D01*
G01X1759D02*
X4195D01*
G01X-5168Y-73346D02*
X-32766D01*
G01X-21653Y-58346D02*
G03X-6653Y-73346I15000J0D01*
G01X65080D02*
X-6653D01*
G01X6722Y1153D02*
G03X9506Y0I2784J2784D01*
G01X1Y9504D02*
G03X1154Y6721I3937J1D01*
G01X6722Y1153D02*
G03X9506Y0I2784J2784D01*
G01X1Y9504D02*
G03X1154Y6721I3937J1D01*
G01X22009Y0D02*
X69017D01*
G01X9506D02*
X22000D01*
G01X69017D02*
X9506D01*
G01X1154Y6721D02*
X6722Y1153D01*
G01X1154Y6721D02*
X6722Y1153D01*
G01X22009Y87834D02*
Y0D01*
G01X22000Y99291D02*
Y0D01*
G01X1Y9504D02*
Y103172D01*
G01Y238051D02*
Y9504D01*
G01X9506Y0D02*
X69017D01*
G01X6722Y1153D02*
G03X9506Y0I2784J2784D01*
G01X1154Y6721D02*
X6722Y1153D01*
G01X1Y9505D02*
G03X1154Y6721I3937J0D01*
G01X1Y238051D02*
Y9505D01*
G01Y238051D02*
Y9505D01*
G01X-21653Y238051D02*
Y9505D01*
G01X1D02*
G03X1154Y6721I3937J0D01*
G01X-7873Y9505D02*
G03X-4414Y1153I11811J-1D01*
G01X1154Y6721D02*
X6722Y1153D01*
G01X-4414D02*
X1154Y-4415D01*
G01X6722Y1153D02*
G03X9506Y0I2784J2784D01*
G01X1154Y-4415D02*
G03X9506Y-7874I8351J8352D01*
G01Y0D02*
X69017D01*
G01X9506Y-7874D02*
X14917D01*
G01X-21653Y9505D02*
Y-58346D01*
G01X14917Y-7874D02*
G03Y0I0J3937D01*
G01X-7873Y50852D02*
Y9505D01*
G01X1Y103172D02*
G03Y153127I15748J24977D01*
G01Y103172D02*
G03Y153127I15748J24977D01*
G01X536663Y87834D02*
X22000D01*
G01X-7873Y81561D02*
G03X1I3937J-1D01*
G01Y50852D02*
G03X-7873I-3937J0D01*
G01Y186482D02*
Y81561D01*
G01X8849Y128150D02*
G03X22649I6900J0D01*
G01D02*
G03X8849I-6900J0D01*
G01X22649Y128149D02*
G03I-6900J0D01*
G01D02*
G03I-6900J0D01*
G01X35434D02*
G03I-19685J0D01*
G01X9843Y157080D02*
Y241988D01*
G01X1Y153127D02*
Y238051D01*
G01Y153127D02*
Y103172D01*
G01X22639Y128150D02*
G03X8859I-6890J0D01*
G01D02*
G03X22639I6890J0D01*
G01X3938Y241988D02*
G03X1Y238051I0J-3937D01*
G01X3938Y241988D02*
G03X1Y238051I0J-3937D01*
G01X102717Y241988D02*
X3938D01*
G01X602307D02*
X3938D01*
G01X13443Y249862D02*
X611812D01*
G01X10659Y251015D02*
G03X13443Y249862I2784J2784D01*
G01X1154Y260520D02*
X10659Y251015D01*
G01X3938Y241988D02*
G03X1Y238051I0J-3937D01*
G01X602307Y241988D02*
X3938D01*
G01X602307D02*
X3938D01*
G01D02*
G03X1Y238051I0J-3937D01*
G01X-7873D02*
Y217191D01*
G01X1154Y260520D02*
X10659Y251015D01*
G01D02*
G03X13443Y249862I2784J2784D01*
G01D02*
X611812D01*
G01X-21653Y238051D02*
Y534327D01*
G01X-7873Y238051D02*
Y263304D01*
G01Y217191D02*
G03X1I3937J-1D01*
G01Y186482D02*
G03X-7873I-3937J0D01*
G01X1Y321472D02*
Y617102D01*
G01Y263304D02*
G03X1154Y260520I3937J0D01*
G01X1Y328602D02*
Y263304D01*
G01X3938Y332539D02*
G03X1Y328602I0J-3937D01*
G01X53151Y332539D02*
X3938D01*
G01X53151D02*
X3938D01*
G01D02*
G03X1Y328602I0J-3937D01*
G01X3938Y340413D02*
G03X-7873Y328602I0J-11811D01*
G01X1D02*
Y263304D01*
G01X-7873Y328602D02*
Y263304D01*
G01X1D02*
G03X1154Y260520I3937J0D01*
G01X10965Y332539D02*
G03Y340413I0J3937D01*
G01X-11769Y420310D02*
Y422081D01*
G01Y421195D02*
X-5864D01*
G01Y420310D02*
Y422081D01*
G01Y425477D02*
X-11769D01*
Y426953D01*
X-11474Y427543D01*
X-11080Y427986D01*
X-10490Y428355D01*
X-9801Y428651D01*
X-8816Y428724D01*
X-7832Y428651D01*
X-7143Y428355D01*
X-6553Y427986D01*
X-6159Y427543D01*
X-5864Y426953D01*
Y425477D01*
G01X-7832Y432046D02*
Y433965D01*
G01X-11769Y437434D02*
X-5864D01*
Y440387D01*
G01Y442970D02*
X-11769Y444815D01*
X-5864Y446661D01*
G01X-7931Y445997D02*
Y443634D01*
G01X-9013Y451311D02*
X-9309Y451606D01*
X-9801Y451828D01*
X-10490Y451975D01*
X-11080Y451828D01*
X-11474Y451533D01*
X-11769Y451016D01*
Y449023D01*
X-5864D01*
Y451459D01*
X-6258Y451975D01*
X-6848Y452271D01*
X-7537Y452418D01*
X-8226Y452271D01*
X-8816Y451828D01*
X-9013Y451311D01*
Y449023D01*
G01X-5864Y458102D02*
Y455149D01*
X-11769D01*
Y458102D01*
G01X-8915Y456921D02*
Y455149D01*
G01X-11769Y461054D02*
X-5864D01*
Y464007D01*
G01X-7832Y467476D02*
Y469395D01*
G01X-5864Y474340D02*
X-11769D01*
X-10588Y473455D01*
G01X-5864D02*
Y475226D01*
G01X-8324Y478843D02*
X-9013Y479360D01*
X-9407Y479803D01*
X-9604Y480393D01*
X-9407Y480910D01*
X-9013Y481279D01*
X-8423Y481574D01*
X-7734Y481648D01*
X-7143Y481574D01*
X-6553Y481279D01*
X-6061Y480836D01*
X-5864Y480319D01*
X-6061Y479729D01*
X-6651Y479212D01*
X-7537Y478917D01*
X-8521Y478843D01*
X-9801Y478991D01*
X-10490Y479212D01*
X-11178Y479581D01*
X-11671Y480098D01*
X-11769Y480615D01*
X-11572Y481131D01*
X-11080Y481500D01*
G01X-7832Y485191D02*
Y487110D01*
G01X-11769Y490579D02*
X-5864D01*
Y493532D01*
G01X10965Y340413D02*
X3938D01*
G01X-20253Y349293D02*
X-23052D01*
G01X-20253Y380788D02*
X-23052D01*
G01X-20253Y412283D02*
X-23052D01*
G01X-20253Y443778D02*
X-23052D01*
G01X-20253Y475273D02*
X-23052D01*
G01X-21653Y547819D02*
Y619937D01*
G01X-6653Y565196D02*
G03X-21653Y550196I0J-15000D01*
G01X67796Y565196D02*
X-6653D01*
G01X-21653Y542201D02*
Y550196D01*
G01Y534327D02*
G03Y542201I0J3937D01*
G01Y538264D02*
Y537870D01*
G01Y538264D02*
Y538657D01*
G01X-22145Y538264D02*
X-21160D01*
G01X-20253Y506769D02*
X-23052D01*
G01X-21653Y534327D02*
G03Y542201I0J3937D01*
G01X22374Y621866D02*
X23686Y623047D01*
X24474Y624425D01*
X24736Y626196D01*
X24211Y627968D01*
X23162Y629346D01*
X21324Y630330D01*
X19224Y630527D01*
X17125Y630134D01*
X15812Y629149D01*
X14762Y627771D01*
X14500Y626393D01*
X14762Y625015D01*
X15812Y623244D01*
X8988Y623834D01*
Y629149D01*
G01X25261Y641944D02*
X24998Y641551D01*
X24474D01*
X24211Y641944D01*
X24474Y642338D01*
X24998D01*
X25261Y641944D01*
G01X22374Y653362D02*
X23686Y654543D01*
X24474Y655921D01*
X24736Y657692D01*
X24211Y659464D01*
X23162Y660842D01*
X21324Y661826D01*
X19224Y662023D01*
X17125Y661630D01*
X15812Y660645D01*
X14762Y659267D01*
X14500Y657889D01*
X14762Y656511D01*
X15812Y654740D01*
X8988Y655330D01*
Y660645D01*
G01Y673440D02*
X9513Y671865D01*
X10825Y670685D01*
X12400Y669897D01*
X14500Y669307D01*
X16862Y669110D01*
X19224Y669307D01*
X21324Y669897D01*
X22899Y670685D01*
X24211Y671865D01*
X24736Y673440D01*
X24211Y675015D01*
X22899Y676196D01*
X21324Y676984D01*
X19224Y677574D01*
X16862Y677771D01*
X14500Y677574D01*
X12400Y676984D01*
X10825Y676196D01*
X9513Y675015D01*
X8988Y673440D01*
G01X-29527Y626196D02*
X-29002Y624621D01*
X-27690Y623441D01*
X-26115Y622653D01*
X-24015Y622063D01*
X-21653Y621866D01*
X-19291Y622063D01*
X-17191Y622653D01*
X-15616Y623441D01*
X-14304Y624621D01*
X-13779Y626196D01*
X-14304Y627771D01*
X-15616Y628952D01*
X-17191Y629740D01*
X-19291Y630330D01*
X-21653Y630527D01*
X-24015Y630330D01*
X-26115Y629740D01*
X-27690Y628952D01*
X-29002Y627771D01*
X-29527Y626196D01*
G01X-13254Y641944D02*
X-13517Y641551D01*
X-14041D01*
X-14304Y641944D01*
X-14041Y642338D01*
X-13517D01*
X-13254Y641944D01*
G01X-29527Y657692D02*
X-29002Y656117D01*
X-27690Y654937D01*
X-26115Y654149D01*
X-24015Y653559D01*
X-21653Y653362D01*
X-19291Y653559D01*
X-17191Y654149D01*
X-15616Y654937D01*
X-14304Y656117D01*
X-13779Y657692D01*
X-14304Y659267D01*
X-15616Y660448D01*
X-17191Y661236D01*
X-19291Y661826D01*
X-21653Y662023D01*
X-24015Y661826D01*
X-26115Y661236D01*
X-27690Y660448D01*
X-29002Y659267D01*
X-29527Y657692D01*
G01Y673440D02*
X-29002Y671865D01*
X-27690Y670685D01*
X-26115Y669897D01*
X-24015Y669307D01*
X-21653Y669110D01*
X-19291Y669307D01*
X-17191Y669897D01*
X-15616Y670685D01*
X-14304Y671865D01*
X-13779Y673440D01*
X-14304Y675015D01*
X-15616Y676196D01*
X-17191Y676984D01*
X-19291Y677574D01*
X-21653Y677771D01*
X-24015Y677574D01*
X-26115Y676984D01*
X-27690Y676196D01*
X-29002Y675015D01*
X-29527Y673440D01*
G01X16862Y618520D02*
Y619937D01*
G01X1Y617102D02*
X16862Y618520D01*
G01X34093Y-584245D02*
X34563Y-583615D01*
X35111Y-583300D01*
X35738Y-583195D01*
X36521Y-583405D01*
X37069Y-583930D01*
X37226Y-584560D01*
X37148Y-585190D01*
X36834Y-585715D01*
X35268Y-586765D01*
X34563Y-587500D01*
X34093Y-588550D01*
X33936Y-589495D01*
X37226D01*
G01X105165Y-490225D02*
X93354D01*
G01X107895Y-465221D02*
X105165Y-490225D01*
G01X32940Y-485894D02*
X36838D01*
G01X32940Y-494555D02*
Y-485894D01*
G01X36838Y-494555D02*
X32940D01*
G01X28068Y-486616D02*
X29043Y-488059D01*
G01X27094Y-485894D02*
X28068Y-486616D01*
G01X29043Y-492390D02*
X28068Y-493833D01*
G01X29530Y-490225D02*
X29043Y-492390D01*
G01Y-488059D02*
X29530Y-490225D01*
G01X64122Y-494555D02*
X68019D01*
G01X64122Y-485894D02*
Y-494555D01*
G01X50480Y-485894D02*
X52916Y-494555D01*
G01X48044D02*
X50480Y-485894D01*
G01X89456D02*
X91892Y-494555D01*
G01X87020D02*
X89456Y-485894D01*
G01X28068Y-493833D02*
X27094Y-494555D01*
G01X58275Y-485894D02*
Y-494555D01*
G01X42685Y-485894D02*
Y-494555D01*
G01X40249Y-485894D02*
X45121D01*
G01X32940Y-490225D02*
X35376D01*
G01X87995Y-491668D02*
X90918D01*
G01X49018D02*
X51941D01*
G01X125828Y-439961D02*
G03I-15174J0D01*
G01X104273Y-69410D02*
X106438D01*
G01X101123D02*
X103288D01*
G01X97973D02*
X100139D01*
G01X94824D02*
X96989D01*
G01X91674D02*
X93840D01*
G01X88525D02*
X90690D01*
G01X85375D02*
X87540D01*
G01X82225D02*
X84391D01*
G01X79076D02*
X81241D01*
G01X75926D02*
X78092D01*
G01X177796Y-70278D02*
X72954D01*
G01X74922Y-73347D02*
X175828D01*
G01X74922D02*
X175828D01*
G01X106438Y-69410D02*
Y-58386D01*
G01X104273D02*
Y-69410D01*
G01X103288D02*
Y-58386D01*
G01X101123D02*
Y-69410D01*
G01X100139D02*
Y-58386D01*
G01X97973D02*
Y-69410D01*
G01X96989D02*
Y-58386D01*
G01X94824D02*
Y-69410D01*
G01X93840D02*
Y-58386D01*
G01X91674D02*
Y-69410D01*
G01X90690D02*
Y-58386D01*
G01X88525D02*
Y-69410D01*
G01X87540D02*
Y-58386D01*
G01X85375D02*
Y-69410D01*
G01X84391D02*
Y-58386D01*
G01X82225D02*
Y-69410D01*
G01X81241D02*
Y-58386D01*
G01X79076D02*
Y-69410D01*
G01X78092D02*
Y-58386D01*
G01X75926D02*
Y-69410D01*
G01X72954Y-71378D02*
Y-3937D01*
G01Y-71378D02*
Y-3937D01*
G01X74922Y-73347D02*
X72954Y-71378D01*
G01X74922Y-73347D02*
X72954Y-71378D01*
G01X74922Y-73346D02*
X175828D01*
G01X72954Y-71378D02*
X74922Y-73346D01*
G01X72954Y-3937D02*
Y-71378D01*
G01X65080Y-7874D02*
Y-71772D01*
G01D02*
Y-73346D01*
G01X72954Y-3937D02*
G03X69017Y0I-3937J0D01*
G01X72954Y-3937D02*
G03X69017Y0I-3937J0D01*
G01X74243Y-57100D02*
X74332Y-57069D01*
G01X74479Y-57160D02*
X74361Y-57250D01*
G01D02*
X74214Y-57280D01*
G01X74332Y-57069D02*
X74391Y-57009D01*
G01X122836Y-30079D02*
X72954D01*
G01X78259Y-56738D02*
X78082Y-56949D01*
G01Y-56707D02*
X78259Y-56496D01*
G01D02*
X78436D01*
G01X76251D02*
X76428D01*
G01X75247D02*
X75513D01*
G01X74834D02*
X75011D01*
G01X73505D02*
X74214D01*
G01X74243Y-56647D02*
X73682D01*
G01Y-57100D02*
X74243D01*
G01X74214Y-57280D02*
X73682D01*
G01Y-57914D02*
X73505D01*
G01X75424D02*
X75247D01*
G01X75011D02*
X74834D01*
G01X76428D02*
X76162D01*
G01X78436D02*
X78259D01*
G01X78092Y-58386D02*
X75926D01*
G01X81241D02*
X79076D01*
G01X84391D02*
X82225D01*
G01X87540D02*
X85375D01*
G01X90690D02*
X88525D01*
G01X93840D02*
X91674D01*
G01X96989D02*
X94824D01*
G01X100139D02*
X97973D01*
G01X103288D02*
X101123D01*
G01X106438D02*
X104273D01*
G01X74568Y-57039D02*
X74479Y-57160D01*
G01X74214Y-56496D02*
X74361Y-56527D01*
G01X74332Y-56677D02*
X74243Y-56647D01*
G01X74597Y-56949D02*
X74568Y-57039D01*
G01X74391Y-57009D02*
X74420Y-56919D01*
G01X78436Y-56496D02*
Y-57914D01*
G01X78259D02*
Y-56738D01*
G01X78082Y-56949D02*
Y-56707D01*
G01X76428Y-56496D02*
Y-57914D01*
G01X76251Y-57703D02*
Y-56496D01*
G01X75424Y-56677D02*
Y-57914D01*
G01X75247D02*
Y-56496D01*
G01X75011D02*
Y-57914D01*
G01X74834D02*
Y-56496D01*
G01X74597Y-56828D02*
Y-56949D01*
G01X74420Y-56919D02*
Y-56828D01*
G01X73682Y-57280D02*
Y-57914D01*
G01Y-56647D02*
Y-57100D01*
G01X73505Y-57914D02*
Y-56496D01*
G01X74568Y-56738D02*
X74597Y-56828D01*
G01X74420D02*
X74391Y-56738D01*
G01X76162Y-57914D02*
X75424Y-56677D01*
G01X75513Y-56496D02*
X76251Y-57703D01*
G01X74479Y-56617D02*
X74568Y-56738D01*
G01X74391D02*
X74332Y-56677D01*
G01X74361Y-56527D02*
X74479Y-56617D01*
G01X72954Y-3937D02*
G03X69017Y0I-3937J0D01*
G01X72954Y-3937D02*
G03X69017Y0I-3937J0D01*
G01X45626D02*
G03Y-7874I0J-3937D01*
G01D02*
X65080D01*
G01X468859Y161791D02*
X102717D01*
G01Y154409D02*
X66103D01*
G01X102717Y132362D02*
X66103D01*
G01X106136Y123760D02*
X106628D01*
G01X103347D02*
X103840D01*
G01Y122168D02*
X106136D01*
G01Y121665D02*
X103840D01*
G01Y119822D02*
X103347D01*
G01X106628D02*
X106136D01*
G01X102717Y119074D02*
X468859D01*
G01X106628Y123760D02*
Y119822D01*
G01X106136Y122168D02*
Y123760D01*
G01Y119822D02*
Y121665D01*
G01X103840D02*
Y119822D01*
G01Y123760D02*
Y122168D01*
G01X103347Y119822D02*
Y123760D01*
G01X102717Y161791D02*
Y119074D01*
G01X66103Y154409D02*
Y132362D01*
G01X468859Y242008D02*
X102717D01*
G01X66103Y234311D02*
X102717D01*
G01X66103Y212263D02*
X102717D01*
G01X105979Y203661D02*
X106471D01*
G01X103190D02*
X103682D01*
G01Y202070D02*
X105979D01*
G01Y201567D02*
X103682D01*
G01Y199724D02*
X103190D01*
G01X106471D02*
X105979D01*
G01X468859Y199055D02*
X102717D01*
G01X106471Y203661D02*
Y199724D01*
G01X105979Y202070D02*
Y203661D01*
G01Y199724D02*
Y201567D01*
G01X103682D02*
Y199724D01*
G01Y203661D02*
Y202070D01*
G01X103190Y199724D02*
Y203661D01*
G01X102717Y199055D02*
Y242008D01*
G01X66103Y234311D02*
Y212263D01*
G01X51397Y241988D02*
G03Y249862I0J3937D01*
G01X93906D02*
G03Y241988I0J-3937D01*
G01X53151Y332539D02*
G03X57088Y336476I0J3937D01*
G01Y482345D02*
Y336476D01*
G01Y482345D02*
Y336476D01*
G01X53151Y332539D02*
G03X57088Y336476I0J3937D01*
G01X41674Y340413D02*
G03Y332539I0J-3937D01*
G01X79736Y363700D02*
G03X65936I-6900J0D01*
G01D02*
G03X79736I6900J0D01*
G01X49214Y340413D02*
X41674D01*
G01X65946Y363700D02*
G03X79726I6890J0D01*
G01D02*
G03X65946I-6890J0D01*
G01X49214Y442487D02*
Y340413D01*
G01X67796Y565196D02*
Y499724D01*
G01X75670Y563228D02*
Y495787D01*
G01X58241Y485129D02*
G03X57088Y482345I2784J-2784D01*
G01X63808Y490697D02*
X58241Y485129D01*
G01X66592Y491850D02*
G03X63808Y490697I0J-3937D01*
G01X71733Y491850D02*
X66592D01*
G01X71733D02*
G03X75670Y495787I0J3937D01*
G01X67796Y499724D02*
X66592D01*
G01Y491850D02*
G03X63808Y490697I0J-3937D01*
G01X66592Y499724D02*
G03X58240Y496265I-1J-11811D01*
G01X63808Y490697D02*
X58241Y485129D01*
G01X58240Y496264D02*
X52673Y490696D01*
G01X58241Y485129D02*
G03X57088Y482345I2784J-2784D01*
G01X52673Y490697D02*
G03X49214Y482343I8352J-8351D01*
G01Y482345D02*
Y473195D01*
G01X57088Y442487D02*
G03X49214I-3937J-1D01*
G01Y473195D02*
G03X57088I3937J0D01*
G01X77639Y565196D02*
X75670Y563228D01*
G01X173111Y565196D02*
X77639D01*
G01X34093Y776385D02*
X34563Y777015D01*
X35111Y777330D01*
X35738Y777435D01*
X36521Y777225D01*
X37069Y776700D01*
X37226Y776070D01*
X37148Y775440D01*
X36834Y774915D01*
X35268Y773865D01*
X34563Y773130D01*
X34093Y772080D01*
X33936Y771135D01*
X37226D01*
G01X114845Y-578426D02*
Y-595749D01*
G01X111736Y-447699D02*
X113507Y-444630D01*
G01X113606Y-432738D02*
Y-443762D01*
G01Y-432629D02*
Y-433181D01*
G01Y-430849D02*
Y-432266D01*
G01X113507Y-132364D02*
Y-444630D01*
G01X107326Y-447699D02*
Y-132364D01*
G01D02*
Y-444630D01*
G01X107228Y-432738D02*
Y-443762D01*
G01X109098Y-447699D02*
X107326Y-444630D01*
G01X113507Y-416203D02*
X107326D01*
G01X113507Y-416990D02*
X107326D01*
G01Y-422502D02*
X113507D01*
G01Y-427226D02*
X107326D01*
G01Y-432738D02*
X107228D01*
G01X113606D02*
X113507D01*
G01Y-433526D02*
X113606D01*
G01X107326D02*
X107228D01*
G01X107326Y-443762D02*
X107228D01*
G01X113606D02*
X113507D01*
G01X112872Y-445730D02*
X107961D01*
G01X111736Y-447699D02*
X109098D01*
G01X113507Y-364848D02*
X107326D01*
G01X113507Y-367632D02*
X107326D01*
G01X113507Y-373199D02*
X107326D01*
G01X113507Y-374352D02*
X107326D01*
G01X113507Y-378289D02*
X107326D01*
G01Y-239303D02*
X113507D01*
G01X107326Y-253103D02*
X113507D01*
G01X107326Y-143022D02*
X113507D01*
G01X107326Y-145806D02*
X113507D01*
G01Y-211104D02*
X107326D01*
G01X113507Y-215041D02*
X107326D01*
G01X113507Y-218978D02*
X107326D01*
G01X113507Y-132364D02*
X107326D01*
G01X113507Y-133517D02*
X107326D01*
G01X113507Y-136301D02*
X107326D01*
G01X175828Y-73347D02*
X177796Y-71378D01*
G01X175828Y-73347D02*
X177796Y-71378D01*
G01X170414Y-69410D02*
X172580D01*
G01X167265D02*
X169430D01*
G01X164115D02*
X166280D01*
G01X160966D02*
X163131D01*
G01X157816D02*
X159981D01*
G01X154666D02*
X156832D01*
G01X151517D02*
X153682D01*
G01X148367D02*
X150532D01*
G01X145217D02*
X147383D01*
G01X142068D02*
X144233D01*
G01X138918D02*
X141084D01*
G01X135769D02*
X137934D01*
G01X132619D02*
X134784D01*
G01X129469D02*
X131635D01*
G01X126320D02*
X128485D01*
G01X123170D02*
X125336D01*
G01X120021D02*
X122186D01*
G01X116871D02*
X119036D01*
G01X113721D02*
X115887D01*
G01X110572D02*
X112737D01*
G01X107422D02*
X109588D01*
G01X175729D02*
X173564D01*
G01X177796Y-71378D02*
Y-52874D01*
G01Y-71378D02*
Y-52874D01*
G01X175729Y-58386D02*
Y-69410D01*
G01X173564D02*
Y-58386D01*
G01X172580Y-69410D02*
Y-58386D01*
G01X170414D02*
Y-69410D01*
G01X169430D02*
Y-58386D01*
G01X167265D02*
Y-69410D01*
G01X166280D02*
Y-58386D01*
G01X164115D02*
Y-69410D01*
G01X163131D02*
Y-58386D01*
G01X160966D02*
Y-69410D01*
G01X159981D02*
Y-58386D01*
G01X157816D02*
Y-69410D01*
G01X156832D02*
Y-58386D01*
G01X154666D02*
Y-69410D01*
G01X153682D02*
Y-58386D01*
G01X151517D02*
Y-69410D01*
G01X150532D02*
Y-58386D01*
G01X148367D02*
Y-69410D01*
G01X147383D02*
Y-58386D01*
G01X145217D02*
Y-69410D01*
G01X144233D02*
Y-58386D01*
G01X142068D02*
Y-69410D01*
G01X141084D02*
Y-58386D01*
G01X138918D02*
Y-69410D01*
G01X137934D02*
Y-58386D01*
G01X135769D02*
Y-69410D01*
G01X134784D02*
Y-58386D01*
G01X132619D02*
Y-69410D01*
G01X131635D02*
Y-58386D01*
G01X129469D02*
Y-69410D01*
G01X128485D02*
Y-58386D01*
G01X126320D02*
Y-69410D01*
G01X125336D02*
Y-58386D01*
G01X123170D02*
Y-69410D01*
G01X122186D02*
Y-58386D01*
G01X120021D02*
Y-69410D01*
G01X119036D02*
Y-58386D01*
G01X116871D02*
Y-69410D01*
G01X115887D02*
Y-58386D01*
G01X113721D02*
Y-69410D01*
G01X112737D02*
Y-58386D01*
G01X110572D02*
Y-69410D01*
G01X109588D02*
Y-58386D01*
G01X107422D02*
Y-69410D01*
G01X177796Y-71378D02*
Y-52874D01*
G01X175828Y-73346D02*
X177796Y-71378D01*
G01X187245Y-52874D02*
G03X177796I-4725J0D01*
G01X187245D02*
G03X177796I-4725J0D01*
G01X122836Y-3937D02*
X540080D01*
G01X173564Y-58386D02*
X175729D01*
G01X109588D02*
X107422D01*
G01X112737D02*
X110572D01*
G01X115887D02*
X113721D01*
G01X119036D02*
X116871D01*
G01X122186D02*
X120021D01*
G01X125336D02*
X123170D01*
G01X128485D02*
X126320D01*
G01X131635D02*
X129469D01*
G01X134784D02*
X132619D01*
G01X137934D02*
X135769D01*
G01X141084D02*
X138918D01*
G01X144233D02*
X142068D01*
G01X147383D02*
X145217D01*
G01X150532D02*
X148367D01*
G01X153682D02*
X151517D01*
G01X156832D02*
X154666D01*
G01X159981D02*
X157816D01*
G01X163131D02*
X160966D01*
G01X166280D02*
X164115D01*
G01X169430D02*
X167265D01*
G01X172580D02*
X170414D01*
G01X122836Y87834D02*
Y-30079D01*
G01X187245Y-52874D02*
G03X177796I-4725J0D01*
G01X172725Y145965D02*
X172736Y146012D01*
G01X172719Y146063D02*
X172725Y145965D01*
G01X172714Y146239D02*
X172719Y146063D01*
G01X172810Y148861D02*
X172812Y149826D01*
G01X172808Y148414D02*
X172810Y148861D01*
G01X172804Y148009D02*
X172808Y148414D01*
G01X172801Y147656D02*
X172804Y148009D01*
G01X172796Y147364D02*
X172801Y147656D01*
G01X172791Y147143D02*
X172796Y147364D01*
G01X172786Y146999D02*
X172791Y147143D01*
G01X172820Y148520D02*
X172823Y149807D01*
G01X172817Y147925D02*
X172820Y148520D01*
G01X172813Y147384D02*
X172817Y147925D01*
G01X172808Y146913D02*
X172813Y147384D01*
G01X172802Y146524D02*
X172808Y146913D01*
G01X172795Y146230D02*
X172802Y146524D01*
G01X172788Y146037D02*
X172795Y146230D01*
G01X172723Y144988D02*
X172738Y145050D01*
G01X172716Y145118D02*
X172723Y144988D01*
G01X172709Y145353D02*
X172716Y145118D01*
G01X174444Y144988D02*
X174458Y145353D01*
G01X174437Y144965D02*
X174444Y144988D01*
G01X174429Y145050D02*
X174437Y144965D01*
G01X174365Y146524D02*
X174379Y146037D01*
G01X174359Y146913D02*
X174365Y146524D01*
G01X174354Y147384D02*
X174359Y146913D01*
G01X174350Y147925D02*
X174354Y147384D01*
G01X174347Y148520D02*
X174350Y147925D01*
G01X174345Y149153D02*
X174347Y148520D01*
G01X174344Y149807D02*
X174345Y149153D01*
G01X174371Y147364D02*
X174381Y146999D01*
G01X174367Y147656D02*
X174371Y147364D01*
G01X174363Y148009D02*
X174367Y147656D01*
G01X174360Y148414D02*
X174363Y148009D01*
G01X174357Y148861D02*
X174360Y148414D01*
G01X174356Y149336D02*
X174357Y148861D01*
G01X174355Y149826D02*
X174356Y149336D01*
G01X174443Y145965D02*
X174453Y146239D01*
G01X174437Y145948D02*
X174443Y145965D01*
G01X174432Y146012D02*
X174437Y145948D01*
G01X174443Y140412D02*
X174432Y140365D01*
G01X174448Y140314D02*
X174443Y140412D01*
G01X174453Y140138D02*
X174448Y140314D01*
G01X174357Y137516D02*
X174355Y136551D01*
G01X174360Y137963D02*
X174357Y137516D01*
G01X174363Y138368D02*
X174360Y137963D01*
G01X174367Y138722D02*
X174363Y138368D01*
G01X174371Y139013D02*
X174367Y138722D01*
G01X174376Y139234D02*
X174371Y139013D01*
G01X174381Y139379D02*
X174376Y139234D01*
G01X174347Y137857D02*
X174344Y136570D01*
G01X174350Y138453D02*
X174347Y137857D01*
G01X174354Y138993D02*
X174350Y138453D01*
G01X174359Y139464D02*
X174354Y138993D01*
G01X174365Y139853D02*
X174359Y139464D01*
G01X174372Y140148D02*
X174365Y139853D01*
G01X174379Y140340D02*
X174372Y140148D01*
G01X174444Y141390D02*
X174429Y141327D01*
G01X174451Y141259D02*
X174444Y141390D01*
G01X174458Y141024D02*
X174451Y141259D01*
G01X172723Y141390D02*
X172709Y141024D01*
G01X172731Y141412D02*
X172723Y141390D01*
G01X172738Y141327D02*
X172731Y141412D01*
G01X172802Y139853D02*
X172788Y140340D01*
G01X172808Y139464D02*
X172802Y139853D01*
G01X172813Y138993D02*
X172808Y139464D01*
G01X172817Y138453D02*
X172813Y138993D01*
G01X172820Y137857D02*
X172817Y138453D01*
G01X172822Y137224D02*
X172820Y137857D01*
G01X172823Y136570D02*
X172822Y137224D01*
G01X172796Y139013D02*
X172786Y139379D01*
G01X172801Y138722D02*
X172796Y139013D01*
G01X172804Y138368D02*
X172801Y138722D01*
G01X172808Y137963D02*
X172804Y138368D01*
G01X172810Y137516D02*
X172808Y137963D01*
G01X172811Y137041D02*
X172810Y137516D01*
G01X172812Y136551D02*
X172811Y137041D01*
G01X172725Y140412D02*
X172714Y140138D01*
G01X172730Y140429D02*
X172725Y140412D01*
G01X172736Y140365D02*
X172730Y140429D01*
G01X135073Y140412D02*
X135062Y140365D01*
G01X135078Y140314D02*
X135073Y140412D01*
G01X135083Y140138D02*
X135078Y140314D01*
G01X134987Y137516D02*
X134985Y136551D01*
G01X134990Y137963D02*
X134987Y137516D01*
G01X134993Y138368D02*
X134990Y137963D01*
G01X134997Y138722D02*
X134993Y138368D01*
G01X135001Y139013D02*
X134997Y138722D01*
G01X135006Y139234D02*
X135001Y139013D01*
G01X135011Y139379D02*
X135006Y139234D01*
G01X134977Y137857D02*
X134974Y136570D01*
G01X134980Y138453D02*
X134977Y137857D01*
G01X134984Y138993D02*
X134980Y138453D01*
G01X134989Y139464D02*
X134984Y138993D01*
G01X134995Y139853D02*
X134989Y139464D01*
G01X135002Y140148D02*
X134995Y139853D01*
G01X135009Y140340D02*
X135002Y140148D01*
G01X135074Y141390D02*
X135059Y141327D01*
G01X135081Y141259D02*
X135074Y141390D01*
G01X135088Y141024D02*
X135081Y141259D01*
G01X133353Y141390D02*
X133339Y141024D01*
G01X133361Y141412D02*
X133353Y141390D01*
G01X133368Y141327D02*
X133361Y141412D01*
G01X133432Y139853D02*
X133418Y140340D01*
G01X133438Y139464D02*
X133432Y139853D01*
G01X133443Y138993D02*
X133438Y139464D01*
G01X133447Y138453D02*
X133443Y138993D01*
G01X133450Y137857D02*
X133447Y138453D01*
G01X133452Y137224D02*
X133450Y137857D01*
G01X133453Y136570D02*
X133452Y137224D01*
G01X133426Y139013D02*
X133416Y139379D01*
G01X133431Y138722D02*
X133426Y139013D01*
G01X133434Y138368D02*
X133431Y138722D01*
G01X133438Y137963D02*
X133434Y138368D01*
G01X133440Y137516D02*
X133438Y137963D01*
G01X133441Y137041D02*
X133440Y137516D01*
G01X133442Y136551D02*
X133441Y137041D01*
G01X133355Y140412D02*
X133344Y140138D01*
G01X133360Y140429D02*
X133355Y140412D01*
G01X133365Y140365D02*
X133360Y140429D01*
G01X133355Y145965D02*
X133365Y146012D01*
G01X133349Y146063D02*
X133355Y145965D01*
G01X133344Y146239D02*
X133349Y146063D01*
G01X133440Y148861D02*
X133442Y149826D01*
G01X133438Y148414D02*
X133440Y148861D01*
G01X133434Y148009D02*
X133438Y148414D01*
G01X133431Y147656D02*
X133434Y148009D01*
G01X133426Y147364D02*
X133431Y147656D01*
G01X133421Y147143D02*
X133426Y147364D01*
G01X133416Y146999D02*
X133421Y147143D01*
G01X133450Y148520D02*
X133453Y149807D01*
G01X133447Y147925D02*
X133450Y148520D01*
G01X133443Y147384D02*
X133447Y147925D01*
G01X133438Y146913D02*
X133443Y147384D01*
G01X133432Y146524D02*
X133438Y146913D01*
G01X133425Y146230D02*
X133432Y146524D01*
G01X133418Y146037D02*
X133425Y146230D01*
G01X133353Y144988D02*
X133368Y145050D01*
G01X133346Y145118D02*
X133353Y144988D01*
G01X133339Y145353D02*
X133346Y145118D01*
G01X135074Y144988D02*
X135088Y145353D01*
G01X135067Y144965D02*
X135074Y144988D01*
G01X135059Y145050D02*
X135067Y144965D01*
G01X134995Y146524D02*
X135009Y146037D01*
G01X134989Y146913D02*
X134995Y146524D01*
G01X134984Y147384D02*
X134989Y146913D01*
G01X134980Y147925D02*
X134984Y147384D01*
G01X134977Y148520D02*
X134980Y147925D01*
G01X134975Y149153D02*
X134977Y148520D01*
G01X134974Y149807D02*
X134975Y149153D01*
G01X135001Y147364D02*
X135011Y146999D01*
G01X134997Y147656D02*
X135001Y147364D01*
G01X134993Y148009D02*
X134997Y147656D01*
G01X134990Y148414D02*
X134993Y148009D01*
G01X134987Y148861D02*
X134990Y148414D01*
G01X134986Y149336D02*
X134987Y148861D01*
G01X134985Y149826D02*
X134986Y149336D01*
G01X135073Y145965D02*
X135083Y146239D01*
G01X135067Y145948D02*
X135073Y145965D01*
G01X135062Y146012D02*
X135067Y145948D01*
G01X139005Y140412D02*
X138994Y140365D01*
G01X139010Y140314D02*
X139005Y140412D01*
G01X139015Y140138D02*
X139010Y140314D01*
G01X138920Y137516D02*
X138918Y136551D01*
G01X138922Y137963D02*
X138920Y137516D01*
G01X138925Y138368D02*
X138922Y137963D01*
G01X138929Y138722D02*
X138925Y138368D01*
G01X138933Y139013D02*
X138929Y138722D01*
G01X138938Y139234D02*
X138933Y139013D01*
G01X138943Y139379D02*
X138938Y139234D01*
G01X138916Y135857D02*
X138918Y136551D01*
G01X138914Y135540D02*
X138916Y135857D01*
G01X138912Y135257D02*
X138914Y135540D01*
G01X138909Y135018D02*
X138912Y135257D01*
G01X138905Y134830D02*
X138909Y135018D01*
G01X138902Y134700D02*
X138905Y134830D01*
G01X138898Y134632D02*
X138902Y134700D01*
G01X138894Y134627D02*
X138898Y134632D01*
G01X138909Y137857D02*
X138907Y136570D01*
G01X138912Y138453D02*
X138909Y137857D01*
G01X138917Y138993D02*
X138912Y138453D01*
G01X138922Y139464D02*
X138917Y138993D01*
G01X138928Y139853D02*
X138922Y139464D01*
G01X138934Y140148D02*
X138928Y139853D01*
G01X138941Y140340D02*
X138934Y140148D01*
G01X139006Y141390D02*
X138992Y141327D01*
G01X139013Y141259D02*
X139006Y141390D01*
G01X139020Y141024D02*
X139013Y141259D01*
G01X137286Y141390D02*
X137272Y141024D01*
G01X137293Y141412D02*
X137286Y141390D01*
G01X137300Y141327D02*
X137293Y141412D01*
G01X137364Y139853D02*
X137351Y140340D01*
G01X137370Y139464D02*
X137364Y139853D01*
G01X137375Y138993D02*
X137370Y139464D01*
G01X137379Y138453D02*
X137375Y138993D01*
G01X137382Y137857D02*
X137379Y138453D01*
G01X137384Y137224D02*
X137382Y137857D01*
G01X137385Y136570D02*
X137384Y137224D01*
G01X137390Y134700D02*
X137398Y134627D01*
G01X137386Y134830D02*
X137390Y134700D01*
G01X137383Y135018D02*
X137386Y134830D01*
G01X137380Y135257D02*
X137383Y135018D01*
G01X137378Y135540D02*
X137380Y135257D01*
G01X137376Y135857D02*
X137378Y135540D01*
G01X137375Y136198D02*
X137376Y135857D01*
G01X137374Y136551D02*
X137375Y136198D01*
G01X137358Y139013D02*
X137348Y139379D01*
G01X137363Y138722D02*
X137358Y139013D01*
G01X137367Y138368D02*
X137363Y138722D01*
G01X137370Y137963D02*
X137367Y138368D01*
G01X137372Y137516D02*
X137370Y137963D01*
G01X137374Y137041D02*
X137372Y137516D01*
G01X137374Y136551D02*
Y137041D01*
G01X137287Y140412D02*
X137276Y140138D01*
G01X137292Y140429D02*
X137287Y140412D01*
G01X137298Y140365D02*
X137292Y140429D01*
G01X137296Y145965D02*
X137307Y146012D01*
G01X137291Y146063D02*
X137296Y145965D01*
G01X137286Y146239D02*
X137291Y146063D01*
G01X137382Y148861D02*
X137384Y149826D01*
G01X137379Y148414D02*
X137382Y148861D01*
G01X137376Y148009D02*
X137379Y148414D01*
G01X137372Y147656D02*
X137376Y148009D01*
G01X137368Y147364D02*
X137372Y147656D01*
G01X137363Y147143D02*
X137368Y147364D01*
G01X137358Y146999D02*
X137363Y147143D01*
G01X137385Y150521D02*
X137384Y149826D01*
G01X137387Y150838D02*
X137385Y150521D01*
G01X137389Y151120D02*
X137387Y150838D01*
G01X137392Y151359D02*
X137389Y151120D01*
G01X137396Y151547D02*
X137392Y151359D01*
G01X137399Y151677D02*
X137396Y151547D01*
G01X137403Y151746D02*
X137399Y151677D01*
G01X137407Y151750D02*
X137403Y151746D01*
G01X137392Y148520D02*
X137395Y149807D01*
G01X137389Y147925D02*
X137392Y148520D01*
G01X137385Y147384D02*
X137389Y147925D01*
G01X137379Y146913D02*
X137385Y147384D01*
G01X137374Y146524D02*
X137379Y146913D01*
G01X137367Y146230D02*
X137374Y146524D01*
G01X137360Y146037D02*
X137367Y146230D01*
G01X137295Y144988D02*
X137309Y145050D01*
G01X137288Y145118D02*
X137295Y144988D01*
G01X137281Y145353D02*
X137288Y145118D01*
G01X139015Y144988D02*
X139029Y145353D01*
G01X139008Y144965D02*
X139015Y144988D01*
G01X139001Y145050D02*
X139008Y144965D01*
G01X138937Y146524D02*
X138950Y146037D01*
G01X138931Y146913D02*
X138937Y146524D01*
G01X138926Y147384D02*
X138931Y146913D01*
G01X138922Y147925D02*
X138926Y147384D01*
G01X138919Y148520D02*
X138922Y147925D01*
G01X138917Y149153D02*
X138919Y148520D01*
G01X138916Y149807D02*
X138917Y149153D01*
G01X138911Y151677D02*
X138903Y151750D01*
G01X138915Y151547D02*
X138911Y151677D01*
G01X138918Y151359D02*
X138915Y151547D01*
G01X138921Y151120D02*
X138918Y151359D01*
G01X138924Y150838D02*
X138921Y151120D01*
G01X138925Y150521D02*
X138924Y150838D01*
G01X138926Y150180D02*
X138925Y150521D01*
G01X138927Y149826D02*
X138926Y150180D01*
G01X138943Y147364D02*
X138953Y146999D01*
G01X138938Y147656D02*
X138943Y147364D01*
G01X138934Y148009D02*
X138938Y147656D01*
G01X138931Y148414D02*
X138934Y148009D01*
G01X138929Y148861D02*
X138931Y148414D01*
G01X138927Y149336D02*
X138929Y148861D01*
G01X138927Y149826D02*
Y149336D01*
G01X139014Y145965D02*
X139025Y146239D01*
G01X139009Y145948D02*
X139014Y145965D01*
G01X139003Y146012D02*
X139009Y145948D01*
G01X142947Y140412D02*
X142936Y140365D01*
G01X142952Y140314D02*
X142947Y140412D01*
G01X142957Y140138D02*
X142952Y140314D01*
G01X142861Y137516D02*
X142859Y136551D01*
G01X142864Y137963D02*
X142861Y137516D01*
G01X142867Y138368D02*
X142864Y137963D01*
G01X142871Y138722D02*
X142867Y138368D01*
G01X142875Y139013D02*
X142871Y138722D01*
G01X142880Y139234D02*
X142875Y139013D01*
G01X142885Y139379D02*
X142880Y139234D01*
G01X142851Y137857D02*
X142848Y136570D01*
G01X142854Y138453D02*
X142851Y137857D01*
G01X142858Y138993D02*
X142854Y138453D01*
G01X142863Y139464D02*
X142858Y138993D01*
G01X142869Y139853D02*
X142863Y139464D01*
G01X142876Y140148D02*
X142869Y139853D01*
G01X142883Y140340D02*
X142876Y140148D01*
G01X142948Y141390D02*
X142933Y141327D01*
G01X142955Y141259D02*
X142948Y141390D01*
G01X142962Y141024D02*
X142955Y141259D01*
G01X141227Y141390D02*
X141213Y141024D01*
G01X141235Y141412D02*
X141227Y141390D01*
G01X141242Y141327D02*
X141235Y141412D01*
G01X141306Y139853D02*
X141292Y140340D01*
G01X141312Y139464D02*
X141306Y139853D01*
G01X141317Y138993D02*
X141312Y139464D01*
G01X141321Y138453D02*
X141317Y138993D01*
G01X141324Y137857D02*
X141321Y138453D01*
G01X141326Y137224D02*
X141324Y137857D01*
G01X141327Y136570D02*
X141326Y137224D01*
G01X141300Y139013D02*
X141290Y139379D01*
G01X141305Y138722D02*
X141300Y139013D01*
G01X141308Y138368D02*
X141305Y138722D01*
G01X141312Y137963D02*
X141308Y138368D01*
G01X141314Y137516D02*
X141312Y137963D01*
G01X141315Y137041D02*
X141314Y137516D01*
G01X141316Y136551D02*
X141315Y137041D01*
G01X141229Y140412D02*
X141218Y140138D01*
G01X141234Y140429D02*
X141229Y140412D01*
G01X141239Y140365D02*
X141234Y140429D01*
G01X141229Y145965D02*
X141239Y146012D01*
G01X141223Y146063D02*
X141229Y145965D01*
G01X141218Y146239D02*
X141223Y146063D01*
G01X141314Y148861D02*
X141316Y149826D01*
G01X141312Y148414D02*
X141314Y148861D01*
G01X141308Y148009D02*
X141312Y148414D01*
G01X141305Y147656D02*
X141308Y148009D01*
G01X141300Y147364D02*
X141305Y147656D01*
G01X141295Y147143D02*
X141300Y147364D01*
G01X141290Y146999D02*
X141295Y147143D01*
G01X141324Y148520D02*
X141327Y149807D01*
G01X141321Y147925D02*
X141324Y148520D01*
G01X141317Y147384D02*
X141321Y147925D01*
G01X141312Y146913D02*
X141317Y147384D01*
G01X141306Y146524D02*
X141312Y146913D01*
G01X141299Y146230D02*
X141306Y146524D01*
G01X141292Y146037D02*
X141299Y146230D01*
G01X141227Y144988D02*
X141242Y145050D01*
G01X141220Y145118D02*
X141227Y144988D01*
G01X141213Y145353D02*
X141220Y145118D01*
G01X142948Y144988D02*
X142962Y145353D01*
G01X142941Y144965D02*
X142948Y144988D01*
G01X142933Y145050D02*
X142941Y144965D01*
G01X142869Y146524D02*
X142883Y146037D01*
G01X142863Y146913D02*
X142869Y146524D01*
G01X142858Y147384D02*
X142863Y146913D01*
G01X142854Y147925D02*
X142858Y147384D01*
G01X142851Y148520D02*
X142854Y147925D01*
G01X142849Y149153D02*
X142851Y148520D01*
G01X142848Y149807D02*
X142849Y149153D01*
G01X142875Y147364D02*
X142885Y146999D01*
G01X142871Y147656D02*
X142875Y147364D01*
G01X142867Y148009D02*
X142871Y147656D01*
G01X142864Y148414D02*
X142867Y148009D01*
G01X142861Y148861D02*
X142864Y148414D01*
G01X142860Y149336D02*
X142861Y148861D01*
G01X142859Y149826D02*
X142860Y149336D01*
G01X142947Y145965D02*
X142957Y146239D01*
G01X142941Y145948D02*
X142947Y145965D01*
G01X142936Y146012D02*
X142941Y145948D01*
G01X146879Y140412D02*
X146868Y140365D01*
G01X146884Y140314D02*
X146879Y140412D01*
G01X146889Y140138D02*
X146884Y140314D01*
G01X146794Y137516D02*
X146792Y136551D01*
G01X146796Y137963D02*
X146794Y137516D01*
G01X146799Y138368D02*
X146796Y137963D01*
G01X146803Y138722D02*
X146799Y138368D01*
G01X146807Y139013D02*
X146803Y138722D01*
G01X146812Y139234D02*
X146807Y139013D01*
G01X146817Y139379D02*
X146812Y139234D01*
G01X146790Y135857D02*
X146792Y136551D01*
G01X146788Y135540D02*
X146790Y135857D01*
G01X146786Y135257D02*
X146788Y135540D01*
G01X146783Y135018D02*
X146786Y135257D01*
G01X146779Y134830D02*
X146783Y135018D01*
G01X146776Y134700D02*
X146779Y134830D01*
G01X146772Y134632D02*
X146776Y134700D01*
G01X146768Y134627D02*
X146772Y134632D01*
G01X146783Y137857D02*
X146781Y136570D01*
G01X146786Y138453D02*
X146783Y137857D01*
G01X146791Y138993D02*
X146786Y138453D01*
G01X146796Y139464D02*
X146791Y138993D01*
G01X146802Y139853D02*
X146796Y139464D01*
G01X146808Y140148D02*
X146802Y139853D01*
G01X146815Y140340D02*
X146808Y140148D01*
G01X146880Y141390D02*
X146866Y141327D01*
G01X146887Y141259D02*
X146880Y141390D01*
G01X146894Y141024D02*
X146887Y141259D01*
G01X145160Y141390D02*
X145146Y141024D01*
G01X145167Y141412D02*
X145160Y141390D01*
G01X145174Y141327D02*
X145167Y141412D01*
G01X145238Y139853D02*
X145225Y140340D01*
G01X145244Y139464D02*
X145238Y139853D01*
G01X145249Y138993D02*
X145244Y139464D01*
G01X145253Y138453D02*
X145249Y138993D01*
G01X145257Y137857D02*
X145253Y138453D01*
G01X145258Y137224D02*
X145257Y137857D01*
G01X145259Y136570D02*
X145258Y137224D01*
G01X145264Y134700D02*
X145272Y134627D01*
G01X145260Y134830D02*
X145264Y134700D01*
G01X145257Y135018D02*
X145260Y134830D01*
G01X145254Y135257D02*
X145257Y135018D01*
G01X145252Y135540D02*
X145254Y135257D01*
G01X145250Y135857D02*
X145252Y135540D01*
G01X145249Y136198D02*
X145250Y135857D01*
G01X145248Y136551D02*
X145249Y136198D01*
G01X145232Y139013D02*
X145222Y139379D01*
G01X145237Y138722D02*
X145232Y139013D01*
G01X145241Y138368D02*
X145237Y138722D01*
G01X145244Y137963D02*
X145241Y138368D01*
G01X145246Y137516D02*
X145244Y137963D01*
G01X145248Y137041D02*
X145246Y137516D01*
G01X145248Y136551D02*
Y137041D01*
G01X145161Y140412D02*
X145151Y140138D01*
G01X145166Y140429D02*
X145161Y140412D01*
G01X145172Y140365D02*
X145166Y140429D01*
G01X145170Y145965D02*
X145181Y146012D01*
G01X145165Y146063D02*
X145170Y145965D01*
G01X145160Y146239D02*
X145165Y146063D01*
G01X145256Y148861D02*
X145258Y149826D01*
G01X145253Y148414D02*
X145256Y148861D01*
G01X145250Y148009D02*
X145253Y148414D01*
G01X145246Y147656D02*
X145250Y148009D01*
G01X145242Y147364D02*
X145246Y147656D01*
G01X145237Y147143D02*
X145242Y147364D01*
G01X145232Y146999D02*
X145237Y147143D01*
G01X145259Y150521D02*
X145258Y149826D01*
G01X145261Y150838D02*
X145259Y150521D01*
G01X145263Y151120D02*
X145261Y150838D01*
G01X145266Y151359D02*
X145263Y151120D01*
G01X145270Y151547D02*
X145266Y151359D01*
G01X145273Y151677D02*
X145270Y151547D01*
G01X145277Y151746D02*
X145273Y151677D01*
G01X145281Y151750D02*
X145277Y151746D01*
G01X145266Y148520D02*
X145269Y149807D01*
G01X145263Y147925D02*
X145266Y148520D01*
G01X145259Y147384D02*
X145263Y147925D01*
G01X145253Y146913D02*
X145259Y147384D01*
G01X145248Y146524D02*
X145253Y146913D01*
G01X145241Y146230D02*
X145248Y146524D01*
G01X145234Y146037D02*
X145241Y146230D01*
G01X145169Y144988D02*
X145184Y145050D01*
G01X145162Y145118D02*
X145169Y144988D01*
G01X145155Y145353D02*
X145162Y145118D01*
G01X146889Y144988D02*
X146903Y145353D01*
G01X146882Y144965D02*
X146889Y144988D01*
G01X146875Y145050D02*
X146882Y144965D01*
G01X146811Y146524D02*
X146825Y146037D01*
G01X146805Y146913D02*
X146811Y146524D01*
G01X146800Y147384D02*
X146805Y146913D01*
G01X146796Y147925D02*
X146800Y147384D01*
G01X146793Y148520D02*
X146796Y147925D01*
G01X146791Y149153D02*
X146793Y148520D01*
G01X146790Y149807D02*
X146791Y149153D01*
G01X146785Y151677D02*
X146777Y151750D01*
G01X146789Y151547D02*
X146785Y151677D01*
G01X146792Y151359D02*
X146789Y151547D01*
G01X146795Y151120D02*
X146792Y151359D01*
G01X146798Y150838D02*
X146795Y151120D01*
G01X146799Y150521D02*
X146798Y150838D01*
G01X146801Y150180D02*
X146799Y150521D01*
G01X146801Y149826D02*
Y150180D01*
G01X146817Y147364D02*
X146827Y146999D01*
G01X146812Y147656D02*
X146817Y147364D01*
G01X146808Y148009D02*
X146812Y147656D01*
G01X146805Y148414D02*
X146808Y148009D01*
G01X146803Y148861D02*
X146805Y148414D01*
G01X146801Y149336D02*
X146803Y148861D01*
G01X146801Y149826D02*
Y149336D01*
G01X146888Y145965D02*
X146899Y146239D01*
G01X146883Y145948D02*
X146888Y145965D01*
G01X146877Y146012D02*
X146883Y145948D01*
G01X150821Y140412D02*
X150810Y140365D01*
G01X150826Y140314D02*
X150821Y140412D01*
G01X150831Y140138D02*
X150826Y140314D01*
G01X150735Y137516D02*
X150733Y136551D01*
G01X150738Y137963D02*
X150735Y137516D01*
G01X150741Y138368D02*
X150738Y137963D01*
G01X150745Y138722D02*
X150741Y138368D01*
G01X150749Y139013D02*
X150745Y138722D01*
G01X150754Y139234D02*
X150749Y139013D01*
G01X150759Y139379D02*
X150754Y139234D01*
G01X150725Y137857D02*
X150722Y136570D01*
G01X150728Y138453D02*
X150725Y137857D01*
G01X150732Y138993D02*
X150728Y138453D01*
G01X150737Y139464D02*
X150732Y138993D01*
G01X150743Y139853D02*
X150737Y139464D01*
G01X150750Y140148D02*
X150743Y139853D01*
G01X150757Y140340D02*
X150750Y140148D01*
G01X150822Y141390D02*
X150807Y141327D01*
G01X150829Y141259D02*
X150822Y141390D01*
G01X150836Y141024D02*
X150829Y141259D01*
G01X149101Y141390D02*
X149087Y141024D01*
G01X149109Y141412D02*
X149101Y141390D01*
G01X149116Y141327D02*
X149109Y141412D01*
G01X149180Y139853D02*
X149166Y140340D01*
G01X149186Y139464D02*
X149180Y139853D01*
G01X149191Y138993D02*
X149186Y139464D01*
G01X149195Y138453D02*
X149191Y138993D01*
G01X149198Y137857D02*
X149195Y138453D01*
G01X149200Y137224D02*
X149198Y137857D01*
G01X149201Y136570D02*
X149200Y137224D01*
G01X149174Y139013D02*
X149164Y139379D01*
G01X149179Y138722D02*
X149174Y139013D01*
G01X149182Y138368D02*
X149179Y138722D01*
G01X149186Y137963D02*
X149182Y138368D01*
G01X149188Y137516D02*
X149186Y137963D01*
G01X149189Y137041D02*
X149188Y137516D01*
G01X149190Y136551D02*
X149189Y137041D01*
G01X149103Y140412D02*
X149092Y140138D01*
G01X149108Y140429D02*
X149103Y140412D01*
G01X149114Y140365D02*
X149108Y140429D01*
G01X149103Y145965D02*
X149114Y146012D01*
G01X149097Y146063D02*
X149103Y145965D01*
G01X149092Y146239D02*
X149097Y146063D01*
G01X149188Y148861D02*
X149190Y149826D01*
G01X149186Y148414D02*
X149188Y148861D01*
G01X149182Y148009D02*
X149186Y148414D01*
G01X149179Y147656D02*
X149182Y148009D01*
G01X149174Y147364D02*
X149179Y147656D01*
G01X149169Y147143D02*
X149174Y147364D01*
G01X149164Y146999D02*
X149169Y147143D01*
G01X149198Y148520D02*
X149201Y149807D01*
G01X149195Y147925D02*
X149198Y148520D01*
G01X149191Y147384D02*
X149195Y147925D01*
G01X149186Y146913D02*
X149191Y147384D01*
G01X149180Y146524D02*
X149186Y146913D01*
G01X149173Y146230D02*
X149180Y146524D01*
G01X149166Y146037D02*
X149173Y146230D01*
G01X149101Y144988D02*
X149116Y145050D01*
G01X149094Y145118D02*
X149101Y144988D01*
G01X149087Y145353D02*
X149094Y145118D01*
G01X150822Y144988D02*
X150836Y145353D01*
G01X150815Y144965D02*
X150822Y144988D01*
G01X150807Y145050D02*
X150815Y144965D01*
G01X150743Y146524D02*
X150757Y146037D01*
G01X150737Y146913D02*
X150743Y146524D01*
G01X150732Y147384D02*
X150737Y146913D01*
G01X150728Y147925D02*
X150732Y147384D01*
G01X150725Y148520D02*
X150728Y147925D01*
G01X150723Y149153D02*
X150725Y148520D01*
G01X150722Y149807D02*
X150723Y149153D01*
G01X150749Y147364D02*
X150759Y146999D01*
G01X150745Y147656D02*
X150749Y147364D01*
G01X150741Y148009D02*
X150745Y147656D01*
G01X150738Y148414D02*
X150741Y148009D01*
G01X150735Y148861D02*
X150738Y148414D01*
G01X150734Y149336D02*
X150735Y148861D01*
G01X150733Y149826D02*
X150734Y149336D01*
G01X150821Y145965D02*
X150831Y146239D01*
G01X150815Y145948D02*
X150821Y145965D01*
G01X150810Y146012D02*
X150815Y145948D01*
G01X158695Y140412D02*
X158684Y140365D01*
G01X158700Y140314D02*
X158695Y140412D01*
G01X158705Y140138D02*
X158700Y140314D01*
G01X158609Y137516D02*
X158607Y136551D01*
G01X158612Y137963D02*
X158609Y137516D01*
G01X158615Y138368D02*
X158612Y137963D01*
G01X158619Y138722D02*
X158615Y138368D01*
G01X158623Y139013D02*
X158619Y138722D01*
G01X158628Y139234D02*
X158623Y139013D01*
G01X158633Y139379D02*
X158628Y139234D01*
G01X158599Y137857D02*
X158596Y136570D01*
G01X158602Y138453D02*
X158599Y137857D01*
G01X158606Y138993D02*
X158602Y138453D01*
G01X158611Y139464D02*
X158606Y138993D01*
G01X158617Y139853D02*
X158611Y139464D01*
G01X158624Y140148D02*
X158617Y139853D01*
G01X158631Y140340D02*
X158624Y140148D01*
G01X158696Y141390D02*
X158681Y141327D01*
G01X158703Y141259D02*
X158696Y141390D01*
G01X158710Y141024D02*
X158703Y141259D01*
G01X156975Y141390D02*
X156961Y141024D01*
G01X156983Y141412D02*
X156975Y141390D01*
G01X156990Y141327D02*
X156983Y141412D01*
G01X157054Y139853D02*
X157040Y140340D01*
G01X157060Y139464D02*
X157054Y139853D01*
G01X157065Y138993D02*
X157060Y139464D01*
G01X157069Y138453D02*
X157065Y138993D01*
G01X157072Y137857D02*
X157069Y138453D01*
G01X157074Y137224D02*
X157072Y137857D01*
G01X157075Y136570D02*
X157074Y137224D01*
G01X157048Y139013D02*
X157038Y139379D01*
G01X157053Y138722D02*
X157048Y139013D01*
G01X157056Y138368D02*
X157053Y138722D01*
G01X157060Y137963D02*
X157056Y138368D01*
G01X157062Y137516D02*
X157060Y137963D01*
G01X157063Y137041D02*
X157062Y137516D01*
G01X157064Y136551D02*
X157063Y137041D01*
G01X156977Y140412D02*
X156966Y140138D01*
G01X156982Y140429D02*
X156977Y140412D01*
G01X156988Y140365D02*
X156982Y140429D01*
G01X156977Y145965D02*
X156988Y146012D01*
G01X156971Y146063D02*
X156977Y145965D01*
G01X156966Y146239D02*
X156971Y146063D01*
G01X157062Y148861D02*
X157064Y149826D01*
G01X157060Y148414D02*
X157062Y148861D01*
G01X157056Y148009D02*
X157060Y148414D01*
G01X157053Y147656D02*
X157056Y148009D01*
G01X157048Y147364D02*
X157053Y147656D01*
G01X157043Y147143D02*
X157048Y147364D01*
G01X157038Y146999D02*
X157043Y147143D01*
G01X157072Y148520D02*
X157075Y149807D01*
G01X157069Y147925D02*
X157072Y148520D01*
G01X157065Y147384D02*
X157069Y147925D01*
G01X157060Y146913D02*
X157065Y147384D01*
G01X157054Y146524D02*
X157060Y146913D01*
G01X157047Y146230D02*
X157054Y146524D01*
G01X157040Y146037D02*
X157047Y146230D01*
G01X156975Y144988D02*
X156990Y145050D01*
G01X156968Y145118D02*
X156975Y144988D01*
G01X156961Y145353D02*
X156968Y145118D01*
G01X158696Y144988D02*
X158710Y145353D01*
G01X158689Y144965D02*
X158696Y144988D01*
G01X158681Y145050D02*
X158689Y144965D01*
G01X158617Y146524D02*
X158631Y146037D01*
G01X158611Y146913D02*
X158617Y146524D01*
G01X158606Y147384D02*
X158611Y146913D01*
G01X158602Y147925D02*
X158606Y147384D01*
G01X158599Y148520D02*
X158602Y147925D01*
G01X158597Y149153D02*
X158599Y148520D01*
G01X158596Y149807D02*
X158597Y149153D01*
G01X158623Y147364D02*
X158633Y146999D01*
G01X158619Y147656D02*
X158623Y147364D01*
G01X158615Y148009D02*
X158619Y147656D01*
G01X158612Y148414D02*
X158615Y148009D01*
G01X158609Y148861D02*
X158612Y148414D01*
G01X158608Y149336D02*
X158609Y148861D01*
G01X158607Y149826D02*
X158608Y149336D01*
G01X158695Y145965D02*
X158705Y146239D01*
G01X158689Y145948D02*
X158695Y145965D01*
G01X158684Y146012D02*
X158689Y145948D01*
G01X162627Y140412D02*
X162616Y140365D01*
G01X162632Y140314D02*
X162627Y140412D01*
G01X162637Y140138D02*
X162632Y140314D01*
G01X162542Y137516D02*
X162540Y136551D01*
G01X162544Y137963D02*
X162542Y137516D01*
G01X162547Y138368D02*
X162544Y137963D01*
G01X162551Y138722D02*
X162547Y138368D01*
G01X162555Y139013D02*
X162551Y138722D01*
G01X162560Y139234D02*
X162555Y139013D01*
G01X162566Y139379D02*
X162560Y139234D01*
G01X162538Y135857D02*
X162540Y136551D01*
G01X162536Y135540D02*
X162538Y135857D01*
G01X162534Y135257D02*
X162536Y135540D01*
G01X162531Y135018D02*
X162534Y135257D01*
G01X162528Y134830D02*
X162531Y135018D01*
G01X162524Y134700D02*
X162528Y134830D01*
G01X162520Y134632D02*
X162524Y134700D01*
G01X162516Y134627D02*
X162520Y134632D01*
G01X162531Y137857D02*
X162529Y136570D01*
G01X162534Y138453D02*
X162531Y137857D01*
G01X162539Y138993D02*
X162534Y138453D01*
G01X162544Y139464D02*
X162539Y138993D01*
G01X162550Y139853D02*
X162544Y139464D01*
G01X162556Y140148D02*
X162550Y139853D01*
G01X162563Y140340D02*
X162556Y140148D01*
G01X162628Y141390D02*
X162614Y141327D01*
G01X162635Y141259D02*
X162628Y141390D01*
G01X162642Y141024D02*
X162635Y141259D01*
G01X160908Y141390D02*
X160894Y141024D01*
G01X160915Y141412D02*
X160908Y141390D01*
G01X160922Y141327D02*
X160915Y141412D01*
G01X160986Y139853D02*
X160973Y140340D01*
G01X160992Y139464D02*
X160986Y139853D01*
G01X160997Y138993D02*
X160992Y139464D01*
G01X161001Y138453D02*
X160997Y138993D01*
G01X161005Y137857D02*
X161001Y138453D01*
G01X161006Y137224D02*
X161005Y137857D01*
G01X161007Y136570D02*
X161006Y137224D01*
G01X161012Y134700D02*
X161020Y134627D01*
G01X161008Y134830D02*
X161012Y134700D01*
G01X161005Y135018D02*
X161008Y134830D01*
G01X161002Y135257D02*
X161005Y135018D01*
G01X161000Y135540D02*
X161002Y135257D01*
G01X160998Y135857D02*
X161000Y135540D01*
G01X160997Y136198D02*
X160998Y135857D01*
G01X160996Y136551D02*
X160997Y136198D01*
G01X160981Y139013D02*
X160970Y139379D01*
G01X160985Y138722D02*
X160981Y139013D01*
G01X160989Y138368D02*
X160985Y138722D01*
G01X160992Y137963D02*
X160989Y138368D01*
G01X160994Y137516D02*
X160992Y137963D01*
G01X160996Y137041D02*
X160994Y137516D01*
G01X160996Y136551D02*
Y137041D01*
G01X160909Y140412D02*
X160899Y140138D01*
G01X160914Y140429D02*
X160909Y140412D01*
G01X160920Y140365D02*
X160914Y140429D01*
G01X160918Y145965D02*
X160929Y146012D01*
G01X160913Y146063D02*
X160918Y145965D01*
G01X160908Y146239D02*
X160913Y146063D01*
G01X161004Y148861D02*
X161006Y149826D01*
G01X161001Y148414D02*
X161004Y148861D01*
G01X160998Y148009D02*
X161001Y148414D01*
G01X160994Y147656D02*
X160998Y148009D01*
G01X160990Y147364D02*
X160994Y147656D01*
G01X160985Y147143D02*
X160990Y147364D01*
G01X160980Y146999D02*
X160985Y147143D01*
G01X161007Y150521D02*
X161006Y149826D01*
G01X161009Y150838D02*
X161007Y150521D01*
G01X161011Y151120D02*
X161009Y150838D01*
G01X161014Y151359D02*
X161011Y151120D01*
G01X161018Y151547D02*
X161014Y151359D01*
G01X161021Y151677D02*
X161018Y151547D01*
G01X161025Y151746D02*
X161021Y151677D01*
G01X161029Y151750D02*
X161025Y151746D01*
G01X161014Y148520D02*
X161017Y149807D01*
G01X161011Y147925D02*
X161014Y148520D01*
G01X161007Y147384D02*
X161011Y147925D01*
G01X161001Y146913D02*
X161007Y147384D01*
G01X160996Y146524D02*
X161001Y146913D01*
G01X160989Y146230D02*
X160996Y146524D01*
G01X160982Y146037D02*
X160989Y146230D01*
G01X160917Y144988D02*
X160932Y145050D01*
G01X160910Y145118D02*
X160917Y144988D01*
G01X160903Y145353D02*
X160910Y145118D01*
G01X162638Y144988D02*
X162651Y145353D01*
G01X162630Y144965D02*
X162638Y144988D01*
G01X162623Y145050D02*
X162630Y144965D01*
G01X162559Y146524D02*
X162573Y146037D01*
G01X162553Y146913D02*
X162559Y146524D01*
G01X162548Y147384D02*
X162553Y146913D01*
G01X162544Y147925D02*
X162548Y147384D01*
G01X162541Y148520D02*
X162544Y147925D01*
G01X162539Y149153D02*
X162541Y148520D01*
G01X162538Y149807D02*
X162539Y149153D01*
G01X162533Y151677D02*
X162525Y151750D01*
G01X162537Y151547D02*
X162533Y151677D01*
G01X162540Y151359D02*
X162537Y151547D01*
G01X162543Y151120D02*
X162540Y151359D01*
G01X162546Y150838D02*
X162543Y151120D01*
G01X162547Y150521D02*
X162546Y150838D01*
G01X162549Y150180D02*
X162547Y150521D01*
G01X162549Y149826D02*
Y150180D01*
G01X162565Y147364D02*
X162575Y146999D01*
G01X162560Y147656D02*
X162565Y147364D01*
G01X162556Y148009D02*
X162560Y147656D01*
G01X162553Y148414D02*
X162556Y148009D01*
G01X162551Y148861D02*
X162553Y148414D01*
G01X162550Y149336D02*
X162551Y148861D01*
G01X162549Y149826D02*
X162550Y149336D01*
G01X162636Y145965D02*
X162647Y146239D01*
G01X162631Y145948D02*
X162636Y145965D01*
G01X162625Y146012D02*
X162631Y145948D01*
G01X123257Y140412D02*
X123246Y140365D01*
G01X123262Y140314D02*
X123257Y140412D01*
G01X123267Y140138D02*
X123262Y140314D01*
G01X123172Y137516D02*
X123170Y136551D01*
G01X123174Y137963D02*
X123172Y137516D01*
G01X123177Y138368D02*
X123174Y137963D01*
G01X123181Y138722D02*
X123177Y138368D01*
G01X123185Y139013D02*
X123181Y138722D01*
G01X123190Y139234D02*
X123185Y139013D01*
G01X123195Y139379D02*
X123190Y139234D01*
G01X123168Y135857D02*
X123170Y136551D01*
G01X123166Y135540D02*
X123168Y135857D01*
G01X123164Y135257D02*
X123166Y135540D01*
G01X123161Y135018D02*
X123164Y135257D01*
G01X123157Y134830D02*
X123161Y135018D01*
G01X123154Y134700D02*
X123157Y134830D01*
G01X123150Y134632D02*
X123154Y134700D01*
G01X123146Y134627D02*
X123150Y134632D01*
G01X123161Y137857D02*
X123159Y136570D01*
G01X123164Y138453D02*
X123161Y137857D01*
G01X123169Y138993D02*
X123164Y138453D01*
G01X123174Y139464D02*
X123169Y138993D01*
G01X123180Y139853D02*
X123174Y139464D01*
G01X123186Y140148D02*
X123180Y139853D01*
G01X123193Y140340D02*
X123186Y140148D01*
G01X123258Y141390D02*
X123244Y141327D01*
G01X123265Y141259D02*
X123258Y141390D01*
G01X123272Y141024D02*
X123265Y141259D01*
G01X121538Y141390D02*
X121524Y141024D01*
G01X121545Y141412D02*
X121538Y141390D01*
G01X121552Y141327D02*
X121545Y141412D01*
G01X121616Y139853D02*
X121603Y140340D01*
G01X121622Y139464D02*
X121616Y139853D01*
G01X121627Y138993D02*
X121622Y139464D01*
G01X121631Y138453D02*
X121627Y138993D01*
G01X121634Y137857D02*
X121631Y138453D01*
G01X121636Y137224D02*
X121634Y137857D01*
G01X121637Y136570D02*
X121636Y137224D01*
G01X121642Y134700D02*
X121650Y134627D01*
G01X121638Y134830D02*
X121642Y134700D01*
G01X121635Y135018D02*
X121638Y134830D01*
G01X121632Y135257D02*
X121635Y135018D01*
G01X121630Y135540D02*
X121632Y135257D01*
G01X121628Y135857D02*
X121630Y135540D01*
G01X121627Y136198D02*
X121628Y135857D01*
G01X121626Y136551D02*
X121627Y136198D01*
G01X121610Y139013D02*
X121600Y139379D01*
G01X121615Y138722D02*
X121610Y139013D01*
G01X121619Y138368D02*
X121615Y138722D01*
G01X121622Y137963D02*
X121619Y138368D01*
G01X121624Y137516D02*
X121622Y137963D01*
G01X121626Y137041D02*
X121624Y137516D01*
G01X121626Y136551D02*
Y137041D01*
G01X121539Y140412D02*
X121528Y140138D01*
G01X121544Y140429D02*
X121539Y140412D01*
G01X121550Y140365D02*
X121544Y140429D01*
G01X121548Y145965D02*
X121559Y146012D01*
G01X121543Y146063D02*
X121548Y145965D01*
G01X121538Y146239D02*
X121543Y146063D01*
G01X121633Y148861D02*
X121636Y149826D01*
G01X121631Y148414D02*
X121633Y148861D01*
G01X121628Y148009D02*
X121631Y148414D01*
G01X121624Y147656D02*
X121628Y148009D01*
G01X121620Y147364D02*
X121624Y147656D01*
G01X121615Y147143D02*
X121620Y147364D01*
G01X121610Y146999D02*
X121615Y147143D01*
G01X121637Y150521D02*
X121636Y149826D01*
G01X121639Y150838D02*
X121637Y150521D01*
G01X121641Y151120D02*
X121639Y150838D01*
G01X121644Y151359D02*
X121641Y151120D01*
G01X121648Y151547D02*
X121644Y151359D01*
G01X121651Y151677D02*
X121648Y151547D01*
G01X121655Y151746D02*
X121651Y151677D01*
G01X121659Y151750D02*
X121655Y151746D01*
G01X121644Y148520D02*
X121647Y149807D01*
G01X121641Y147925D02*
X121644Y148520D01*
G01X121637Y147384D02*
X121641Y147925D01*
G01X121631Y146913D02*
X121637Y147384D01*
G01X121626Y146524D02*
X121631Y146913D01*
G01X121619Y146230D02*
X121626Y146524D01*
G01X121612Y146037D02*
X121619Y146230D01*
G01X121547Y144988D02*
X121561Y145050D01*
G01X121540Y145118D02*
X121547Y144988D01*
G01X121533Y145353D02*
X121540Y145118D01*
G01X123267Y144988D02*
X123281Y145353D01*
G01X123260Y144965D02*
X123267Y144988D01*
G01X123253Y145050D02*
X123260Y144965D01*
G01X123189Y146524D02*
X123202Y146037D01*
G01X123183Y146913D02*
X123189Y146524D01*
G01X123178Y147384D02*
X123183Y146913D01*
G01X123174Y147925D02*
X123178Y147384D01*
G01X123171Y148520D02*
X123174Y147925D01*
G01X123169Y149153D02*
X123171Y148520D01*
G01X123168Y149807D02*
X123169Y149153D01*
G01X123163Y151677D02*
X123155Y151750D01*
G01X123167Y151547D02*
X123163Y151677D01*
G01X123170Y151359D02*
X123167Y151547D01*
G01X123173Y151120D02*
X123170Y151359D01*
G01X123176Y150838D02*
X123173Y151120D01*
G01X123177Y150521D02*
X123176Y150838D01*
G01X123178Y150180D02*
X123177Y150521D01*
G01X123179Y149826D02*
X123178Y150180D01*
G01X123195Y147364D02*
X123205Y146999D01*
G01X123190Y147656D02*
X123195Y147364D01*
G01X123186Y148009D02*
X123190Y147656D01*
G01X123183Y148414D02*
X123186Y148009D01*
G01X123181Y148861D02*
X123183Y148414D01*
G01X123179Y149336D02*
X123181Y148861D01*
G01X123179Y149826D02*
Y149336D01*
G01X123266Y145965D02*
X123277Y146239D01*
G01X123261Y145948D02*
X123266Y145965D01*
G01X123255Y146012D02*
X123261Y145948D01*
G01X127199Y140412D02*
X127188Y140365D01*
G01X127204Y140314D02*
X127199Y140412D01*
G01X127209Y140138D02*
X127204Y140314D01*
G01X127113Y137516D02*
X127111Y136551D01*
G01X127116Y137963D02*
X127113Y137516D01*
G01X127119Y138368D02*
X127116Y137963D01*
G01X127123Y138722D02*
X127119Y138368D01*
G01X127127Y139013D02*
X127123Y138722D01*
G01X127132Y139234D02*
X127127Y139013D01*
G01X127137Y139379D02*
X127132Y139234D01*
G01X127103Y137857D02*
X127100Y136570D01*
G01X127106Y138453D02*
X127103Y137857D01*
G01X127110Y138993D02*
X127106Y138453D01*
G01X127115Y139464D02*
X127110Y138993D01*
G01X127121Y139853D02*
X127115Y139464D01*
G01X127128Y140148D02*
X127121Y139853D01*
G01X127135Y140340D02*
X127128Y140148D01*
G01X127200Y141390D02*
X127185Y141327D01*
G01X127207Y141259D02*
X127200Y141390D01*
G01X127214Y141024D02*
X127207Y141259D01*
G01X125479Y141390D02*
X125465Y141024D01*
G01X125487Y141412D02*
X125479Y141390D01*
G01X125494Y141327D02*
X125487Y141412D01*
G01X125558Y139853D02*
X125544Y140340D01*
G01X125564Y139464D02*
X125558Y139853D01*
G01X125569Y138993D02*
X125564Y139464D01*
G01X125573Y138453D02*
X125569Y138993D01*
G01X125576Y137857D02*
X125573Y138453D01*
G01X125578Y137224D02*
X125576Y137857D01*
G01X125579Y136570D02*
X125578Y137224D01*
G01X125552Y139013D02*
X125542Y139379D01*
G01X125557Y138722D02*
X125552Y139013D01*
G01X125560Y138368D02*
X125557Y138722D01*
G01X125564Y137963D02*
X125560Y138368D01*
G01X125566Y137516D02*
X125564Y137963D01*
G01X125567Y137041D02*
X125566Y137516D01*
G01X125568Y136551D02*
X125567Y137041D01*
G01X125481Y140412D02*
X125470Y140138D01*
G01X125486Y140429D02*
X125481Y140412D01*
G01X125491Y140365D02*
X125486Y140429D01*
G01X131131Y140412D02*
X131120Y140365D01*
G01X131136Y140314D02*
X131131Y140412D01*
G01X131141Y140138D02*
X131136Y140314D01*
G01X131046Y137516D02*
X131044Y136551D01*
G01X131048Y137963D02*
X131046Y137516D01*
G01X131051Y138368D02*
X131048Y137963D01*
G01X131055Y138722D02*
X131051Y138368D01*
G01X131059Y139013D02*
X131055Y138722D01*
G01X131064Y139234D02*
X131059Y139013D01*
G01X131069Y139379D02*
X131064Y139234D01*
G01X131042Y135857D02*
X131044Y136551D01*
G01X131040Y135540D02*
X131042Y135857D01*
G01X131038Y135257D02*
X131040Y135540D01*
G01X131035Y135018D02*
X131038Y135257D01*
G01X131031Y134830D02*
X131035Y135018D01*
G01X131028Y134700D02*
X131031Y134830D01*
G01X131024Y134632D02*
X131028Y134700D01*
G01X131020Y134627D02*
X131024Y134632D01*
G01X131035Y137857D02*
X131033Y136570D01*
G01X131038Y138453D02*
X131035Y137857D01*
G01X131043Y138993D02*
X131038Y138453D01*
G01X131048Y139464D02*
X131043Y138993D01*
G01X131054Y139853D02*
X131048Y139464D01*
G01X131060Y140148D02*
X131054Y139853D01*
G01X131067Y140340D02*
X131060Y140148D01*
G01X131132Y141390D02*
X131118Y141327D01*
G01X131139Y141259D02*
X131132Y141390D01*
G01X131146Y141024D02*
X131139Y141259D01*
G01X129412Y141390D02*
X129398Y141024D01*
G01X129419Y141412D02*
X129412Y141390D01*
G01X129426Y141327D02*
X129419Y141412D01*
G01X129490Y139853D02*
X129477Y140340D01*
G01X129496Y139464D02*
X129490Y139853D01*
G01X129501Y138993D02*
X129496Y139464D01*
G01X129505Y138453D02*
X129501Y138993D01*
G01X129508Y137857D02*
X129505Y138453D01*
G01X129510Y137224D02*
X129508Y137857D01*
G01X129511Y136570D02*
X129510Y137224D01*
G01X129516Y134700D02*
X129524Y134627D01*
G01X129512Y134830D02*
X129516Y134700D01*
G01X129509Y135018D02*
X129512Y134830D01*
G01X129506Y135257D02*
X129509Y135018D01*
G01X129504Y135540D02*
X129506Y135257D01*
G01X129502Y135857D02*
X129504Y135540D01*
G01X129501Y136198D02*
X129502Y135857D01*
G01X129500Y136551D02*
X129501Y136198D01*
G01X129484Y139013D02*
X129474Y139379D01*
G01X129489Y138722D02*
X129484Y139013D01*
G01X129493Y138368D02*
X129489Y138722D01*
G01X129496Y137963D02*
X129493Y138368D01*
G01X129498Y137516D02*
X129496Y137963D01*
G01X129500Y137041D02*
X129498Y137516D01*
G01X129500Y136551D02*
Y137041D01*
G01X129413Y140412D02*
X129402Y140138D01*
G01X129418Y140429D02*
X129413Y140412D01*
G01X129424Y140365D02*
X129418Y140429D01*
G01X129422Y145965D02*
X129433Y146012D01*
G01X129417Y146063D02*
X129422Y145965D01*
G01X129412Y146239D02*
X129417Y146063D01*
G01X129508Y148861D02*
X129510Y149826D01*
G01X129505Y148414D02*
X129508Y148861D01*
G01X129502Y148009D02*
X129505Y148414D01*
G01X129498Y147656D02*
X129502Y148009D01*
G01X129494Y147364D02*
X129498Y147656D01*
G01X129489Y147143D02*
X129494Y147364D01*
G01X129484Y146999D02*
X129489Y147143D01*
G01X129511Y150521D02*
X129510Y149826D01*
G01X129513Y150838D02*
X129511Y150521D01*
G01X129515Y151120D02*
X129513Y150838D01*
G01X129518Y151359D02*
X129515Y151120D01*
G01X129522Y151547D02*
X129518Y151359D01*
G01X129525Y151677D02*
X129522Y151547D01*
G01X129529Y151746D02*
X129525Y151677D01*
G01X129533Y151750D02*
X129529Y151746D01*
G01X129518Y148520D02*
X129521Y149807D01*
G01X129515Y147925D02*
X129518Y148520D01*
G01X129511Y147384D02*
X129515Y147925D01*
G01X129505Y146913D02*
X129511Y147384D01*
G01X129500Y146524D02*
X129505Y146913D01*
G01X129493Y146230D02*
X129500Y146524D01*
G01X129486Y146037D02*
X129493Y146230D01*
G01X129421Y144988D02*
X129435Y145050D01*
G01X129414Y145118D02*
X129421Y144988D01*
G01X129407Y145353D02*
X129414Y145118D01*
G01X131141Y144988D02*
X131155Y145353D01*
G01X131134Y144965D02*
X131141Y144988D01*
G01X131127Y145050D02*
X131134Y144965D01*
G01X131063Y146524D02*
X131076Y146037D01*
G01X131057Y146913D02*
X131063Y146524D01*
G01X131052Y147384D02*
X131057Y146913D01*
G01X131048Y147925D02*
X131052Y147384D01*
G01X131045Y148520D02*
X131048Y147925D01*
G01X131043Y149153D02*
X131045Y148520D01*
G01X131042Y149807D02*
X131043Y149153D01*
G01X131037Y151677D02*
X131029Y151750D01*
G01X131041Y151547D02*
X131037Y151677D01*
G01X131044Y151359D02*
X131041Y151547D01*
G01X131047Y151120D02*
X131044Y151359D01*
G01X131050Y150838D02*
X131047Y151120D01*
G01X131051Y150521D02*
X131050Y150838D01*
G01X131052Y150180D02*
X131051Y150521D01*
G01X131053Y149826D02*
X131052Y150180D01*
G01X131069Y147364D02*
X131079Y146999D01*
G01X131064Y147656D02*
X131069Y147364D01*
G01X131060Y148009D02*
X131064Y147656D01*
G01X131057Y148414D02*
X131060Y148009D01*
G01X131055Y148861D02*
X131057Y148414D01*
G01X131053Y149336D02*
X131055Y148861D01*
G01X131053Y149826D02*
Y149336D01*
G01X131140Y145965D02*
X131151Y146239D01*
G01X131135Y145948D02*
X131140Y145965D01*
G01X131129Y146012D02*
X131135Y145948D01*
G01X184540Y145965D02*
X184551Y146012D01*
G01X184535Y146063D02*
X184540Y145965D01*
G01X184530Y146239D02*
X184535Y146063D01*
G01X184626Y148861D02*
X184628Y149826D01*
G01X184623Y148414D02*
X184626Y148861D01*
G01X184620Y148009D02*
X184623Y148414D01*
G01X184616Y147656D02*
X184620Y148009D01*
G01X184612Y147364D02*
X184616Y147656D01*
G01X184607Y147143D02*
X184612Y147364D01*
G01X184602Y146999D02*
X184607Y147143D01*
G01X184629Y150521D02*
X184628Y149826D01*
G01X184631Y150838D02*
X184629Y150521D01*
G01X184633Y151120D02*
X184631Y150838D01*
G01X184636Y151359D02*
X184633Y151120D01*
G01X184640Y151547D02*
X184636Y151359D01*
G01X184643Y151677D02*
X184640Y151547D01*
G01X184647Y151746D02*
X184643Y151677D01*
G01X184651Y151750D02*
X184647Y151746D01*
G01X184636Y148520D02*
X184639Y149807D01*
G01X184633Y147925D02*
X184636Y148520D01*
G01X184629Y147384D02*
X184633Y147925D01*
G01X184624Y146913D02*
X184629Y147384D01*
G01X184618Y146524D02*
X184624Y146913D01*
G01X184611Y146230D02*
X184618Y146524D01*
G01X184604Y146037D02*
X184611Y146230D01*
G01X184539Y144988D02*
X184554Y145050D01*
G01X184532Y145118D02*
X184539Y144988D01*
G01X184525Y145353D02*
X184532Y145118D01*
G01X186260Y144988D02*
X186274Y145353D01*
G01X186252Y144965D02*
X186260Y144988D01*
G01X186245Y145050D02*
X186252Y144965D01*
G01X186181Y146524D02*
X186195Y146037D01*
G01X186175Y146913D02*
X186181Y146524D01*
G01X186170Y147384D02*
X186175Y146913D01*
G01X186166Y147925D02*
X186170Y147384D01*
G01X186163Y148520D02*
X186166Y147925D01*
G01X186161Y149153D02*
X186163Y148520D01*
G01X186160Y149807D02*
X186161Y149153D01*
G01X186155Y151677D02*
X186147Y151750D01*
G01X186159Y151547D02*
X186155Y151677D01*
G01X186162Y151359D02*
X186159Y151547D01*
G01X186165Y151120D02*
X186162Y151359D01*
G01X186168Y150838D02*
X186165Y151120D01*
G01X186169Y150521D02*
X186168Y150838D01*
G01X186171Y150180D02*
X186169Y150521D01*
G01X186171Y149826D02*
Y150180D01*
G01X186187Y147364D02*
X186197Y146999D01*
G01X186182Y147656D02*
X186187Y147364D01*
G01X186179Y148009D02*
X186182Y147656D01*
G01X186175Y148414D02*
X186179Y148009D01*
G01X186173Y148861D02*
X186175Y148414D01*
G01X186172Y149336D02*
X186173Y148861D01*
G01X186171Y149826D02*
X186172Y149336D01*
G01X186258Y145965D02*
X186269Y146239D01*
G01X186253Y145948D02*
X186258Y145965D01*
G01X186247Y146012D02*
X186253Y145948D01*
G01X186249Y140412D02*
X186238Y140365D01*
G01X186254Y140314D02*
X186249Y140412D01*
G01X186259Y140138D02*
X186254Y140314D01*
G01X186164Y137516D02*
X186162Y136551D01*
G01X186166Y137963D02*
X186164Y137516D01*
G01X186169Y138368D02*
X186166Y137963D01*
G01X186173Y138722D02*
X186169Y138368D01*
G01X186177Y139013D02*
X186173Y138722D01*
G01X186182Y139234D02*
X186177Y139013D01*
G01X186188Y139379D02*
X186182Y139234D01*
G01X186160Y135857D02*
X186162Y136551D01*
G01X186158Y135540D02*
X186160Y135857D01*
G01X186156Y135257D02*
X186158Y135540D01*
G01X186153Y135018D02*
X186156Y135257D01*
G01X186150Y134830D02*
X186153Y135018D01*
G01X186146Y134700D02*
X186150Y134830D01*
G01X186142Y134632D02*
X186146Y134700D01*
G01X186138Y134627D02*
X186142Y134632D01*
G01X186153Y137857D02*
X186151Y136570D01*
G01X186157Y138453D02*
X186153Y137857D01*
G01X186161Y138993D02*
X186157Y138453D01*
G01X186166Y139464D02*
X186161Y138993D01*
G01X186172Y139853D02*
X186166Y139464D01*
G01X186178Y140148D02*
X186172Y139853D01*
G01X186185Y140340D02*
X186178Y140148D01*
G01X186250Y141390D02*
X186236Y141327D01*
G01X186257Y141259D02*
X186250Y141390D01*
G01X186264Y141024D02*
X186257Y141259D01*
G01X184530Y141390D02*
X184516Y141024D01*
G01X184537Y141412D02*
X184530Y141390D01*
G01X184544Y141327D02*
X184537Y141412D01*
G01X184608Y139853D02*
X184595Y140340D01*
G01X184614Y139464D02*
X184608Y139853D01*
G01X184619Y138993D02*
X184614Y139464D01*
G01X184623Y138453D02*
X184619Y138993D01*
G01X184627Y137857D02*
X184623Y138453D01*
G01X184629Y137224D02*
X184627Y137857D01*
G01X184629Y136570D02*
Y137224D01*
G01X184634Y134700D02*
X184642Y134627D01*
G01X184630Y134830D02*
X184634Y134700D01*
G01X184627Y135018D02*
X184630Y134830D01*
G01X184624Y135257D02*
X184627Y135018D01*
G01X184622Y135540D02*
X184624Y135257D01*
G01X184620Y135857D02*
X184622Y135540D01*
G01X184619Y136198D02*
X184620Y135857D01*
G01X184618Y136551D02*
X184619Y136198D01*
G01X184603Y139013D02*
X184592Y139379D01*
G01X184607Y138722D02*
X184603Y139013D01*
G01X184611Y138368D02*
X184607Y138722D01*
G01X184614Y137963D02*
X184611Y138368D01*
G01X184616Y137516D02*
X184614Y137963D01*
G01X184618Y137041D02*
X184616Y137516D01*
G01X184618Y136551D02*
Y137041D01*
G01X184531Y140412D02*
X184521Y140138D01*
G01X184537Y140429D02*
X184531Y140412D01*
G01X184542Y140365D02*
X184537Y140429D01*
G01X180599Y145965D02*
X180610Y146012D01*
G01X180593Y146063D02*
X180599Y145965D01*
G01X180588Y146239D02*
X180593Y146063D01*
G01X180684Y148861D02*
X180686Y149826D01*
G01X180682Y148414D02*
X180684Y148861D01*
G01X180678Y148009D02*
X180682Y148414D01*
G01X180675Y147656D02*
X180678Y148009D01*
G01X180670Y147364D02*
X180675Y147656D01*
G01X180665Y147143D02*
X180670Y147364D01*
G01X180660Y146999D02*
X180665Y147143D01*
G01X180694Y148520D02*
X180697Y149807D01*
G01X180691Y147925D02*
X180694Y148520D01*
G01X180687Y147384D02*
X180691Y147925D01*
G01X180682Y146913D02*
X180687Y147384D01*
G01X180676Y146524D02*
X180682Y146913D01*
G01X180669Y146230D02*
X180676Y146524D01*
G01X180662Y146037D02*
X180669Y146230D01*
G01X180597Y144988D02*
X180612Y145050D01*
G01X180590Y145118D02*
X180597Y144988D01*
G01X180583Y145353D02*
X180590Y145118D01*
G01X182318Y144988D02*
X182332Y145353D01*
G01X182311Y144965D02*
X182318Y144988D01*
G01X182303Y145050D02*
X182311Y144965D01*
G01X182239Y146524D02*
X182253Y146037D01*
G01X182233Y146913D02*
X182239Y146524D01*
G01X182228Y147384D02*
X182233Y146913D01*
G01X182224Y147925D02*
X182228Y147384D01*
G01X182221Y148520D02*
X182224Y147925D01*
G01X182219Y149153D02*
X182221Y148520D01*
G01X182218Y149807D02*
X182219Y149153D01*
G01X182245Y147364D02*
X182255Y146999D01*
G01X182241Y147656D02*
X182245Y147364D01*
G01X182237Y148009D02*
X182241Y147656D01*
G01X182234Y148414D02*
X182237Y148009D01*
G01X182231Y148861D02*
X182234Y148414D01*
G01X182230Y149336D02*
X182231Y148861D01*
G01X182229Y149826D02*
X182230Y149336D01*
G01X182317Y145965D02*
X182327Y146239D01*
G01X182311Y145948D02*
X182317Y145965D01*
G01X182306Y146012D02*
X182311Y145948D01*
G01X182317Y140412D02*
X182306Y140365D01*
G01X182322Y140314D02*
X182317Y140412D01*
G01X182327Y140138D02*
X182322Y140314D01*
G01X182231Y137516D02*
X182229Y136551D01*
G01X182234Y137963D02*
X182231Y137516D01*
G01X182237Y138368D02*
X182234Y137963D01*
G01X182241Y138722D02*
X182237Y138368D01*
G01X182245Y139013D02*
X182241Y138722D01*
G01X182250Y139234D02*
X182245Y139013D01*
G01X182255Y139379D02*
X182250Y139234D01*
G01X182221Y137857D02*
X182218Y136570D01*
G01X182224Y138453D02*
X182221Y137857D01*
G01X182228Y138993D02*
X182224Y138453D01*
G01X182233Y139464D02*
X182228Y138993D01*
G01X182239Y139853D02*
X182233Y139464D01*
G01X182246Y140148D02*
X182239Y139853D01*
G01X182253Y140340D02*
X182246Y140148D01*
G01X182318Y141390D02*
X182303Y141327D01*
G01X182325Y141259D02*
X182318Y141390D01*
G01X182332Y141024D02*
X182325Y141259D01*
G01X180597Y141390D02*
X180583Y141024D01*
G01X180605Y141412D02*
X180597Y141390D01*
G01X180612Y141327D02*
X180605Y141412D01*
G01X180676Y139853D02*
X180662Y140340D01*
G01X180682Y139464D02*
X180676Y139853D01*
G01X180687Y138993D02*
X180682Y139464D01*
G01X180691Y138453D02*
X180687Y138993D01*
G01X180694Y137857D02*
X180691Y138453D01*
G01X180696Y137224D02*
X180694Y137857D01*
G01X180697Y136570D02*
X180696Y137224D01*
G01X180670Y139013D02*
X180660Y139379D01*
G01X180675Y138722D02*
X180670Y139013D01*
G01X180678Y138368D02*
X180675Y138722D01*
G01X180682Y137963D02*
X180678Y138368D01*
G01X180684Y137516D02*
X180682Y137963D01*
G01X180685Y137041D02*
X180684Y137516D01*
G01X180686Y136551D02*
X180685Y137041D01*
G01X180599Y140412D02*
X180588Y140138D01*
G01X180604Y140429D02*
X180599Y140412D01*
G01X180610Y140365D02*
X180604Y140429D01*
G01X176666Y145965D02*
X176677Y146012D01*
G01X176661Y146063D02*
X176666Y145965D01*
G01X176656Y146239D02*
X176661Y146063D01*
G01X176752Y148861D02*
X176754Y149826D01*
G01X176749Y148414D02*
X176752Y148861D01*
G01X176746Y148009D02*
X176749Y148414D01*
G01X176742Y147656D02*
X176746Y148009D01*
G01X176738Y147364D02*
X176742Y147656D01*
G01X176733Y147143D02*
X176738Y147364D01*
G01X176728Y146999D02*
X176733Y147143D01*
G01X176755Y150521D02*
X176754Y149826D01*
G01X176757Y150838D02*
X176755Y150521D01*
G01X176759Y151120D02*
X176757Y150838D01*
G01X176762Y151359D02*
X176759Y151120D01*
G01X176766Y151547D02*
X176762Y151359D01*
G01X176769Y151677D02*
X176766Y151547D01*
G01X176773Y151746D02*
X176769Y151677D01*
G01X176777Y151750D02*
X176773Y151746D01*
G01X176762Y148520D02*
X176765Y149807D01*
G01X176759Y147925D02*
X176762Y148520D01*
G01X176755Y147384D02*
X176759Y147925D01*
G01X176750Y146913D02*
X176755Y147384D01*
G01X176744Y146524D02*
X176750Y146913D01*
G01X176737Y146230D02*
X176744Y146524D01*
G01X176730Y146037D02*
X176737Y146230D01*
G01X176665Y144988D02*
X176680Y145050D01*
G01X176658Y145118D02*
X176665Y144988D01*
G01X176651Y145353D02*
X176658Y145118D01*
G01X178386Y144988D02*
X178399Y145353D01*
G01X178378Y144965D02*
X178386Y144988D01*
G01X178371Y145050D02*
X178378Y144965D01*
G01X178307Y146524D02*
X178321Y146037D01*
G01X178301Y146913D02*
X178307Y146524D01*
G01X178296Y147384D02*
X178301Y146913D01*
G01X178292Y147925D02*
X178296Y147384D01*
G01X178289Y148520D02*
X178292Y147925D01*
G01X178287Y149153D02*
X178289Y148520D01*
G01X178286Y149807D02*
X178287Y149153D01*
G01X178281Y151677D02*
X178273Y151750D01*
G01X178285Y151547D02*
X178281Y151677D01*
G01X178288Y151359D02*
X178285Y151547D01*
G01X178291Y151120D02*
X178288Y151359D01*
G01X178294Y150838D02*
X178291Y151120D01*
G01X178295Y150521D02*
X178294Y150838D01*
G01X178297Y150180D02*
X178295Y150521D01*
G01X178297Y149826D02*
Y150180D01*
G01X178313Y147364D02*
X178323Y146999D01*
G01X178308Y147656D02*
X178313Y147364D01*
G01X178304Y148009D02*
X178308Y147656D01*
G01X178301Y148414D02*
X178304Y148009D01*
G01X178299Y148861D02*
X178301Y148414D01*
G01X178298Y149336D02*
X178299Y148861D01*
G01X178297Y149826D02*
X178298Y149336D01*
G01X178384Y145965D02*
X178395Y146239D01*
G01X178379Y145948D02*
X178384Y145965D01*
G01X178373Y146012D02*
X178379Y145948D01*
G01X178375Y140412D02*
X178364Y140365D01*
G01X178380Y140314D02*
X178375Y140412D01*
G01X178385Y140138D02*
X178380Y140314D01*
G01X178290Y137516D02*
X178288Y136551D01*
G01X178292Y137963D02*
X178290Y137516D01*
G01X178295Y138368D02*
X178292Y137963D01*
G01X178299Y138722D02*
X178295Y138368D01*
G01X178303Y139013D02*
X178299Y138722D01*
G01X178308Y139234D02*
X178303Y139013D01*
G01X178314Y139379D02*
X178308Y139234D01*
G01X178286Y135857D02*
X178288Y136551D01*
G01X178284Y135540D02*
X178286Y135857D01*
G01X178282Y135257D02*
X178284Y135540D01*
G01X178279Y135018D02*
X178282Y135257D01*
G01X178276Y134830D02*
X178279Y135018D01*
G01X178272Y134700D02*
X178276Y134830D01*
G01X178268Y134632D02*
X178272Y134700D01*
G01X178264Y134627D02*
X178268Y134632D01*
G01X178279Y137857D02*
X178277Y136570D01*
G01X178283Y138453D02*
X178279Y137857D01*
G01X178287Y138993D02*
X178283Y138453D01*
G01X178292Y139464D02*
X178287Y138993D01*
G01X178298Y139853D02*
X178292Y139464D01*
G01X178304Y140148D02*
X178298Y139853D01*
G01X178311Y140340D02*
X178304Y140148D01*
G01X178376Y141390D02*
X178362Y141327D01*
G01X178383Y141259D02*
X178376Y141390D01*
G01X178390Y141024D02*
X178383Y141259D01*
G01X176656Y141390D02*
X176642Y141024D01*
G01X176663Y141412D02*
X176656Y141390D01*
G01X176670Y141327D02*
X176663Y141412D01*
G01X176734Y139853D02*
X176721Y140340D01*
G01X176740Y139464D02*
X176734Y139853D01*
G01X176745Y138993D02*
X176740Y139464D01*
G01X176749Y138453D02*
X176745Y138993D01*
G01X176753Y137857D02*
X176749Y138453D01*
G01X176755Y137224D02*
X176753Y137857D01*
G01X176755Y136570D02*
Y137224D01*
G01X176760Y134700D02*
X176768Y134627D01*
G01X176756Y134830D02*
X176760Y134700D01*
G01X176753Y135018D02*
X176756Y134830D01*
G01X176750Y135257D02*
X176753Y135018D01*
G01X176748Y135540D02*
X176750Y135257D01*
G01X176746Y135857D02*
X176748Y135540D01*
G01X176745Y136198D02*
X176746Y135857D01*
G01X176744Y136551D02*
X176745Y136198D01*
G01X176729Y139013D02*
X176718Y139379D01*
G01X176733Y138722D02*
X176729Y139013D01*
G01X176737Y138368D02*
X176733Y138722D01*
G01X176740Y137963D02*
X176737Y138368D01*
G01X176742Y137516D02*
X176740Y137963D01*
G01X176744Y137041D02*
X176742Y137516D01*
G01X176744Y136551D02*
Y137041D01*
G01X176657Y140412D02*
X176647Y140138D01*
G01X176662Y140429D02*
X176657Y140412D01*
G01X176668Y140365D02*
X176662Y140429D01*
G01X153044Y145965D02*
X153055Y146012D01*
G01X153039Y146063D02*
X153044Y145965D01*
G01X153034Y146239D02*
X153039Y146063D01*
G01X153130Y148861D02*
X153132Y149826D01*
G01X153127Y148414D02*
X153130Y148861D01*
G01X153124Y148009D02*
X153127Y148414D01*
G01X153120Y147656D02*
X153124Y148009D01*
G01X153116Y147364D02*
X153120Y147656D01*
G01X153111Y147143D02*
X153116Y147364D01*
G01X153106Y146999D02*
X153111Y147143D01*
G01X153133Y150521D02*
X153132Y149826D01*
G01X153135Y150838D02*
X153133Y150521D01*
G01X153137Y151120D02*
X153135Y150838D01*
G01X153140Y151359D02*
X153137Y151120D01*
G01X153144Y151547D02*
X153140Y151359D01*
G01X153147Y151677D02*
X153144Y151547D01*
G01X153151Y151746D02*
X153147Y151677D01*
G01X153155Y151750D02*
X153151Y151746D01*
G01X153140Y148520D02*
X153143Y149807D01*
G01X153137Y147925D02*
X153140Y148520D01*
G01X153133Y147384D02*
X153137Y147925D01*
G01X153127Y146913D02*
X153133Y147384D01*
G01X153122Y146524D02*
X153127Y146913D01*
G01X153115Y146230D02*
X153122Y146524D01*
G01X153108Y146037D02*
X153115Y146230D01*
G01X153043Y144988D02*
X153058Y145050D01*
G01X153036Y145118D02*
X153043Y144988D01*
G01X153029Y145353D02*
X153036Y145118D01*
G01X154764Y144988D02*
X154777Y145353D01*
G01X154756Y144965D02*
X154764Y144988D01*
G01X154749Y145050D02*
X154756Y144965D01*
G01X154685Y146524D02*
X154699Y146037D01*
G01X154679Y146913D02*
X154685Y146524D01*
G01X154674Y147384D02*
X154679Y146913D01*
G01X154670Y147925D02*
X154674Y147384D01*
G01X154667Y148520D02*
X154670Y147925D01*
G01X154665Y149153D02*
X154667Y148520D01*
G01X154664Y149807D02*
X154665Y149153D01*
G01X154659Y151677D02*
X154651Y151750D01*
G01X154663Y151547D02*
X154659Y151677D01*
G01X154666Y151359D02*
X154663Y151547D01*
G01X154669Y151120D02*
X154666Y151359D01*
G01X154672Y150838D02*
X154669Y151120D01*
G01X154673Y150521D02*
X154672Y150838D01*
G01X154675Y150180D02*
X154673Y150521D01*
G01X154675Y149826D02*
Y150180D01*
G01X154691Y147364D02*
X154701Y146999D01*
G01X154686Y147656D02*
X154691Y147364D01*
G01X154682Y148009D02*
X154686Y147656D01*
G01X154679Y148414D02*
X154682Y148009D01*
G01X154677Y148861D02*
X154679Y148414D01*
G01X154676Y149336D02*
X154677Y148861D01*
G01X154675Y149826D02*
X154676Y149336D01*
G01X154762Y145965D02*
X154773Y146239D01*
G01X154757Y145948D02*
X154762Y145965D01*
G01X154751Y146012D02*
X154757Y145948D01*
G01X154753Y140412D02*
X154742Y140365D01*
G01X154758Y140314D02*
X154753Y140412D01*
G01X154763Y140138D02*
X154758Y140314D01*
G01X154668Y137516D02*
X154666Y136551D01*
G01X154670Y137963D02*
X154668Y137516D01*
G01X154673Y138368D02*
X154670Y137963D01*
G01X154677Y138722D02*
X154673Y138368D01*
G01X154681Y139013D02*
X154677Y138722D01*
G01X154686Y139234D02*
X154681Y139013D01*
G01X154692Y139379D02*
X154686Y139234D01*
G01X154664Y135857D02*
X154666Y136551D01*
G01X154662Y135540D02*
X154664Y135857D01*
G01X154660Y135257D02*
X154662Y135540D01*
G01X154657Y135018D02*
X154660Y135257D01*
G01X154654Y134830D02*
X154657Y135018D01*
G01X154650Y134700D02*
X154654Y134830D01*
G01X154646Y134632D02*
X154650Y134700D01*
G01X154642Y134627D02*
X154646Y134632D01*
G01X154657Y137857D02*
X154655Y136570D01*
G01X154660Y138453D02*
X154657Y137857D01*
G01X154665Y138993D02*
X154660Y138453D01*
G01X154670Y139464D02*
X154665Y138993D01*
G01X154676Y139853D02*
X154670Y139464D01*
G01X154682Y140148D02*
X154676Y139853D01*
G01X154689Y140340D02*
X154682Y140148D01*
G01X154754Y141390D02*
X154740Y141327D01*
G01X154761Y141259D02*
X154754Y141390D01*
G01X154768Y141024D02*
X154761Y141259D01*
G01X153034Y141390D02*
X153020Y141024D01*
G01X153041Y141412D02*
X153034Y141390D01*
G01X153048Y141327D02*
X153041Y141412D01*
G01X153112Y139853D02*
X153099Y140340D01*
G01X153118Y139464D02*
X153112Y139853D01*
G01X153123Y138993D02*
X153118Y139464D01*
G01X153127Y138453D02*
X153123Y138993D01*
G01X153131Y137857D02*
X153127Y138453D01*
G01X153132Y137224D02*
X153131Y137857D01*
G01X153133Y136570D02*
X153132Y137224D01*
G01X153138Y134700D02*
X153146Y134627D01*
G01X153134Y134830D02*
X153138Y134700D01*
G01X153131Y135018D02*
X153134Y134830D01*
G01X153128Y135257D02*
X153131Y135018D01*
G01X153126Y135540D02*
X153128Y135257D01*
G01X153124Y135857D02*
X153126Y135540D01*
G01X153123Y136198D02*
X153124Y135857D01*
G01X153122Y136551D02*
X153123Y136198D01*
G01X153107Y139013D02*
X153096Y139379D01*
G01X153111Y138722D02*
X153107Y139013D01*
G01X153115Y138368D02*
X153111Y138722D01*
G01X153118Y137963D02*
X153115Y138368D01*
G01X153120Y137516D02*
X153118Y137963D01*
G01X153122Y137041D02*
X153120Y137516D01*
G01X153122Y136551D02*
Y137041D01*
G01X153035Y140412D02*
X153025Y140138D01*
G01X153040Y140429D02*
X153035Y140412D01*
G01X153046Y140365D02*
X153040Y140429D01*
G01X125481Y145965D02*
X125491Y146012D01*
G01X125475Y146063D02*
X125481Y145965D01*
G01X125470Y146239D02*
X125475Y146063D01*
G01X125566Y148861D02*
X125568Y149826D01*
G01X125564Y148414D02*
X125566Y148861D01*
G01X125560Y148009D02*
X125564Y148414D01*
G01X125557Y147656D02*
X125560Y148009D01*
G01X125552Y147364D02*
X125557Y147656D01*
G01X125547Y147143D02*
X125552Y147364D01*
G01X125542Y146999D02*
X125547Y147143D01*
G01X125576Y148520D02*
X125579Y149807D01*
G01X125573Y147925D02*
X125576Y148520D01*
G01X125569Y147384D02*
X125573Y147925D01*
G01X125564Y146913D02*
X125569Y147384D01*
G01X125558Y146524D02*
X125564Y146913D01*
G01X125551Y146230D02*
X125558Y146524D01*
G01X125544Y146037D02*
X125551Y146230D01*
G01X125479Y144988D02*
X125494Y145050D01*
G01X125472Y145118D02*
X125479Y144988D01*
G01X125465Y145353D02*
X125472Y145118D01*
G01X127200Y144988D02*
X127214Y145353D01*
G01X127193Y144965D02*
X127200Y144988D01*
G01X127185Y145050D02*
X127193Y144965D01*
G01X127121Y146524D02*
X127135Y146037D01*
G01X127115Y146913D02*
X127121Y146524D01*
G01X127110Y147384D02*
X127115Y146913D01*
G01X127106Y147925D02*
X127110Y147384D01*
G01X127103Y148520D02*
X127106Y147925D01*
G01X127101Y149153D02*
X127103Y148520D01*
G01X127100Y149807D02*
X127101Y149153D01*
G01X127127Y147364D02*
X127137Y146999D01*
G01X127123Y147656D02*
X127127Y147364D01*
G01X127119Y148009D02*
X127123Y147656D01*
G01X127116Y148414D02*
X127119Y148009D01*
G01X127113Y148861D02*
X127116Y148414D01*
G01X127112Y149336D02*
X127113Y148861D01*
G01X127111Y149826D02*
X127112Y149336D01*
G01X127199Y145965D02*
X127209Y146239D01*
G01X127193Y145948D02*
X127199Y145965D01*
G01X127188Y146012D02*
X127193Y145948D01*
G01X125580Y136197D02*
X125579Y136570D01*
G01X125582Y135887D02*
X125580Y136197D01*
G01X125586Y135680D02*
X125582Y135887D01*
G01X125590Y135605D02*
X125586Y135680D01*
G01X127099Y150180D02*
X127100Y149807D01*
G01X127097Y150490D02*
X127099Y150180D01*
G01X127093Y150698D02*
X127097Y150490D01*
G01X127089Y150772D02*
X127093Y150698D01*
G01X121390Y152484D02*
X121384Y152538D01*
G01X121396Y152353D02*
X121390Y152484D01*
G01X121402Y152147D02*
X121396Y152353D01*
G01X123415Y133893D02*
X123421Y133840D01*
G01X123409Y134024D02*
X123415Y133893D01*
G01X123403Y134231D02*
X123409Y134024D01*
G01X125322Y152484D02*
X125316Y152538D01*
G01X125328Y152353D02*
X125322Y152484D01*
G01X125334Y152147D02*
X125328Y152353D01*
G01X127357Y133893D02*
X127363Y133840D01*
G01X127351Y134024D02*
X127357Y133893D01*
G01X127345Y134231D02*
X127351Y134024D01*
G01X129264Y152484D02*
X129258Y152538D01*
G01X129270Y152353D02*
X129264Y152484D01*
G01X129276Y152147D02*
X129270Y152353D01*
G01X131289Y133893D02*
X131295Y133840D01*
G01X131283Y134024D02*
X131289Y133893D01*
G01X131278Y134231D02*
X131283Y134024D01*
G01X121388Y151511D02*
X121384Y151553D01*
G01X121393Y151413D02*
X121388Y151511D01*
G01X121397Y151260D02*
X121393Y151413D01*
G01X123417Y134866D02*
X123421Y134824D01*
G01X123413Y134965D02*
X123417Y134866D01*
G01X123408Y135117D02*
X123413Y134965D01*
G01X125320Y151511D02*
X125316Y151553D01*
G01X125325Y151413D02*
X125320Y151511D01*
G01X125329Y151260D02*
X125325Y151413D01*
G01X127359Y134866D02*
X127363Y134824D01*
G01X127354Y134965D02*
X127359Y134866D01*
G01X127350Y135117D02*
X127354Y134965D01*
G01X129262Y151511D02*
X129258Y151553D01*
G01X129267Y151413D02*
X129262Y151511D01*
G01X129271Y151260D02*
X129267Y151413D01*
G01X131291Y134866D02*
X131296Y134824D01*
G01X131287Y134965D02*
X131291Y134866D01*
G01X131282Y135117D02*
X131287Y134965D01*
G01X121645Y135645D02*
X121650Y135615D01*
G01X121641Y135841D02*
X121645Y135645D01*
G01X121638Y136168D02*
X121641Y135841D01*
G01X121637Y136570D02*
X121638Y136168D01*
G01X123160Y150733D02*
X123155Y150762D01*
G01X123164Y150537D02*
X123160Y150733D01*
G01X123167Y150209D02*
X123164Y150537D01*
G01X123168Y149807D02*
X123167Y150209D01*
G01X129519Y135645D02*
X129524Y135615D01*
G01X129515Y135841D02*
X129519Y135645D01*
G01X129512Y136168D02*
X129515Y135841D01*
G01X129511Y136570D02*
X129512Y136168D01*
G01X131034Y150733D02*
X131029Y150762D01*
G01X131038Y150537D02*
X131034Y150733D01*
G01X131041Y150209D02*
X131038Y150537D01*
G01X131042Y149807D02*
X131041Y150209D01*
G01X125581Y134770D02*
X125590Y134621D01*
G01X125574Y135184D02*
X125581Y134770D01*
G01X125570Y135804D02*
X125574Y135184D01*
G01X125568Y136551D02*
X125570Y135804D01*
G01X127098Y151608D02*
X127089Y151756D01*
G01X127105Y151193D02*
X127098Y151608D01*
G01X127109Y150573D02*
X127105Y151193D01*
G01X127111Y149826D02*
X127109Y150573D01*
G01X133455Y134770D02*
X133464Y134621D01*
G01X133448Y135184D02*
X133455Y134770D01*
G01X133444Y135804D02*
X133448Y135184D01*
G01X133442Y136551D02*
X133444Y135804D01*
G01X125586Y150698D02*
X125590Y150772D01*
G01X125582Y150490D02*
X125586Y150698D01*
G01X125580Y150180D02*
X125582Y150490D01*
G01X125579Y149807D02*
X125580Y150180D01*
G01X127093Y135680D02*
X127089Y135605D01*
G01X127097Y135887D02*
X127093Y135680D01*
G01X127099Y136197D02*
X127097Y135887D01*
G01X127100Y136570D02*
X127099Y136197D01*
G01X133460Y150698D02*
X133464Y150772D01*
G01X133456Y150490D02*
X133460Y150698D01*
G01X133454Y150180D02*
X133456Y150490D01*
G01X133453Y149807D02*
X133454Y150180D01*
G01X125570Y150573D02*
X125568Y149826D01*
G01X125574Y151193D02*
X125570Y150573D01*
G01X125581Y151608D02*
X125574Y151193D01*
G01X125590Y151756D02*
X125581Y151608D01*
G01X127109Y135804D02*
X127111Y136551D01*
G01X127105Y135184D02*
X127109Y135804D01*
G01X127098Y134770D02*
X127105Y135184D01*
G01X127089Y134621D02*
X127098Y134770D01*
G01X133444Y150573D02*
X133442Y149826D01*
G01X133448Y151193D02*
X133444Y150573D01*
G01X133455Y151608D02*
X133448Y151193D01*
G01X133464Y151756D02*
X133455Y151608D01*
G01X134983Y135804D02*
X134985Y136551D01*
G01X134979Y135184D02*
X134983Y135804D01*
G01X134972Y134770D02*
X134979Y135184D01*
G01X134963Y134621D02*
X134972Y134770D01*
G01X125590Y135606D02*
Y135605D01*
G01X125591Y135610D02*
X125590Y135606D01*
G01X125592Y135617D02*
X125591Y135610D01*
G01X127089Y150771D02*
Y150772D01*
G01X127088Y150768D02*
X127089Y150771D01*
G01X127088Y150760D02*
Y150768D01*
G01X133464Y135606D02*
Y135605D01*
G01X133465Y135610D02*
X133464Y135606D01*
G01X133466Y135617D02*
X133465Y135610D01*
G01X134963Y150771D02*
Y150772D01*
G01X134962Y150768D02*
X134963Y150771D01*
G01X134962Y150760D02*
Y150768D01*
G01X121383Y134965D02*
X121387Y135117D01*
G01X121379Y134866D02*
X121383Y134965D01*
G01X121374Y134824D02*
X121379Y134866D01*
G01X123422Y151413D02*
X123418Y151260D01*
G01X123426Y151511D02*
X123422Y151413D01*
G01X123431Y151553D02*
X123426Y151511D01*
G01X125325Y134965D02*
X125329Y135117D01*
G01X125320Y134866D02*
X125325Y134965D01*
G01X125316Y134824D02*
X125320Y134866D01*
G01X127354Y151413D02*
X127350Y151260D01*
G01X127359Y151511D02*
X127354Y151413D01*
G01X127363Y151553D02*
X127359Y151511D01*
G01X129257Y134965D02*
X129261Y135117D01*
G01X129253Y134866D02*
X129257Y134965D01*
G01X129248Y134824D02*
X129253Y134866D01*
G01X131296Y151413D02*
X131292Y151260D01*
G01X131300Y151511D02*
X131296Y151413D01*
G01X131305Y151553D02*
X131300Y151511D01*
G01X133199Y134965D02*
X133203Y135117D01*
G01X133194Y134866D02*
X133199Y134965D01*
G01X133190Y134824D02*
X133194Y134866D01*
G01X135228Y151413D02*
X135224Y151260D01*
G01X135233Y151511D02*
X135228Y151413D01*
G01X135237Y151553D02*
X135233Y151511D01*
G01X137131Y134965D02*
X137135Y135117D01*
G01X137127Y134866D02*
X137131Y134965D01*
G01X137122Y134824D02*
X137127Y134866D01*
G01X139170Y151413D02*
X139166Y151260D01*
G01X139174Y151511D02*
X139170Y151413D01*
G01X139179Y151553D02*
X139174Y151511D01*
G01X123419Y152353D02*
X123413Y152147D01*
G01X123425Y152484D02*
X123419Y152353D01*
G01X123431Y152538D02*
X123425Y152484D01*
G01X121386Y134024D02*
X121392Y134231D01*
G01X121380Y133893D02*
X121386Y134024D01*
G01X121374Y133840D02*
X121380Y133893D01*
G01X127351Y152353D02*
X127345Y152147D01*
G01X127357Y152484D02*
X127351Y152353D01*
G01X127363Y152538D02*
X127357Y152484D01*
G01X125328Y134024D02*
X125334Y134231D01*
G01X125322Y133893D02*
X125328Y134024D01*
G01X125316Y133840D02*
X125322Y133893D01*
G01X131293Y152353D02*
X131287Y152147D01*
G01X131299Y152484D02*
X131293Y152353D01*
G01X131305Y152538D02*
X131299Y152484D01*
G01X129260Y134024D02*
X129266Y134231D01*
G01X129254Y133893D02*
X129260Y134024D01*
G01X129248Y133840D02*
X129254Y133893D01*
G01X135225Y152353D02*
X135219Y152147D01*
G01X135231Y152484D02*
X135225Y152353D01*
G01X135237Y152538D02*
X135231Y152484D01*
G01X133202Y134024D02*
X133208Y134231D01*
G01X133196Y133893D02*
X133202Y134024D01*
G01X133190Y133840D02*
X133196Y133893D01*
G01X139167Y152353D02*
X139161Y152147D01*
G01X139173Y152484D02*
X139167Y152353D01*
G01X139179Y152538D02*
X139173Y152484D01*
G01X137135Y134024D02*
X137140Y134231D01*
G01X137128Y133893D02*
X137135Y134024D01*
G01X137122Y133840D02*
X137128Y133893D01*
G01X121648Y150209D02*
X121647Y149807D01*
G01X121650Y150537D02*
X121648Y150209D01*
G01X121654Y150733D02*
X121650Y150537D01*
G01X121659Y150762D02*
X121654Y150733D01*
G01X123158Y136168D02*
X123159Y136570D01*
G01X123155Y135841D02*
X123158Y136168D01*
G01X123151Y135645D02*
X123155Y135841D01*
G01X123146Y135615D02*
X123151Y135645D01*
G01X129522Y150209D02*
X129521Y149807D01*
G01X129524Y150537D02*
X129522Y150209D01*
G01X129528Y150733D02*
X129524Y150537D01*
G01X129533Y150762D02*
X129528Y150733D01*
G01X131032Y136168D02*
X131033Y136570D01*
G01X131029Y135841D02*
X131032Y136168D01*
G01X131025Y135645D02*
X131029Y135841D01*
G01X131020Y135615D02*
X131025Y135645D01*
G01X137396Y150209D02*
X137395Y149807D01*
G01X137398Y150537D02*
X137396Y150209D01*
G01X137402Y150733D02*
X137398Y150537D01*
G01X137407Y150762D02*
X137402Y150733D01*
G01X138906Y136168D02*
X138907Y136570D01*
G01X138903Y135841D02*
X138906Y136168D01*
G01X138899Y135645D02*
X138903Y135841D01*
G01X138894Y135615D02*
X138899Y135645D01*
G01X127088Y151754D02*
Y151750D01*
G01X127089Y151756D02*
X127088Y151754D01*
G01X133454Y136197D02*
X133453Y136570D01*
G01X133456Y135887D02*
X133454Y136197D01*
G01X133460Y135680D02*
X133456Y135887D01*
G01X133464Y135605D02*
X133460Y135680D01*
G01X134973Y150180D02*
X134974Y149807D01*
G01X134971Y150490D02*
X134973Y150180D01*
G01X134967Y150698D02*
X134971Y150490D01*
G01X134963Y150772D02*
X134967Y150698D01*
G01X141328Y136197D02*
X141327Y136570D01*
G01X141330Y135887D02*
X141328Y136197D01*
G01X141334Y135680D02*
X141330Y135887D01*
G01X141338Y135605D02*
X141334Y135680D01*
G01X142847Y150180D02*
X142848Y149807D01*
G01X142845Y150490D02*
X142847Y150180D01*
G01X142841Y150698D02*
X142845Y150490D01*
G01X142837Y150772D02*
X142841Y150698D01*
G01X149202Y136197D02*
X149201Y136570D01*
G01X149204Y135887D02*
X149202Y136197D01*
G01X149208Y135680D02*
X149204Y135887D01*
G01X149212Y135605D02*
X149208Y135680D01*
G01X150721Y150180D02*
X150722Y149807D01*
G01X150719Y150490D02*
X150721Y150180D01*
G01X150716Y150698D02*
X150719Y150490D01*
G01X150711Y150772D02*
X150716Y150698D01*
G01X133196Y152484D02*
X133190Y152538D01*
G01X133202Y152353D02*
X133196Y152484D01*
G01X133208Y152147D02*
X133202Y152353D01*
G01X135231Y133893D02*
X135237Y133840D01*
G01X135225Y134024D02*
X135231Y133893D01*
G01X135219Y134231D02*
X135225Y134024D01*
G01X137138Y152484D02*
X137132Y152538D01*
G01X137144Y152353D02*
X137138Y152484D01*
G01X137150Y152147D02*
X137144Y152353D01*
G01X139163Y133893D02*
X139170Y133840D01*
G01X139157Y134024D02*
X139163Y133893D01*
G01X139152Y134231D02*
X139157Y134024D01*
G01X141070Y152484D02*
X141064Y152538D01*
G01X141076Y152353D02*
X141070Y152484D01*
G01X141082Y152147D02*
X141076Y152353D01*
G01X143105Y133893D02*
X143111Y133840D01*
G01X143099Y134024D02*
X143105Y133893D01*
G01X143093Y134231D02*
X143099Y134024D01*
G01X145012Y152484D02*
X145006Y152538D01*
G01X145018Y152353D02*
X145012Y152484D01*
G01X145024Y152147D02*
X145018Y152353D01*
G01X147037Y133893D02*
X147044Y133840D01*
G01X147031Y134024D02*
X147037Y133893D01*
G01X147026Y134231D02*
X147031Y134024D01*
G01X148944Y152484D02*
X148938Y152538D01*
G01X148950Y152353D02*
X148944Y152484D01*
G01X148956Y152147D02*
X148950Y152353D01*
G01X150979Y133893D02*
X150985Y133840D01*
G01X150973Y134024D02*
X150979Y133893D01*
G01X150967Y134231D02*
X150973Y134024D01*
G01X152886Y152484D02*
X152880Y152538D01*
G01X152892Y152353D02*
X152886Y152484D01*
G01X152898Y152147D02*
X152892Y152353D01*
G01X154911Y133893D02*
X154918Y133840D01*
G01X154905Y134024D02*
X154911Y133893D01*
G01X154900Y134231D02*
X154905Y134024D01*
G01X156818Y152484D02*
X156812Y152538D01*
G01X156824Y152353D02*
X156818Y152484D01*
G01X156830Y152147D02*
X156824Y152353D01*
G01X133194Y151511D02*
X133190Y151553D01*
G01X133199Y151413D02*
X133194Y151511D01*
G01X133203Y151260D02*
X133199Y151413D01*
G01X135233Y134866D02*
X135237Y134824D01*
G01X135228Y134965D02*
X135233Y134866D01*
G01X135224Y135117D02*
X135228Y134965D01*
G01X137136Y151511D02*
X137132Y151553D01*
G01X137141Y151413D02*
X137136Y151511D01*
G01X137145Y151260D02*
X137141Y151413D01*
G01X139165Y134866D02*
X139170Y134824D01*
G01X139161Y134965D02*
X139165Y134866D01*
G01X139156Y135117D02*
X139161Y134965D01*
G01X141069Y151511D02*
X141064Y151553D01*
G01X141073Y151413D02*
X141069Y151511D01*
G01X141077Y151260D02*
X141073Y151413D01*
G01X143107Y134866D02*
X143111Y134824D01*
G01X143102Y134965D02*
X143107Y134866D01*
G01X143098Y135117D02*
X143102Y134965D01*
G01X145010Y151511D02*
X145006Y151553D01*
G01X145015Y151413D02*
X145010Y151511D01*
G01X145019Y151260D02*
X145015Y151413D01*
G01X147039Y134866D02*
X147044Y134824D01*
G01X147035Y134965D02*
X147039Y134866D01*
G01X147030Y135117D02*
X147035Y134965D01*
G01X148943Y151511D02*
X148938Y151553D01*
G01X148947Y151413D02*
X148943Y151511D01*
G01X148951Y151260D02*
X148947Y151413D01*
G01X150981Y134866D02*
X150985Y134824D01*
G01X150976Y134965D02*
X150981Y134866D01*
G01X150972Y135117D02*
X150976Y134965D01*
G01X152884Y151511D02*
X152880Y151553D01*
G01X152889Y151413D02*
X152884Y151511D01*
G01X152893Y151260D02*
X152889Y151413D01*
G01X154913Y134866D02*
X154918Y134824D01*
G01X154909Y134965D02*
X154913Y134866D01*
G01X154904Y135117D02*
X154909Y134965D01*
G01X156817Y151511D02*
X156812Y151553D01*
G01X156821Y151413D02*
X156817Y151511D01*
G01X156825Y151260D02*
X156821Y151413D01*
G01X137393Y135645D02*
X137398Y135615D01*
G01X137389Y135841D02*
X137393Y135645D01*
G01X137386Y136168D02*
X137389Y135841D01*
G01X137385Y136570D02*
X137386Y136168D01*
G01X138908Y150733D02*
X138903Y150762D01*
G01X138912Y150537D02*
X138908Y150733D01*
G01X138915Y150209D02*
X138912Y150537D01*
G01X138916Y149807D02*
X138915Y150209D01*
G01X145267Y135645D02*
X145272Y135615D01*
G01X145263Y135841D02*
X145267Y135645D01*
G01X145260Y136168D02*
X145263Y135841D01*
G01X145259Y136570D02*
X145260Y136168D01*
G01X146782Y150733D02*
X146777Y150762D01*
G01X146786Y150537D02*
X146782Y150733D01*
G01X146789Y150209D02*
X146786Y150537D01*
G01X146790Y149807D02*
X146789Y150209D01*
G01X153141Y135645D02*
X153146Y135615D01*
G01X153137Y135841D02*
X153141Y135645D01*
G01X153134Y136168D02*
X153137Y135841D01*
G01X153133Y136570D02*
X153134Y136168D01*
G01X154656Y150733D02*
X154651Y150762D01*
G01X154660Y150537D02*
X154656Y150733D01*
G01X154663Y150209D02*
X154660Y150537D01*
G01X154664Y149807D02*
X154663Y150209D01*
G01X134972Y151608D02*
X134963Y151756D01*
G01X134979Y151193D02*
X134972Y151608D01*
G01X134983Y150573D02*
X134979Y151193D01*
G01X134985Y149826D02*
X134983Y150573D01*
G01X141329Y134770D02*
X141338Y134621D01*
G01X141322Y135184D02*
X141329Y134770D01*
G01X141318Y135804D02*
X141322Y135184D01*
G01X141316Y136551D02*
X141318Y135804D01*
G01X142846Y151608D02*
X142837Y151756D01*
G01X142853Y151193D02*
X142846Y151608D01*
G01X142857Y150573D02*
X142853Y151193D01*
G01X142859Y149826D02*
X142857Y150573D01*
G01X149203Y134770D02*
X149212Y134621D01*
G01X149196Y135184D02*
X149203Y134770D01*
G01X149192Y135804D02*
X149196Y135184D01*
G01X149190Y136551D02*
X149192Y135804D01*
G01X150720Y151608D02*
X150711Y151756D01*
G01X150727Y151193D02*
X150720Y151608D01*
G01X150731Y150573D02*
X150727Y151193D01*
G01X150733Y149826D02*
X150731Y150573D01*
G01X157078Y134770D02*
X157086Y134621D01*
G01X157071Y135184D02*
X157078Y134770D01*
G01X157066Y135804D02*
X157071Y135184D01*
G01X157064Y136551D02*
X157066Y135804D01*
G01X158594Y151608D02*
X158585Y151756D01*
G01X158601Y151193D02*
X158594Y151608D01*
G01X158605Y150573D02*
X158601Y151193D01*
G01X158607Y149826D02*
X158605Y150573D01*
G01X134967Y135680D02*
X134963Y135605D01*
G01X134971Y135887D02*
X134967Y135680D01*
G01X134973Y136197D02*
X134971Y135887D01*
G01X134974Y136570D02*
X134973Y136197D01*
G01X141334Y150698D02*
X141338Y150772D01*
G01X141330Y150490D02*
X141334Y150698D01*
G01X141328Y150180D02*
X141330Y150490D01*
G01X141327Y149807D02*
X141328Y150180D01*
G01X142841Y135680D02*
X142837Y135605D01*
G01X142845Y135887D02*
X142841Y135680D01*
G01X142847Y136197D02*
X142845Y135887D01*
G01X142848Y136570D02*
X142847Y136197D01*
G01X149208Y150698D02*
X149212Y150772D01*
G01X149204Y150490D02*
X149208Y150698D01*
G01X149202Y150180D02*
X149204Y150490D01*
G01X149201Y149807D02*
X149202Y150180D01*
G01X150716Y135680D02*
X150711Y135605D01*
G01X150719Y135887D02*
X150716Y135680D01*
G01X150721Y136197D02*
X150719Y135887D01*
G01X150722Y136570D02*
X150721Y136197D01*
G01X157082Y150698D02*
X157086Y150772D01*
G01X157078Y150490D02*
X157082Y150698D01*
G01X157076Y150180D02*
X157078Y150490D01*
G01X157075Y149807D02*
X157076Y150180D01*
G01X158590Y135680D02*
X158585Y135605D01*
G01X158593Y135887D02*
X158590Y135680D01*
G01X158595Y136197D02*
X158593Y135887D01*
G01X158596Y136570D02*
X158595Y136197D01*
G01X141318Y150573D02*
X141316Y149826D01*
G01X141322Y151193D02*
X141318Y150573D01*
G01X141329Y151608D02*
X141322Y151193D01*
G01X141338Y151756D02*
X141329Y151608D01*
G01X142857Y135804D02*
X142859Y136551D01*
G01X142853Y135184D02*
X142857Y135804D01*
G01X142846Y134770D02*
X142853Y135184D01*
G01X142837Y134621D02*
X142846Y134770D01*
G01X149192Y150573D02*
X149190Y149826D01*
G01X149196Y151193D02*
X149192Y150573D01*
G01X149203Y151608D02*
X149196Y151193D01*
G01X149212Y151756D02*
X149203Y151608D01*
G01X150731Y135804D02*
X150733Y136551D01*
G01X150727Y135184D02*
X150731Y135804D01*
G01X150720Y134770D02*
X150727Y135184D01*
G01X150711Y134621D02*
X150720Y134770D01*
G01X157066Y150573D02*
X157064Y149826D01*
G01X157071Y151193D02*
X157066Y150573D01*
G01X157078Y151608D02*
X157071Y151193D01*
G01X157086Y151756D02*
X157078Y151608D01*
G01X158605Y135804D02*
X158607Y136551D01*
G01X158601Y135184D02*
X158605Y135804D01*
G01X158594Y134770D02*
X158601Y135184D01*
G01X158585Y134621D02*
X158594Y134770D01*
G01X141338Y135606D02*
Y135605D01*
G01X141339Y135610D02*
X141338Y135606D01*
G01X141340Y135617D02*
X141339Y135610D01*
G01X142837Y150771D02*
Y150772D01*
G01X142836Y150768D02*
X142837Y150771D01*
G01X142836Y150760D02*
Y150768D01*
G01X149212Y135606D02*
Y135605D01*
G01X149213Y135610D02*
X149212Y135606D01*
G01X149214Y135617D02*
X149213Y135610D01*
G01X150711Y150771D02*
Y150772D01*
G01X150710Y150768D02*
X150711Y150771D01*
G01X150710Y150760D02*
Y150768D01*
G01X157086Y135606D02*
Y135605D01*
G01X157087Y135610D02*
X157086Y135606D01*
G01X157088Y135617D02*
X157087Y135610D01*
G01X158585Y150771D02*
Y150772D01*
G01X158584Y150768D02*
X158585Y150771D01*
G01X158584Y150760D02*
Y150768D01*
G01X141073Y134965D02*
X141077Y135117D01*
G01X141069Y134866D02*
X141073Y134965D01*
G01X141064Y134824D02*
X141069Y134866D01*
G01X143102Y151413D02*
X143098Y151260D01*
G01X143107Y151511D02*
X143102Y151413D01*
G01X143111Y151553D02*
X143107Y151511D01*
G01X145005Y134965D02*
X145009Y135117D01*
G01X145001Y134866D02*
X145005Y134965D01*
G01X144996Y134824D02*
X145001Y134866D01*
G01X147044Y151413D02*
X147040Y151260D01*
G01X147048Y151511D02*
X147044Y151413D01*
G01X147053Y151553D02*
X147048Y151511D01*
G01X148947Y134965D02*
X148951Y135117D01*
G01X148943Y134866D02*
X148947Y134965D01*
G01X148938Y134824D02*
X148943Y134866D01*
G01X150976Y151413D02*
X150972Y151260D01*
G01X150981Y151511D02*
X150976Y151413D01*
G01X150985Y151553D02*
X150981Y151511D01*
G01X152879Y134965D02*
X152884Y135117D01*
G01X152875Y134866D02*
X152879Y134965D01*
G01X152870Y134824D02*
X152875Y134866D01*
G01X154918Y151413D02*
X154914Y151260D01*
G01X154922Y151511D02*
X154918Y151413D01*
G01X154927Y151553D02*
X154922Y151511D01*
G01X156821Y134965D02*
X156825Y135117D01*
G01X156817Y134866D02*
X156821Y134965D01*
G01X156812Y134824D02*
X156817Y134866D01*
G01X158850Y151413D02*
X158846Y151260D01*
G01X158855Y151511D02*
X158850Y151413D01*
G01X158859Y151553D02*
X158855Y151511D01*
G01X160753Y134965D02*
X160758Y135117D01*
G01X160749Y134866D02*
X160753Y134965D01*
G01X160744Y134824D02*
X160749Y134866D01*
G01X162792Y151413D02*
X162788Y151260D01*
G01X162796Y151511D02*
X162792Y151413D01*
G01X162801Y151553D02*
X162796Y151511D01*
G01X143099Y152353D02*
X143093Y152147D01*
G01X143105Y152484D02*
X143099Y152353D01*
G01X143111Y152538D02*
X143105Y152484D01*
G01X141076Y134024D02*
X141082Y134231D01*
G01X141070Y133893D02*
X141076Y134024D01*
G01X141064Y133840D02*
X141070Y133893D01*
G01X147041Y152353D02*
X147035Y152147D01*
G01X147047Y152484D02*
X147041Y152353D01*
G01X147053Y152538D02*
X147047Y152484D01*
G01X145009Y134024D02*
X145014Y134231D01*
G01X145002Y133893D02*
X145009Y134024D01*
G01X144996Y133840D02*
X145002Y133893D01*
G01X150973Y152353D02*
X150967Y152147D01*
G01X150979Y152484D02*
X150973Y152353D01*
G01X150985Y152538D02*
X150979Y152484D01*
G01X148950Y134024D02*
X148956Y134231D01*
G01X148944Y133893D02*
X148950Y134024D01*
G01X148938Y133840D02*
X148944Y133893D01*
G01X154915Y152353D02*
X154909Y152147D01*
G01X154921Y152484D02*
X154915Y152353D01*
G01X154927Y152538D02*
X154921Y152484D01*
G01X152883Y134024D02*
X152888Y134231D01*
G01X152876Y133893D02*
X152883Y134024D01*
G01X152870Y133840D02*
X152876Y133893D01*
G01X158847Y152353D02*
X158841Y152147D01*
G01X158853Y152484D02*
X158847Y152353D01*
G01X158859Y152538D02*
X158853Y152484D01*
G01X156824Y134024D02*
X156830Y134231D01*
G01X156818Y133893D02*
X156824Y134024D01*
G01X156812Y133840D02*
X156818Y133893D01*
G01X162789Y152353D02*
X162783Y152147D01*
G01X162795Y152484D02*
X162789Y152353D01*
G01X162801Y152538D02*
X162795Y152484D01*
G01X160757Y134024D02*
X160762Y134231D01*
G01X160751Y133893D02*
X160757Y134024D01*
G01X160744Y133840D02*
X160751Y133893D01*
G01X145270Y150209D02*
X145269Y149807D01*
G01X145272Y150537D02*
X145270Y150209D01*
G01X145276Y150733D02*
X145272Y150537D01*
G01X145281Y150762D02*
X145276Y150733D01*
G01X146780Y136168D02*
X146781Y136570D01*
G01X146777Y135841D02*
X146780Y136168D01*
G01X146773Y135645D02*
X146777Y135841D01*
G01X146768Y135615D02*
X146773Y135645D01*
G01X153144Y150209D02*
X153143Y149807D01*
G01X153146Y150537D02*
X153144Y150209D01*
G01X153150Y150733D02*
X153146Y150537D01*
G01X153155Y150762D02*
X153150Y150733D01*
G01X154654Y136168D02*
X154655Y136570D01*
G01X154651Y135841D02*
X154654Y136168D01*
G01X154647Y135645D02*
X154651Y135841D01*
G01X154642Y135615D02*
X154647Y135645D01*
G01X161018Y150209D02*
X161017Y149807D01*
G01X161020Y150537D02*
X161018Y150209D01*
G01X161024Y150733D02*
X161020Y150537D01*
G01X161029Y150762D02*
X161024Y150733D01*
G01X162528Y136168D02*
X162529Y136570D01*
G01X162525Y135841D02*
X162528Y136168D01*
G01X162521Y135645D02*
X162525Y135841D01*
G01X162516Y135615D02*
X162521Y135645D01*
G01X134962Y151754D02*
Y151750D01*
G01X134963Y151756D02*
X134962Y151754D01*
G01X125591Y134624D02*
X125592Y134627D01*
G01X125590Y134622D02*
X125591Y134624D01*
G01X125590Y134621D02*
Y134622D01*
G01X142836Y151754D02*
Y151750D01*
G01X142837Y151756D02*
X142836Y151754D01*
G01X133465Y134624D02*
X133466Y134627D01*
G01X133464Y134622D02*
X133465Y134624D01*
G01X133464Y134621D02*
Y134622D01*
G01X150710Y151754D02*
Y151750D01*
G01X150711Y151756D02*
X150710Y151754D01*
G01X141339Y134624D02*
X141340Y134627D01*
G01X141338Y134622D02*
X141339Y134624D01*
G01X141338Y134621D02*
Y134622D01*
G01X158584Y151754D02*
Y151750D01*
G01X158585Y151756D02*
X158584Y151754D01*
G01X127089Y134622D02*
Y134621D01*
G01X127088Y134624D02*
X127089Y134622D01*
G01X127088Y134627D02*
Y134624D01*
G01X125591Y151754D02*
X125590Y151756D01*
G01X125592Y151750D02*
X125591Y151754D01*
G01X134963Y134622D02*
Y134621D01*
G01X134962Y134624D02*
X134963Y134622D01*
G01X134962Y134627D02*
Y134624D01*
G01X133465Y151754D02*
X133464Y151756D01*
G01X133466Y151750D02*
X133465Y151754D01*
G01X142837Y134622D02*
Y134621D01*
G01X142836Y134624D02*
X142837Y134622D01*
G01X142836Y134627D02*
Y134624D01*
G01X141339Y151754D02*
X141338Y151756D01*
G01X141340Y151750D02*
X141339Y151754D01*
G01X157076Y136197D02*
X157075Y136570D01*
G01X157078Y135887D02*
X157076Y136197D01*
G01X157082Y135680D02*
X157078Y135887D01*
G01X157086Y135605D02*
X157082Y135680D01*
G01X158595Y150180D02*
X158596Y149807D01*
G01X158593Y150490D02*
X158595Y150180D01*
G01X158590Y150698D02*
X158593Y150490D01*
G01X158585Y150772D02*
X158590Y150698D01*
G01X172824Y136197D02*
X172823Y136570D01*
G01X172826Y135887D02*
X172824Y136197D01*
G01X172830Y135680D02*
X172826Y135887D01*
G01X172834Y135605D02*
X172830Y135680D01*
G01X174343Y150180D02*
X174344Y149807D01*
G01X174341Y150490D02*
X174343Y150180D01*
G01X174338Y150698D02*
X174341Y150490D01*
G01X174333Y150772D02*
X174338Y150698D01*
G01X158853Y133893D02*
X158859Y133840D01*
G01X158847Y134024D02*
X158853Y133893D01*
G01X158841Y134231D02*
X158847Y134024D01*
G01X160760Y152484D02*
X160754Y152538D01*
G01X160766Y152353D02*
X160760Y152484D01*
G01X160772Y152147D02*
X160766Y152353D01*
G01X162785Y133893D02*
X162792Y133840D01*
G01X162779Y134024D02*
X162785Y133893D01*
G01X162774Y134231D02*
X162779Y134024D01*
G01X172566Y152484D02*
X172560Y152538D01*
G01X172572Y152353D02*
X172566Y152484D01*
G01X172578Y152147D02*
X172572Y152353D01*
G01X174601Y133893D02*
X174607Y133840D01*
G01X174595Y134024D02*
X174601Y133893D01*
G01X174589Y134231D02*
X174595Y134024D01*
G01X176508Y152484D02*
X176502Y152538D01*
G01X176514Y152353D02*
X176508Y152484D01*
G01X176520Y152147D02*
X176514Y152353D01*
G01X178533Y133893D02*
X178540Y133840D01*
G01X178527Y134024D02*
X178533Y133893D01*
G01X178522Y134231D02*
X178527Y134024D01*
G01X180440Y152484D02*
X180434Y152538D01*
G01X180446Y152353D02*
X180440Y152484D01*
G01X180452Y152147D02*
X180446Y152353D01*
G01X158855Y134866D02*
X158859Y134824D01*
G01X158850Y134965D02*
X158855Y134866D01*
G01X158846Y135117D02*
X158850Y134965D01*
G01X160758Y151511D02*
X160754Y151553D01*
G01X160763Y151413D02*
X160758Y151511D01*
G01X160767Y151260D02*
X160763Y151413D01*
G01X162787Y134866D02*
X162792Y134824D01*
G01X162783Y134965D02*
X162787Y134866D01*
G01X162778Y135117D02*
X162783Y134965D01*
G01X172565Y151511D02*
X172560Y151553D01*
G01X172569Y151413D02*
X172565Y151511D01*
G01X172573Y151260D02*
X172569Y151413D01*
G01X174603Y134866D02*
X174607Y134824D01*
G01X174598Y134965D02*
X174603Y134866D01*
G01X174594Y135117D02*
X174598Y134965D01*
G01X176506Y151511D02*
X176502Y151553D01*
G01X176511Y151413D02*
X176506Y151511D01*
G01X176515Y151260D02*
X176511Y151413D01*
G01X178535Y134866D02*
X178540Y134824D01*
G01X178531Y134965D02*
X178535Y134866D01*
G01X178526Y135117D02*
X178531Y134965D01*
G01X180439Y151511D02*
X180434Y151553D01*
G01X180443Y151413D02*
X180439Y151511D01*
G01X180447Y151260D02*
X180443Y151413D01*
G01X161015Y135645D02*
X161020Y135615D01*
G01X161011Y135841D02*
X161015Y135645D01*
G01X161008Y136168D02*
X161011Y135841D01*
G01X161007Y136570D02*
X161008Y136168D01*
G01X162530Y150733D02*
X162525Y150762D01*
G01X162534Y150537D02*
X162530Y150733D01*
G01X162537Y150209D02*
X162534Y150537D01*
G01X162538Y149807D02*
X162537Y150209D01*
G01X176763Y135645D02*
X176768Y135615D01*
G01X176759Y135841D02*
X176763Y135645D01*
G01X176756Y136168D02*
X176759Y135841D01*
G01X176755Y136570D02*
X176756Y136168D01*
G01X178278Y150733D02*
X178274Y150762D01*
G01X178282Y150537D02*
X178278Y150733D01*
G01X178285Y150209D02*
X178282Y150537D01*
G01X178286Y149807D02*
X178285Y150209D01*
G01X172826Y134770D02*
X172834Y134621D01*
G01X172819Y135184D02*
X172826Y134770D01*
G01X172814Y135804D02*
X172819Y135184D01*
G01X172812Y136551D02*
X172814Y135804D01*
G01X174342Y151608D02*
X174333Y151756D01*
G01X174349Y151193D02*
X174342Y151608D01*
G01X174353Y150573D02*
X174349Y151193D01*
G01X174355Y149826D02*
X174353Y150573D01*
G01X180700Y134770D02*
X180708Y134621D01*
G01X180693Y135184D02*
X180700Y134770D01*
G01X180688Y135804D02*
X180693Y135184D01*
G01X180686Y136551D02*
X180688Y135804D01*
G01X182216Y151608D02*
X182207Y151756D01*
G01X182223Y151193D02*
X182216Y151608D01*
G01X182228Y150573D02*
X182223Y151193D01*
G01X182229Y149826D02*
X182228Y150573D01*
G01X172830Y150698D02*
X172834Y150772D01*
G01X172826Y150490D02*
X172830Y150698D01*
G01X172824Y150180D02*
X172826Y150490D01*
G01X172823Y149807D02*
X172824Y150180D01*
G01X174338Y135680D02*
X174333Y135605D01*
G01X174341Y135887D02*
X174338Y135680D01*
G01X174343Y136197D02*
X174341Y135887D01*
G01X174344Y136570D02*
X174343Y136197D01*
G01X180704Y150698D02*
X180708Y150772D01*
G01X180700Y150490D02*
X180704Y150698D01*
G01X180698Y150180D02*
X180700Y150490D01*
G01X180697Y149807D02*
X180698Y150180D01*
G01X182212Y135680D02*
X182207Y135605D01*
G01X182215Y135887D02*
X182212Y135680D01*
G01X182217Y136197D02*
X182215Y135887D01*
G01X182218Y136570D02*
X182217Y136197D01*
G01X172814Y150573D02*
X172812Y149826D01*
G01X172819Y151193D02*
X172814Y150573D01*
G01X172826Y151608D02*
X172819Y151193D01*
G01X172834Y151756D02*
X172826Y151608D01*
G01X174353Y135804D02*
X174355Y136551D01*
G01X174349Y135184D02*
X174353Y135804D01*
G01X174342Y134770D02*
X174349Y135184D01*
G01X174333Y134621D02*
X174342Y134770D01*
G01X180688Y150573D02*
X180686Y149826D01*
G01X180693Y151193D02*
X180688Y150573D01*
G01X180700Y151608D02*
X180693Y151193D01*
G01X180708Y151756D02*
X180700Y151608D01*
G01X182228Y135804D02*
X182229Y136551D01*
G01X182223Y135184D02*
X182228Y135804D01*
G01X182216Y134770D02*
X182223Y135184D01*
G01X182207Y134621D02*
X182216Y134770D01*
G01X172834Y135606D02*
Y135605D01*
G01X172835Y135610D02*
X172834Y135606D01*
G01X172836Y135617D02*
X172835Y135610D01*
G01X174333Y150771D02*
Y150772D01*
G01X174332Y150768D02*
X174333Y150771D01*
G01X174332Y150760D02*
Y150768D01*
G01X180708Y135606D02*
Y135605D01*
G01X180709Y135610D02*
X180708Y135606D01*
G01X180710Y135617D02*
X180709Y135610D01*
G01X182207Y150771D02*
Y150772D01*
G01X182206Y150768D02*
X182207Y150771D01*
G01X182206Y150760D02*
Y150768D01*
G01X172569Y134965D02*
X172573Y135117D01*
G01X172565Y134866D02*
X172569Y134965D01*
G01X172560Y134824D02*
X172565Y134866D01*
G01X174598Y151413D02*
X174594Y151260D01*
G01X174603Y151511D02*
X174598Y151413D01*
G01X174607Y151553D02*
X174603Y151511D01*
G01X176501Y134965D02*
X176506Y135117D01*
G01X176497Y134866D02*
X176501Y134965D01*
G01X176492Y134824D02*
X176497Y134866D01*
G01X178540Y151413D02*
X178536Y151260D01*
G01X178544Y151511D02*
X178540Y151413D01*
G01X178549Y151553D02*
X178544Y151511D01*
G01X180443Y134965D02*
X180447Y135117D01*
G01X180439Y134866D02*
X180443Y134965D01*
G01X180434Y134824D02*
X180439Y134866D01*
G01X182472Y151413D02*
X182468Y151260D01*
G01X182477Y151511D02*
X182472Y151413D01*
G01X182481Y151553D02*
X182477Y151511D01*
G01X184375Y134965D02*
X184380Y135117D01*
G01X184371Y134866D02*
X184375Y134965D01*
G01X184366Y134824D02*
X184371Y134866D01*
G01X186414Y151413D02*
X186410Y151260D01*
G01X186418Y151511D02*
X186414Y151413D01*
G01X186423Y151553D02*
X186418Y151511D01*
G01X174595Y152353D02*
X174589Y152147D01*
G01X174601Y152484D02*
X174595Y152353D01*
G01X174607Y152538D02*
X174601Y152484D01*
G01X172572Y134024D02*
X172578Y134231D01*
G01X172566Y133893D02*
X172572Y134024D01*
G01X172560Y133840D02*
X172566Y133893D01*
G01X178537Y152353D02*
X178531Y152147D01*
G01X178543Y152484D02*
X178537Y152353D01*
G01X178549Y152538D02*
X178543Y152484D01*
G01X176505Y134024D02*
X176510Y134231D01*
G01X176499Y133893D02*
X176505Y134024D01*
G01X176492Y133840D02*
X176499Y133893D01*
G01X182469Y152353D02*
X182463Y152147D01*
G01X182475Y152484D02*
X182469Y152353D01*
G01X182481Y152538D02*
X182475Y152484D01*
G01X180446Y134024D02*
X180452Y134231D01*
G01X180440Y133893D02*
X180446Y134024D01*
G01X180434Y133840D02*
X180440Y133893D01*
G01X186411Y152353D02*
X186405Y152147D01*
G01X186417Y152484D02*
X186411Y152353D01*
G01X186423Y152538D02*
X186417Y152484D01*
G01X184379Y134024D02*
X184384Y134231D01*
G01X184373Y133893D02*
X184379Y134024D01*
G01X184366Y133840D02*
X184373Y133893D01*
G01X176766Y150209D02*
X176765Y149807D01*
G01X176768Y150537D02*
X176766Y150209D01*
G01X176773Y150733D02*
X176768Y150537D01*
G01X176777Y150762D02*
X176773Y150733D01*
G01X178276Y136168D02*
X178277Y136570D01*
G01X178273Y135841D02*
X178276Y136168D01*
G01X178269Y135645D02*
X178273Y135841D01*
G01X178264Y135615D02*
X178269Y135645D01*
G01X184640Y150209D02*
X184639Y149807D01*
G01X184642Y150537D02*
X184640Y150209D01*
G01X184647Y150733D02*
X184642Y150537D01*
G01X184651Y150762D02*
X184647Y150733D01*
G01X186150Y136168D02*
X186151Y136570D01*
G01X186147Y135841D02*
X186150Y136168D01*
G01X186143Y135645D02*
X186147Y135841D01*
G01X186138Y135615D02*
X186143Y135645D01*
G01X149213Y134624D02*
X149214Y134627D01*
G01X149212Y134622D02*
X149213Y134624D01*
G01X149212Y134621D02*
Y134622D01*
G01X157087Y134624D02*
X157088Y134627D01*
G01X157086Y134622D02*
X157087Y134624D01*
G01X157086Y134621D02*
Y134622D01*
G01X174332Y151754D02*
Y151750D01*
G01X174333Y151756D02*
X174332Y151754D01*
G01X182206D02*
Y151750D01*
G01X182207Y151756D02*
X182206Y151754D01*
G01X172835Y134624D02*
X172836Y134627D01*
G01X172834Y134622D02*
X172835Y134624D01*
G01X172834Y134621D02*
Y134622D01*
G01X180709Y134624D02*
X180710Y134627D01*
G01X180708Y134622D02*
X180709Y134624D01*
G01X180708Y134621D02*
Y134622D01*
G01X127088Y135610D02*
Y135617D01*
G01X127089Y135606D02*
X127088Y135610D01*
G01X127089Y135605D02*
Y135606D01*
G01X125591Y150768D02*
X125592Y150760D01*
G01X125590Y150771D02*
X125591Y150768D01*
G01X125590Y150772D02*
Y150771D01*
G01X134962Y135610D02*
Y135617D01*
G01X134963Y135606D02*
X134962Y135610D01*
G01X134963Y135605D02*
Y135606D01*
G01X133465Y150768D02*
X133466Y150760D01*
G01X133464Y150771D02*
X133465Y150768D01*
G01X133464Y150772D02*
Y150771D01*
G01X142836Y135610D02*
Y135617D01*
G01X142837Y135606D02*
X142836Y135610D01*
G01X142837Y135605D02*
Y135606D01*
G01X150711Y134622D02*
Y134621D01*
G01X150710Y134624D02*
X150711Y134622D01*
G01X150710Y134627D02*
Y134624D01*
G01X149213Y151754D02*
X149212Y151756D01*
G01X149214Y151750D02*
X149213Y151754D01*
G01X158585Y134622D02*
Y134621D01*
G01X158584Y134624D02*
X158585Y134622D01*
G01X158584Y134627D02*
Y134624D01*
G01X157087Y151754D02*
X157086Y151756D01*
G01X157088Y151750D02*
X157087Y151754D01*
G01X180698Y136197D02*
X180697Y136570D01*
G01X180700Y135887D02*
X180698Y136197D01*
G01X180704Y135680D02*
X180700Y135887D01*
G01X180708Y135605D02*
X180704Y135680D01*
G01X182217Y150180D02*
X182218Y149807D01*
G01X182215Y150490D02*
X182217Y150180D01*
G01X182212Y150698D02*
X182215Y150490D01*
G01X182207Y150772D02*
X182212Y150698D01*
G01X182475Y133893D02*
X182481Y133840D01*
G01X182469Y134024D02*
X182475Y133893D01*
G01X182463Y134231D02*
X182469Y134024D01*
G01X184382Y152484D02*
X184376Y152538D01*
G01X184388Y152353D02*
X184382Y152484D01*
G01X184394Y152147D02*
X184388Y152353D01*
G01X186407Y133893D02*
X186414Y133840D01*
G01X186401Y134024D02*
X186407Y133893D01*
G01X186396Y134231D02*
X186401Y134024D01*
G01X182477Y134866D02*
X182481Y134824D01*
G01X182472Y134965D02*
X182477Y134866D01*
G01X182468Y135117D02*
X182472Y134965D01*
G01X184380Y151511D02*
X184376Y151553D01*
G01X184385Y151413D02*
X184380Y151511D01*
G01X184389Y151260D02*
X184385Y151413D01*
G01X186409Y134866D02*
X186414Y134824D01*
G01X186405Y134965D02*
X186409Y134866D01*
G01X186400Y135117D02*
X186405Y134965D01*
G01X184637Y135645D02*
X184642Y135615D01*
G01X184633Y135841D02*
X184637Y135645D01*
G01X184630Y136168D02*
X184633Y135841D01*
G01X184629Y136570D02*
X184630Y136168D01*
G01X186152Y150733D02*
X186148Y150762D01*
G01X186156Y150537D02*
X186152Y150733D01*
G01X186159Y150209D02*
X186156Y150537D01*
G01X186160Y149807D02*
X186159Y150209D01*
G01X170745Y146142D02*
X171123Y146314D01*
G01X170377Y145965D02*
X170745Y146142D01*
G01X170021Y145782D02*
X170377Y145965D01*
G01X141339Y150768D02*
X141340Y150760D01*
G01X141338Y150771D02*
X141339Y150768D01*
G01X141338Y150772D02*
Y150771D01*
G01X150710Y135610D02*
Y135617D01*
G01X150711Y135606D02*
X150710Y135610D01*
G01X150711Y135605D02*
Y135606D01*
G01X149213Y150768D02*
X149214Y150760D01*
G01X149212Y150771D02*
X149213Y150768D01*
G01X149212Y150772D02*
Y150771D01*
G01X158584Y135610D02*
Y135617D01*
G01X158585Y135606D02*
X158584Y135610D01*
G01X158585Y135605D02*
Y135606D01*
G01X157087Y150768D02*
X157088Y150760D01*
G01X157086Y150771D02*
X157087Y150768D01*
G01X157086Y150772D02*
Y150771D01*
G01X174333Y134622D02*
Y134621D01*
G01X174332Y134624D02*
X174333Y134622D01*
G01X174332Y134627D02*
Y134624D01*
G01X172835Y151754D02*
X172834Y151756D01*
G01X172836Y151750D02*
X172835Y151754D01*
G01X182207Y134622D02*
Y134621D01*
G01X182206Y134624D02*
X182207Y134622D01*
G01X182206Y134627D02*
Y134624D01*
G01X180709Y151754D02*
X180708Y151756D01*
G01X180710Y151750D02*
X180709Y151754D01*
G01X174332Y135610D02*
Y135617D01*
G01X174333Y135606D02*
X174332Y135610D01*
G01X174333Y135605D02*
Y135606D01*
G01X172835Y150768D02*
X172836Y150760D01*
G01X172834Y150771D02*
X172835Y150768D01*
G01X172834Y150772D02*
Y150771D01*
G01X182206Y135610D02*
Y135617D01*
G01X182207Y135606D02*
X182206Y135610D01*
G01X182207Y135605D02*
Y135606D01*
G01X180709Y150768D02*
X180710Y150760D01*
G01X180708Y150771D02*
X180709Y150768D01*
G01X180708Y150772D02*
Y150771D01*
G01X167458Y136714D02*
X167678Y136693D01*
G01X167235Y136770D02*
X167458Y136714D01*
G01X167015Y136864D02*
X167235Y136770D01*
G01X166801Y136998D02*
X167015Y136864D01*
G01X166600Y137176D02*
X166801Y136998D01*
G01X166421Y137402D02*
X166600Y137176D01*
G01X167898Y149663D02*
X167678Y149684D01*
G01X168121Y149607D02*
X167898Y149663D01*
G01X168341Y149514D02*
X168121Y149607D01*
G01X168555Y149379D02*
X168341Y149514D01*
G01X168756Y149201D02*
X168555Y149379D01*
G01X168936Y148975D02*
X168756Y149201D01*
G01X170745Y140235D02*
X171123Y140064D01*
G01X170377Y140412D02*
X170745Y140235D01*
G01X170021Y140595D02*
X170377Y140412D01*
G01X123437Y133839D02*
X123421Y133840D01*
G01X123451Y133838D02*
X123437Y133839D01*
G01X123467Y133838D02*
X123451D01*
G01X127378Y133839D02*
X127363Y133840D01*
G01X127393Y133838D02*
X127378Y133839D01*
G01X127408Y133838D02*
X127393D01*
G01X131311Y133839D02*
X131296Y133840D01*
G01X131326Y133838D02*
X131311Y133839D01*
G01X131341Y133838D02*
X131326D01*
G01X135252Y133839D02*
X135237Y133840D01*
G01X135267Y133838D02*
X135252Y133839D01*
G01X135282Y133838D02*
X135267D01*
G01X139185Y133839D02*
X139170Y133840D01*
G01X139200Y133838D02*
X139185Y133839D01*
G01X139215Y133838D02*
X139200D01*
G01X143126Y133839D02*
X143111Y133840D01*
G01X143141Y133838D02*
X143126Y133839D01*
G01X143156Y133838D02*
X143141D01*
G01X147059Y133839D02*
X147044Y133840D01*
G01X147074Y133838D02*
X147059Y133839D01*
G01X147089Y133838D02*
X147074D01*
G01X151000Y133839D02*
X150985Y133840D01*
G01X151015Y133838D02*
X151000Y133839D01*
G01X151030Y133838D02*
X151015D01*
G01X154933Y133839D02*
X154918Y133840D01*
G01X154948Y133838D02*
X154933Y133839D01*
G01X154963Y133838D02*
X154948D01*
G01X158874Y133839D02*
X158859Y133840D01*
G01X158889Y133838D02*
X158874Y133839D01*
G01X158904Y133838D02*
X158889D01*
G01X162807Y133839D02*
X162792Y133840D01*
G01X162822Y133838D02*
X162807Y133839D01*
G01X162837Y133838D02*
X162822D01*
G01X174622Y133839D02*
X174607Y133840D01*
G01X174637Y133838D02*
X174622Y133839D01*
G01X174652Y133838D02*
X174637D01*
G01X178555Y133839D02*
X178540Y133840D01*
G01X178570Y133838D02*
X178555Y133839D01*
G01X178585Y133838D02*
X178570D01*
G01X182496Y133839D02*
X182481Y133840D01*
G01X182511Y133838D02*
X182496Y133839D01*
G01X182526Y133838D02*
X182511D01*
G01X186429Y133839D02*
X186414Y133840D01*
G01X186444Y133838D02*
X186429Y133839D01*
G01X186459Y133838D02*
X186444D01*
G01X123437Y134823D02*
X123421Y134824D01*
G01X123451Y134823D02*
X123437D01*
G01X123467Y134822D02*
X123451Y134823D01*
G01X127378D02*
X127363Y134824D01*
G01X127393Y134823D02*
X127378D01*
G01X127408Y134822D02*
X127393Y134823D01*
G01X135252D02*
X135237Y134824D01*
G01X135267Y134823D02*
X135252D01*
G01X135282Y134822D02*
X135267Y134823D01*
G01X143126D02*
X143111Y134824D01*
G01X143141Y134823D02*
X143126D01*
G01X143156Y134822D02*
X143141Y134823D01*
G01X147059D02*
X147044Y134824D01*
G01X147074Y134823D02*
X147059D01*
G01X147089Y134822D02*
X147074Y134823D01*
G01X151000D02*
X150985Y134824D01*
G01X151015Y134823D02*
X151000D01*
G01X151030Y134822D02*
X151015Y134823D01*
G01X154933D02*
X154918Y134824D01*
G01X154948Y134823D02*
X154933D01*
G01X154963Y134822D02*
X154948Y134823D01*
G01X158874D02*
X158859Y134824D01*
G01X158889Y134823D02*
X158874D01*
G01X158904Y134822D02*
X158889Y134823D01*
G01X162807D02*
X162792Y134824D01*
G01X162822Y134823D02*
X162807D01*
G01X162837Y134822D02*
X162822Y134823D01*
G01X174622D02*
X174607Y134824D01*
G01X174637Y134823D02*
X174622D01*
G01X174652Y134822D02*
X174637Y134823D01*
G01X182496D02*
X182481Y134824D01*
G01X182511Y134823D02*
X182496D01*
G01X182526Y134822D02*
X182511Y134823D01*
G01X131326D02*
X131341Y134822D01*
G01X131311Y134823D02*
X131326D01*
G01X131296Y134824D02*
X131311Y134823D01*
G01X139200D02*
X139215Y134822D01*
G01X139185Y134823D02*
X139200D01*
G01X139170Y134824D02*
X139185Y134823D01*
G01X178570D02*
X178585Y134822D01*
G01X178555Y134823D02*
X178570D01*
G01X178540Y134824D02*
X178555Y134823D01*
G01X186444D02*
X186459Y134822D01*
G01X186429Y134823D02*
X186444D01*
G01X186414Y134824D02*
X186429Y134823D01*
G01X168756Y137176D02*
X168936Y137402D01*
G01X168556Y136998D02*
X168756Y137176D01*
G01X168342Y136864D02*
X168556Y136998D01*
G01X168122Y136770D02*
X168342Y136864D01*
G01X167899Y136714D02*
X168122Y136770D01*
G01X167678Y136693D02*
X167899Y136714D01*
G01X180404Y134823D02*
X180389Y134822D01*
G01X180419Y134823D02*
X180404D01*
G01X180434Y134824D02*
X180419Y134823D01*
G01X172530D02*
X172515Y134822D01*
G01X172545Y134823D02*
X172530D01*
G01X172560Y134824D02*
X172545Y134823D01*
G01X156782D02*
X156767Y134822D01*
G01X156797Y134823D02*
X156782D01*
G01X156812Y134824D02*
X156797Y134823D01*
G01X148908D02*
X148893Y134822D01*
G01X148923Y134823D02*
X148908D01*
G01X148938Y134824D02*
X148923Y134823D01*
G01X141034D02*
X141019Y134822D01*
G01X141049Y134823D02*
X141034D01*
G01X141064Y134824D02*
X141049Y134823D01*
G01X133160D02*
X133145Y134822D01*
G01X133175Y134823D02*
X133160D01*
G01X133190Y134824D02*
X133175Y134823D01*
G01X125286D02*
X125271Y134822D01*
G01X125301Y134823D02*
X125286D01*
G01X125316Y134824D02*
X125301Y134823D01*
G01X186453Y151555D02*
X186468D01*
G01X186438Y151554D02*
X186453Y151555D01*
G01X186423Y151553D02*
X186438Y151554D01*
G01X182511Y151555D02*
X182526D01*
G01X182496Y151554D02*
X182511Y151555D01*
G01X182481Y151553D02*
X182496Y151554D01*
G01X178579Y151555D02*
X178594D01*
G01X178564Y151554D02*
X178579Y151555D01*
G01X178549Y151553D02*
X178564Y151554D01*
G01X174637Y151555D02*
X174652D01*
G01X174622Y151554D02*
X174637Y151555D01*
G01X174607Y151553D02*
X174622Y151554D01*
G01X184336Y133838D02*
X184321D01*
G01X184351Y133839D02*
X184336Y133838D01*
G01X184366Y133840D02*
X184351Y133839D01*
G01X176462Y133838D02*
X176447D01*
G01X176477Y133839D02*
X176462Y133838D01*
G01X176492Y133840D02*
X176477Y133839D01*
G01X160714Y133838D02*
X160699D01*
G01X160729Y133839D02*
X160714Y133838D01*
G01X160744Y133840D02*
X160729Y133839D01*
G01X152840Y133838D02*
X152825D01*
G01X152855Y133839D02*
X152840Y133838D01*
G01X152870Y133840D02*
X152855Y133839D01*
G01X144966Y133838D02*
X144951D01*
G01X144981Y133839D02*
X144966Y133838D01*
G01X144996Y133840D02*
X144981Y133839D01*
G01X137092Y133838D02*
X137077D01*
G01X137107Y133839D02*
X137092Y133838D01*
G01X137122Y133840D02*
X137107Y133839D01*
G01X129218Y133838D02*
X129203D01*
G01X129233Y133839D02*
X129218Y133838D01*
G01X129248Y133840D02*
X129233Y133839D01*
G01X121344Y133838D02*
X121329D01*
G01X121359Y133839D02*
X121344Y133838D01*
G01X121374Y133840D02*
X121359Y133839D01*
G01X178579Y152539D02*
X178594D01*
G01X178564Y152538D02*
X178579Y152539D01*
G01X178549Y152538D02*
X178564D01*
G01X162831Y152539D02*
X162846D01*
G01X162816Y152538D02*
X162831Y152539D01*
G01X162801Y152538D02*
X162816D01*
G01X154957Y152539D02*
X154972D01*
G01X154942Y152538D02*
X154957Y152539D01*
G01X154927Y152538D02*
X154942D01*
G01X147083Y152539D02*
X147098D01*
G01X147068Y152538D02*
X147083Y152539D01*
G01X147053Y152538D02*
X147068D01*
G01X121369D02*
X121384D01*
G01X121354Y152539D02*
X121369Y152538D01*
G01X121339Y152539D02*
X121354D01*
G01X125301Y152538D02*
X125316D01*
G01X125286Y152539D02*
X125301Y152538D01*
G01X125271Y152539D02*
X125286D01*
G01X129243Y152538D02*
X129258D01*
G01X129228Y152539D02*
X129243Y152538D01*
G01X129213Y152539D02*
X129228D01*
G01X133175Y152538D02*
X133190D01*
G01X133160Y152539D02*
X133175Y152538D01*
G01X133145Y152539D02*
X133160D01*
G01X137117Y152538D02*
X137132D01*
G01X137102Y152539D02*
X137117Y152538D01*
G01X137087Y152539D02*
X137102D01*
G01X141049Y152538D02*
X141064D01*
G01X141034Y152539D02*
X141049Y152538D01*
G01X141019Y152539D02*
X141034D01*
G01X144991Y152538D02*
X145006D01*
G01X144976Y152539D02*
X144991Y152538D01*
G01X144961Y152539D02*
X144976D01*
G01X148923Y152538D02*
X148938D01*
G01X148908Y152539D02*
X148923Y152538D01*
G01X148893Y152539D02*
X148908D01*
G01X152865Y152538D02*
X152880D01*
G01X152850Y152539D02*
X152865Y152538D01*
G01X152835Y152539D02*
X152850D01*
G01X156797Y152538D02*
X156812D01*
G01X156782Y152539D02*
X156797Y152538D01*
G01X156767Y152539D02*
X156782D01*
G01X160739Y152538D02*
X160754D01*
G01X160724Y152539D02*
X160739Y152538D01*
G01X160709Y152539D02*
X160724D01*
G01X172545Y152538D02*
X172560D01*
G01X172530Y152539D02*
X172545Y152538D01*
G01X172515Y152539D02*
X172530D01*
G01X176487Y152538D02*
X176502D01*
G01X176472Y152539D02*
X176487Y152538D01*
G01X176457Y152539D02*
X176472D01*
G01X180419Y152538D02*
X180434D01*
G01X180404Y152539D02*
X180419Y152538D01*
G01X180389Y152539D02*
X180404D01*
G01X184361Y152538D02*
X184376D01*
G01X184346Y152539D02*
X184361Y152538D01*
G01X184331Y152539D02*
X184346D01*
G01X125301Y151554D02*
X125316Y151553D01*
G01X125286Y151555D02*
X125301Y151554D01*
G01X125271Y151555D02*
X125286D01*
G01X129243Y151554D02*
X129258Y151553D01*
G01X129228Y151555D02*
X129243Y151554D01*
G01X129213Y151555D02*
X129228D01*
G01X133175Y151554D02*
X133190Y151553D01*
G01X133160Y151555D02*
X133175Y151554D01*
G01X133145Y151555D02*
X133160D01*
G01X137117Y151554D02*
X137132Y151553D01*
G01X137102Y151555D02*
X137117Y151554D01*
G01X137087Y151555D02*
X137102D01*
G01X141049Y151554D02*
X141064Y151553D01*
G01X141034Y151555D02*
X141049Y151554D01*
G01X141019Y151555D02*
X141034D01*
G01X148923Y151554D02*
X148938Y151553D01*
G01X148908Y151555D02*
X148923Y151554D01*
G01X148893Y151555D02*
X148908D01*
G01X156797Y151554D02*
X156812Y151553D01*
G01X156782Y151555D02*
X156797Y151554D01*
G01X156767Y151555D02*
X156782D01*
G01X172545Y151554D02*
X172560Y151553D01*
G01X172530Y151555D02*
X172545Y151554D01*
G01X172515Y151555D02*
X172530D01*
G01X176487Y151554D02*
X176502Y151553D01*
G01X176472Y151555D02*
X176487Y151554D01*
G01X176457Y151555D02*
X176472D01*
G01X180419Y151554D02*
X180434Y151553D01*
G01X180404Y151555D02*
X180419Y151554D01*
G01X180389Y151555D02*
X180404D01*
G01X184361Y151554D02*
X184376Y151553D01*
G01X184346Y151555D02*
X184361Y151554D01*
G01X184331Y151555D02*
X184346D01*
G01X121354D02*
X121339D01*
G01X121369Y151554D02*
X121354Y151555D01*
G01X121384Y151553D02*
X121369Y151554D01*
G01X144976Y151555D02*
X144961D01*
G01X144991Y151554D02*
X144976Y151555D01*
G01X145006Y151553D02*
X144991Y151554D01*
G01X152850Y151555D02*
X152835D01*
G01X152865Y151554D02*
X152850Y151555D01*
G01X152880Y151553D02*
X152865Y151554D01*
G01X160724Y151555D02*
X160709D01*
G01X160739Y151554D02*
X160724Y151555D01*
G01X160754Y151553D02*
X160739Y151554D01*
G01X166600Y149201D02*
X166421Y148975D01*
G01X166801Y149379D02*
X166600Y149201D01*
G01X167015Y149514D02*
X166801Y149379D01*
G01X167235Y149607D02*
X167015Y149514D01*
G01X167458Y149663D02*
X167235Y149607D01*
G01X167678Y149684D02*
X167458Y149663D01*
G01X162831Y151555D02*
X162846D01*
G01X162816Y151554D02*
X162831Y151555D01*
G01X162801Y151553D02*
X162816Y151554D01*
G01X158889Y151555D02*
X158904D01*
G01X158874Y151554D02*
X158889Y151555D01*
G01X158859Y151553D02*
X158874Y151554D01*
G01X154957Y151555D02*
X154972D01*
G01X154942Y151554D02*
X154957Y151555D01*
G01X154927Y151553D02*
X154942Y151554D01*
G01X151015Y151555D02*
X151030D01*
G01X151000Y151554D02*
X151015Y151555D01*
G01X150985Y151553D02*
X151000Y151554D01*
G01X147083Y151555D02*
X147098D01*
G01X147068Y151554D02*
X147083Y151555D01*
G01X147053Y151553D02*
X147068Y151554D01*
G01X143141Y151555D02*
X143156D01*
G01X143126Y151554D02*
X143141Y151555D01*
G01X143111Y151553D02*
X143126Y151554D01*
G01X139209Y151555D02*
X139224D01*
G01X139194Y151554D02*
X139209Y151555D01*
G01X139179Y151553D02*
X139194Y151554D01*
G01X135267Y151555D02*
X135282D01*
G01X135252Y151554D02*
X135267Y151555D01*
G01X135237Y151553D02*
X135252Y151554D01*
G01X131335Y151555D02*
X131350D01*
G01X131320Y151554D02*
X131335Y151555D01*
G01X131305Y151553D02*
X131320Y151554D01*
G01X127393Y151555D02*
X127408D01*
G01X127378Y151554D02*
X127393Y151555D01*
G01X127363Y151553D02*
X127378Y151554D01*
G01X123461Y151555D02*
X123476D01*
G01X123446Y151554D02*
X123461Y151555D01*
G01X123431Y151553D02*
X123446Y151554D01*
G01X123461Y152539D02*
X123476D01*
G01X123446Y152538D02*
X123461Y152539D01*
G01X123431Y152538D02*
X123446D01*
G01X125670Y156434D02*
X125513Y156396D01*
G01X127166D02*
X127009Y156434D01*
G01X125670Y155412D02*
X125513Y155338D01*
G01X127166D02*
X127009Y155412D01*
G01X127408Y152539D02*
X127363Y152538D01*
G01X127088Y151750D02*
X127076Y151737D01*
G01X125603D02*
X125592Y151750D01*
G01X154725Y138680D02*
X154568Y138717D01*
G01X153229Y137696D02*
X153072Y137621D01*
G01X154725D02*
X154568Y137696D01*
G01X153229Y138717D02*
X153072Y138680D01*
G01X154630Y134640D02*
X154642Y134627D01*
G01X153146D02*
X153157Y134640D01*
G01X152825Y134822D02*
X152870Y134824D01*
G01X154568Y147660D02*
X154725Y147698D01*
G01X153072D02*
X153229Y147660D01*
G01X154568Y148681D02*
X154725Y148756D01*
G01X153072D02*
X153229Y148681D01*
G01X153167Y151737D02*
X153155Y151750D01*
G01X154651D02*
X154640Y151737D01*
G01X176851Y138717D02*
X176694Y138680D01*
G01X178347D02*
X178190Y138717D01*
G01X176851Y137696D02*
X176694Y137621D01*
G01X178347D02*
X178190Y137696D01*
G01X178252Y134640D02*
X178264Y134627D01*
G01X176768D02*
X176779Y134640D01*
G01X176447Y134822D02*
X176492Y134824D01*
G01X176789Y151737D02*
X176777Y151750D01*
G01X178273D02*
X178262Y151737D01*
G01X178190Y147660D02*
X178347Y147698D01*
G01X176694D02*
X176851Y147660D01*
G01X178190Y148681D02*
X178347Y148756D01*
G01X176694D02*
X176851Y148681D01*
G01X182127Y129943D02*
X182284Y129981D01*
G01X180631D02*
X180788Y129943D01*
G01X182127Y130965D02*
X182284Y131039D01*
G01X180631D02*
X180788Y130965D01*
G01X180389Y133838D02*
X180434Y133840D01*
G01X180710Y134627D02*
X180721Y134640D01*
G01X182194D02*
X182206Y134627D01*
G01X180788Y156434D02*
X180631Y156396D01*
G01X182284D02*
X182127Y156434D01*
G01X180788Y155412D02*
X180631Y155338D01*
G01X182284D02*
X182127Y155412D01*
G01X180721Y151737D02*
X180710Y151750D01*
G01X182206D02*
X182194Y151737D01*
G01X182526Y152539D02*
X182481Y152538D01*
G01X186221Y138680D02*
X186064Y138717D01*
G01X184725D02*
X184568Y138680D01*
G01X184725Y137696D02*
X184568Y137621D01*
G01X186221D02*
X186064Y137696D01*
G01X186126Y134640D02*
X186138Y134627D01*
G01X184642D02*
X184653Y134640D01*
G01X184321Y134822D02*
X184366Y134824D01*
G01X184568Y147698D02*
X184725Y147660D01*
G01X186064Y148681D02*
X186221Y148756D01*
G01X184568D02*
X184725Y148681D01*
G01X186064Y147660D02*
X186221Y147698D01*
G01X184663Y151737D02*
X184651Y151750D01*
G01X186147D02*
X186136Y151737D01*
G01X186468Y152539D02*
X186423Y152538D01*
G01X129450Y147698D02*
X129607Y147660D01*
G01X130946Y148681D02*
X131103Y148756D01*
G01X129450D02*
X129607Y148681D01*
G01X130946Y147660D02*
X131103Y147698D01*
G01X129545Y151737D02*
X129533Y151750D01*
G01X131029D02*
X131018Y151737D01*
G01X131350Y152539D02*
X131305Y152538D01*
G01X131008Y134640D02*
X131020Y134627D01*
G01X129524D02*
X129535Y134640D01*
G01X129203Y134822D02*
X129248Y134824D01*
G01X131103Y138680D02*
X130946Y138717D01*
G01X129607D02*
X129450Y138680D01*
G01X129607Y137696D02*
X129450Y137621D01*
G01X131103D02*
X130946Y137696D01*
G01X127009Y129943D02*
X127166Y129981D01*
G01X125513D02*
X125670Y129943D01*
G01X127009Y130965D02*
X127166Y131039D01*
G01X125513D02*
X125670Y130965D01*
G01X127076Y134640D02*
X127088Y134627D01*
G01X125592D02*
X125603Y134640D01*
G01X125271Y133838D02*
X125316Y133840D01*
G01X123072Y147660D02*
X123229Y147698D01*
G01X121576D02*
X121733Y147660D01*
G01X123072Y148681D02*
X123229Y148756D01*
G01X121576D02*
X121733Y148681D01*
G01X121671Y151737D02*
X121659Y151750D01*
G01X123155D02*
X123144Y151737D01*
G01X123134Y134640D02*
X123146Y134627D01*
G01X121650D02*
X121661Y134640D01*
G01X121329Y134822D02*
X121374Y134824D01*
G01X123229Y138680D02*
X123072Y138717D01*
G01X121733D02*
X121576Y138680D01*
G01X121733Y137696D02*
X121576Y137621D01*
G01X123229D02*
X123072Y137696D01*
G01X162442Y147660D02*
X162599Y147698D01*
G01X160946D02*
X161103Y147660D01*
G01X162442Y148681D02*
X162599Y148756D01*
G01X160946D02*
X161103Y148681D01*
G01X161041Y151737D02*
X161029Y151750D01*
G01X162525D02*
X162514Y151737D01*
G01X162504Y134640D02*
X162516Y134627D01*
G01X161020D02*
X161031Y134640D01*
G01X160699Y134822D02*
X160744Y134824D01*
G01X162599Y138680D02*
X162442Y138717D01*
G01X161103D02*
X160946Y138680D01*
G01X161103Y137696D02*
X160946Y137621D01*
G01X162599D02*
X162442Y137696D01*
G01X157166Y156434D02*
X157009Y156396D01*
G01X158662D02*
X158505Y156434D01*
G01X157166Y155412D02*
X157009Y155338D01*
G01X158662D02*
X158505Y155412D01*
G01X158904Y152539D02*
X158859Y152538D01*
G01X158584Y151750D02*
X158572Y151737D01*
G01X157099D02*
X157088Y151750D01*
G01X158505Y129943D02*
X158662Y129981D01*
G01X157009D02*
X157166Y129943D01*
G01X158505Y130965D02*
X158662Y131039D01*
G01X157009D02*
X157166Y130965D01*
G01X158572Y134640D02*
X158584Y134627D01*
G01X157088D02*
X157099Y134640D01*
G01X156767Y133838D02*
X156812Y133840D01*
G01X149292Y156434D02*
X149135Y156396D01*
G01X150788D02*
X150631Y156434D01*
G01X149292Y155412D02*
X149135Y155338D01*
G01X150788D02*
X150631Y155412D01*
G01X151030Y152539D02*
X150985Y152538D01*
G01X150710Y151750D02*
X150698Y151737D01*
G01X149225D02*
X149214Y151750D01*
G01X150631Y129943D02*
X150788Y129981D01*
G01X149135D02*
X149292Y129943D01*
G01X150631Y130965D02*
X150788Y131039D01*
G01X149135D02*
X149292Y130965D01*
G01X150698Y134640D02*
X150710Y134627D01*
G01X149214D02*
X149225Y134640D01*
G01X148893Y133838D02*
X148938Y133840D01*
G01X146694Y147660D02*
X146851Y147698D01*
G01X145198D02*
X145355Y147660D01*
G01X146694Y148681D02*
X146851Y148756D01*
G01X145198D02*
X145355Y148681D01*
G01X145293Y151737D02*
X145281Y151750D01*
G01X146777D02*
X146766Y151737D01*
G01X146756Y134640D02*
X146768Y134627D01*
G01X145272D02*
X145283Y134640D01*
G01X144951Y134822D02*
X144996Y134824D01*
G01X146851Y138680D02*
X146694Y138717D01*
G01X145355D02*
X145198Y138680D01*
G01X145355Y137696D02*
X145198Y137621D01*
G01X146851D02*
X146694Y137696D01*
G01X141418Y156434D02*
X141261Y156396D01*
G01X142914D02*
X142757Y156434D01*
G01X141418Y155412D02*
X141261Y155338D01*
G01X142914D02*
X142757Y155412D01*
G01X143156Y152539D02*
X143111Y152538D01*
G01X142836Y151750D02*
X142824Y151737D01*
G01X141351D02*
X141340Y151750D01*
G01X142757Y129943D02*
X142914Y129981D01*
G01X141261D02*
X141418Y129943D01*
G01X142757Y130965D02*
X142914Y131039D01*
G01X141261D02*
X141418Y130965D01*
G01X142824Y134640D02*
X142836Y134627D01*
G01X141340D02*
X141351Y134640D01*
G01X141019Y133838D02*
X141064Y133840D01*
G01X137324Y147698D02*
X137481Y147660D01*
G01X138820Y148681D02*
X138977Y148756D01*
G01X137324D02*
X137481Y148681D01*
G01X138820Y147660D02*
X138977Y147698D01*
G01X137419Y151737D02*
X137407Y151750D01*
G01X138903D02*
X138892Y151737D01*
G01X139224Y152539D02*
X139179Y152538D01*
G01X138882Y134640D02*
X138894Y134627D01*
G01X137398D02*
X137409Y134640D01*
G01X137077Y134822D02*
X137122Y134824D01*
G01X138977Y138680D02*
X138820Y138717D01*
G01X137481D02*
X137324Y138680D01*
G01X137481Y137696D02*
X137324Y137621D01*
G01X138977D02*
X138820Y137696D01*
G01X133544Y156434D02*
X133387Y156396D01*
G01X135040D02*
X134883Y156434D01*
G01X133544Y155412D02*
X133387Y155338D01*
G01X135040D02*
X134883Y155412D01*
G01X135282Y152539D02*
X135237Y152538D01*
G01X134962Y151750D02*
X134950Y151737D01*
G01X133477D02*
X133466Y151750D01*
G01X134883Y129943D02*
X135040Y129981D01*
G01X133387D02*
X133544Y129943D01*
G01X134883Y130965D02*
X135040Y131039D01*
G01X133387D02*
X133544Y130965D01*
G01X134950Y134640D02*
X134962Y134627D01*
G01X133466D02*
X133477Y134640D01*
G01X133145Y133838D02*
X133190Y133840D01*
G01X174253Y129943D02*
X174410Y129981D01*
G01X172757D02*
X172914Y129943D01*
G01X174253Y130965D02*
X174410Y131039D01*
G01X172757D02*
X172914Y130965D01*
G01X172515Y133838D02*
X172560Y133840D01*
G01X172836Y134627D02*
X172847Y134640D01*
G01X174320D02*
X174332Y134627D01*
G01X172914Y156434D02*
X172757Y156396D01*
G01X174410D02*
X174253Y156434D01*
G01X172914Y155412D02*
X172757Y155338D01*
G01X174410D02*
X174253Y155412D01*
G01X172847Y151737D02*
X172836Y151750D01*
G01X174332D02*
X174320Y151737D01*
G01X174652Y152539D02*
X174607Y152538D01*
G01X170021Y145782D02*
G03Y140595I-1752J-2593D01*
G01X171123Y146314D02*
G03Y140064I-2854J-3125D01*
G01X172895Y143189D02*
G03I-4626J0D01*
G01X115021Y163189D02*
X115513D01*
G01X111904D02*
X112560D01*
G01X115651Y123341D02*
X115240Y123257D01*
G01X110893Y122335D02*
X110483Y122252D01*
G01X111385Y119822D02*
X111796Y119906D01*
G01X116061Y120241D02*
X116471Y120325D01*
G01X110565Y121833D02*
X110893Y121917D01*
G01X111714Y120325D02*
X111385Y120241D01*
G01X116471Y119906D02*
X116143Y119822D01*
G01X112970Y160592D02*
X111494D01*
G01X113052Y160257D02*
X111412D01*
G01X111084Y159252D02*
X110592D01*
G01X113872D02*
X113380D01*
G01X115513D02*
X115021D01*
G01X460985Y157854D02*
X110592D01*
G01X123584Y156476D02*
X121221D01*
G01X127521D02*
X125158D01*
G01X131458D02*
X129095D01*
G01X135395D02*
X133032D01*
G01X139332D02*
X136969D01*
G01X143269D02*
X140906D01*
G01X147206D02*
X144843D01*
G01X151143D02*
X148780D01*
G01X155080D02*
X152717D01*
G01X159017D02*
X156655D01*
G01X162954D02*
X160592D01*
G01X174765D02*
X172403D01*
G01X178702D02*
X176340D01*
G01X182639D02*
X180277D01*
G01X186576D02*
X184214D01*
G01X127009Y155492D02*
X125670D01*
G01X134883D02*
X133544D01*
G01X142757D02*
X141418D01*
G01X150631D02*
X149292D01*
G01X158505D02*
X157166D01*
G01X170178D02*
X165178D01*
G01X174253D02*
X172914D01*
G01X182127D02*
X180788D01*
G01X180631Y155393D02*
X182284D01*
G01X172757D02*
X174410D01*
G01X157009D02*
X158662D01*
G01X149135D02*
X150788D01*
G01X141261D02*
X142914D01*
G01X133387D02*
X135040D01*
G01X125513D02*
X127166D01*
G01X116241Y155295D02*
X111517D01*
G01X123584D02*
X121221D01*
G01X127521D02*
X125158D01*
G01X131458D02*
X129095D01*
G01X135395D02*
X133032D01*
G01X139332D02*
X136969D01*
G01X143269D02*
X140906D01*
G01X147206D02*
X144843D01*
G01X151143D02*
X148780D01*
G01X155080D02*
X152717D01*
G01X159017D02*
X156655D01*
G01X162954D02*
X160592D01*
G01X174765D02*
X172403D01*
G01X178702D02*
X176340D01*
G01X182639D02*
X180277D01*
G01X186576D02*
X184214D01*
G01X127166Y154901D02*
X125513D01*
G01X135040D02*
X133387D01*
G01X142914D02*
X141261D01*
G01X150788D02*
X149135D01*
G01X158662D02*
X157009D01*
G01X174410D02*
X172757D01*
G01X182284D02*
X180631D01*
G01X117856Y154735D02*
X114270D01*
G01X123820Y154035D02*
X120985D01*
G01X127757D02*
X124922D01*
G01X131694D02*
X128859D01*
G01X135631D02*
X132796D01*
G01X139568D02*
X136733D01*
G01X143505D02*
X140670D01*
G01X147442D02*
X144607D01*
G01X151379D02*
X148544D01*
G01X155316D02*
X152481D01*
G01X159253D02*
X156418D01*
G01X163190D02*
X160355D01*
G01X175001D02*
X172166D01*
G01X178938D02*
X176103D01*
G01X182875D02*
X180040D01*
G01X186812D02*
X183977D01*
G01X127166Y153130D02*
X125513D01*
G01X135040D02*
X133387D01*
G01X142914D02*
X141261D01*
G01X150788D02*
X149135D01*
G01X158662D02*
X157009D01*
G01X174410D02*
X172757D01*
G01X182284D02*
X180631D01*
G01Y152637D02*
X182284D01*
G01X172757D02*
X174410D01*
G01X157009D02*
X158662D01*
G01X149135D02*
X150788D01*
G01X141261D02*
X142914D01*
G01X133387D02*
X135040D01*
G01X125513D02*
X127166D01*
G01X123820Y152539D02*
X120985D01*
G01X127757D02*
X124922D01*
G01X131694D02*
X128859D01*
G01X135631D02*
X132796D01*
G01X139568D02*
X136733D01*
G01X143505D02*
X140670D01*
G01X147442D02*
X144607D01*
G01X151379D02*
X148544D01*
G01X155316D02*
X152481D01*
G01X159253D02*
X156418D01*
G01X163190D02*
X160355D01*
G01X175001D02*
X172166D01*
G01X178938D02*
X176103D01*
G01X182875D02*
X180040D01*
G01X186812D02*
X183977D01*
G01X186221Y152382D02*
X186812D01*
G01X183977D02*
X184568D01*
G01X182284D02*
X182875D01*
G01X180040D02*
X180631D01*
G01X178347D02*
X178938D01*
G01X176103D02*
X176694D01*
G01X174410D02*
X175001D01*
G01X172166D02*
X172757D01*
G01X162599D02*
X163190D01*
G01X160355D02*
X160946D01*
G01X158662D02*
X159253D01*
G01X156418D02*
X157009D01*
G01X154725D02*
X155316D01*
G01X152481D02*
X153072D01*
G01X150788D02*
X151379D01*
G01X148544D02*
X149135D01*
G01X146851D02*
X147442D01*
G01X144607D02*
X145198D01*
G01X142914D02*
X143505D01*
G01X140670D02*
X141261D01*
G01X138977D02*
X139568D01*
G01X136733D02*
X137324D01*
G01X135040D02*
X135631D01*
G01X132796D02*
X133387D01*
G01X131103D02*
X131694D01*
G01X128859D02*
X129450D01*
G01X127166D02*
X127757D01*
G01X124922D02*
X125513D01*
G01X123229D02*
X123820D01*
G01X120985D02*
X121576D01*
G01X184394Y152147D02*
X186405D01*
G01X180452D02*
X182463D01*
G01X176520D02*
X178531D01*
G01X172578D02*
X174589D01*
G01X160772D02*
X162783D01*
G01X156830D02*
X158841D01*
G01X152898D02*
X154909D01*
G01X148956D02*
X150967D01*
G01X145024D02*
X147035D01*
G01X141082D02*
X143093D01*
G01X137150D02*
X139161D01*
G01X133208D02*
X135219D01*
G01X129276D02*
X131287D01*
G01X125334D02*
X127345D01*
G01X121402D02*
X123413D01*
G01X123157Y151756D02*
X121657D01*
G01X127089D02*
X125590D01*
G01X131031D02*
X129531D01*
G01X134963D02*
X133464D01*
G01X138905D02*
X137406D01*
G01X142837D02*
X141338D01*
G01X146779D02*
X145280D01*
G01X150711D02*
X149212D01*
G01X154653D02*
X153154D01*
G01X158585D02*
X157086D01*
G01X162527D02*
X161028D01*
G01X174333D02*
X172834D01*
G01X178275D02*
X176776D01*
G01X182207D02*
X180708D01*
G01X186149D02*
X184650D01*
G01X184663Y151737D02*
X186136D01*
G01X180721D02*
X182194D01*
G01X176789D02*
X178262D01*
G01X172847D02*
X174320D01*
G01X161041D02*
X162514D01*
G01X157099D02*
X158572D01*
G01X153167D02*
X154640D01*
G01X149225D02*
X150698D01*
G01X145293D02*
X146766D01*
G01X141351D02*
X142824D01*
G01X137419D02*
X138892D01*
G01X133477D02*
X134950D01*
G01X129545D02*
X131018D01*
G01X125603D02*
X127076D01*
G01X121671D02*
X123144D01*
G01X121576Y151712D02*
X120985D01*
G01X123820D02*
X123229D01*
G01X125513D02*
X124922D01*
G01X127757D02*
X127166D01*
G01X129450D02*
X128859D01*
G01X131694D02*
X131103D01*
G01X133387D02*
X132796D01*
G01X135631D02*
X135040D01*
G01X137324D02*
X136733D01*
G01X139568D02*
X138977D01*
G01X141261D02*
X140670D01*
G01X143505D02*
X142914D01*
G01X145198D02*
X144607D01*
G01X147442D02*
X146851D01*
G01X149135D02*
X148544D01*
G01X151379D02*
X150788D01*
G01X153072D02*
X152481D01*
G01X155316D02*
X154725D01*
G01X157009D02*
X156418D01*
G01X159253D02*
X158662D01*
G01X160946D02*
X160355D01*
G01X163190D02*
X162599D01*
G01X172757D02*
X172166D01*
G01X175001D02*
X174410D01*
G01X176694D02*
X176103D01*
G01X178938D02*
X178347D01*
G01X180631D02*
X180040D01*
G01X182875D02*
X182284D01*
G01X184568D02*
X183977D01*
G01X186812D02*
X186221D01*
G01X183977Y151555D02*
X186812D01*
G01X180040D02*
X182875D01*
G01X176103D02*
X178938D01*
G01X172166D02*
X175001D01*
G01X156418D02*
X159253D01*
G01X148544D02*
X151379D01*
G01X144607D02*
X147442D01*
G01X140670D02*
X143505D01*
G01X136733D02*
X139568D01*
G01X132796D02*
X135631D01*
G01X128859D02*
X131694D01*
G01X124922D02*
X127757D01*
G01X123820D02*
X120985D01*
G01X155316D02*
X152481D01*
G01X163190D02*
X160355D01*
G01X123229Y151456D02*
X121576D01*
G01X131103D02*
X129450D01*
G01X138977D02*
X137324D01*
G01X146851D02*
X145198D01*
G01X154725D02*
X153072D01*
G01X162599D02*
X160946D01*
G01X178347D02*
X176694D01*
G01X186221D02*
X184568D01*
G01X122890Y151368D02*
X121925D01*
G01X126822D02*
X125857D01*
G01X130764D02*
X129799D01*
G01X134696D02*
X133731D01*
G01X138638D02*
X137673D01*
G01X142570D02*
X141605D01*
G01X146512D02*
X145547D01*
G01X150444D02*
X149479D01*
G01X154386D02*
X153421D01*
G01X158318D02*
X157353D01*
G01X162260D02*
X161295D01*
G01X174066D02*
X173101D01*
G01X178008D02*
X177043D01*
G01X181940D02*
X180975D01*
G01X185882D02*
X184917D01*
G01X183977Y151358D02*
X184292D01*
G01X176103D02*
X176418D01*
G01X160355D02*
X160670D01*
G01X152481D02*
X152796D01*
G01X144607D02*
X144922D01*
G01X136733D02*
X137048D01*
G01X128859D02*
X129174D01*
G01X120985D02*
X121300D01*
G01X123820D02*
X123505D01*
G01X125237D02*
X124922D01*
G01X127757D02*
X127442D01*
G01X131694D02*
X131379D01*
G01X133111D02*
X132796D01*
G01X135631D02*
X135316D01*
G01X139568D02*
X139253D01*
G01X140985D02*
X140670D01*
G01X143505D02*
X143190D01*
G01X147442D02*
X147127D01*
G01X148859D02*
X148544D01*
G01X151379D02*
X151064D01*
G01X155316D02*
X155001D01*
G01X156733D02*
X156418D01*
G01X159253D02*
X158938D01*
G01X163190D02*
X162875D01*
G01X172481D02*
X172166D01*
G01X175001D02*
X174686D01*
G01X178938D02*
X178623D01*
G01X180355D02*
X180040D01*
G01X182875D02*
X182560D01*
G01X186812D02*
X186497D01*
G01X123418Y151260D02*
X121397D01*
G01X127350D02*
X125329D01*
G01X131292D02*
X129271D01*
G01X135224D02*
X133203D01*
G01X139166D02*
X137145D01*
G01X143098D02*
X141077D01*
G01X147040D02*
X145019D01*
G01X150972D02*
X148951D01*
G01X154914D02*
X152893D01*
G01X158846D02*
X156825D01*
G01X162788D02*
X160767D01*
G01X174594D02*
X172573D01*
G01X178536D02*
X176515D01*
G01X182468D02*
X180447D01*
G01X186410D02*
X184389D01*
G01X184568Y150964D02*
X186221D01*
G01X176694D02*
X178347D01*
G01X160946D02*
X162599D01*
G01X153072D02*
X154725D01*
G01X145198D02*
X146851D01*
G01X137324D02*
X138977D01*
G01X129450D02*
X131103D01*
G01X121576D02*
X123229D01*
G01X123157Y150772D02*
X121657D01*
G01X127089D02*
X125590D01*
G01X131031D02*
X129531D01*
G01X134963D02*
X133464D01*
G01X138905D02*
X137406D01*
G01X142837D02*
X141338D01*
G01X146779D02*
X145280D01*
G01X150711D02*
X149212D01*
G01X154653D02*
X153154D01*
G01X158585D02*
X157086D01*
G01X162527D02*
X161028D01*
G01X174333D02*
X172834D01*
G01X178275D02*
X176776D01*
G01X182207D02*
X180708D01*
G01X186149D02*
X184650D01*
G01X165178Y150767D02*
X170178D01*
G01X123155Y150762D02*
X121659D01*
G01X127088D02*
X125591D01*
G01X131029D02*
X129533D01*
G01X134962D02*
X133465D01*
G01X138903D02*
X137407D01*
G01X142836D02*
X141339D01*
G01X146777D02*
X145281D01*
G01X150710D02*
X149213D01*
G01X154651D02*
X153155D01*
G01X158584D02*
X157087D01*
G01X162525D02*
X161029D01*
G01X174332D02*
X172835D01*
G01X178274D02*
X176777D01*
G01X182206D02*
X180709D01*
G01X186148D02*
X184651D01*
G01X184871Y150441D02*
X185928D01*
G01X180929D02*
X181986D01*
G01X176997D02*
X178054D01*
G01X173055D02*
X174112D01*
G01X161249D02*
X162306D01*
G01X157307D02*
X158364D01*
G01X153375D02*
X154432D01*
G01X149433D02*
X150490D01*
G01X145501D02*
X146558D01*
G01X141559D02*
X142616D01*
G01X137627D02*
X138684D01*
G01X133685D02*
X134742D01*
G01X129753D02*
X130810D01*
G01X125811D02*
X126868D01*
G01X121879D02*
X122935D01*
G01X184214Y150393D02*
X186576D01*
G01X180277D02*
X182639D01*
G01X176340D02*
X178702D01*
G01X172403D02*
X174765D01*
G01X160592D02*
X162954D01*
G01X156655D02*
X159017D01*
G01X152717D02*
X155080D01*
G01X148780D02*
X151143D01*
G01X144843D02*
X147206D01*
G01X140906D02*
X143269D01*
G01X136969D02*
X139332D01*
G01X133032D02*
X135395D01*
G01X129095D02*
X131458D01*
G01X125158D02*
X127521D01*
G01X121221D02*
X123584D01*
G01X186497Y149862D02*
X186812D01*
G01X183977D02*
X184292D01*
G01X182560D02*
X182875D01*
G01X180040D02*
X180355D01*
G01X178623D02*
X178938D01*
G01X176103D02*
X176418D01*
G01X174686D02*
X175001D01*
G01X172166D02*
X172481D01*
G01X162875D02*
X163190D01*
G01X160355D02*
X160670D01*
G01X158938D02*
X159253D01*
G01X155001D02*
X155316D01*
G01X156418D02*
X156733D01*
G01X152481D02*
X152796D01*
G01X151064D02*
X151379D01*
G01X148544D02*
X148859D01*
G01X147127D02*
X147442D01*
G01X144607D02*
X144922D01*
G01X143190D02*
X143505D01*
G01X140670D02*
X140985D01*
G01X139253D02*
X139568D01*
G01X136733D02*
X137048D01*
G01X135316D02*
X135631D01*
G01X132796D02*
X133111D01*
G01X131379D02*
X131694D01*
G01X128859D02*
X129174D01*
G01X127442D02*
X127757D01*
G01X124922D02*
X125237D01*
G01X123505D02*
X123820D01*
G01X120985D02*
X121300D01*
G01X184628Y149826D02*
X186171D01*
G01X180686D02*
X182229D01*
G01X176754D02*
X178297D01*
G01X172812D02*
X174355D01*
G01X161006D02*
X162549D01*
G01X157064D02*
X158607D01*
G01X153132D02*
X154675D01*
G01X149190D02*
X150733D01*
G01X145258D02*
X146801D01*
G01X141316D02*
X142859D01*
G01X137384D02*
X138927D01*
G01X133442D02*
X134985D01*
G01X129510D02*
X131053D01*
G01X125568D02*
X127111D01*
G01X121636D02*
X123179D01*
G01X184639Y149807D02*
X186160D01*
G01X180697D02*
X182218D01*
G01X176765D02*
X178286D01*
G01X172823D02*
X174344D01*
G01X161017D02*
X162538D01*
G01X157075D02*
X158596D01*
G01X153143D02*
X154664D01*
G01X149201D02*
X150722D01*
G01X145269D02*
X146790D01*
G01X141327D02*
X142848D01*
G01X137395D02*
X138916D01*
G01X133453D02*
X134974D01*
G01X129521D02*
X131042D01*
G01X125579D02*
X127100D01*
G01X121647D02*
X123168D01*
G01X456576Y149685D02*
X115001D01*
G01X116241Y149389D02*
X111517D01*
G01X184568Y149193D02*
X186221D01*
G01X176694D02*
X178347D01*
G01X160946D02*
X162599D01*
G01X153072D02*
X154725D01*
G01X145198D02*
X146851D01*
G01X137324D02*
X138977D01*
G01X129450D02*
X131103D01*
G01X121576D02*
X123229D01*
G01Y148700D02*
X121576D01*
G01X131103D02*
X129450D01*
G01X138977D02*
X137324D01*
G01X146851D02*
X145198D01*
G01X154725D02*
X153072D01*
G01X162599D02*
X160946D01*
G01X178347D02*
X176694D01*
G01X186221D02*
X184568D01*
G01X123072Y148602D02*
X121733D01*
G01X130946D02*
X129607D01*
G01X138820D02*
X137481D01*
G01X146694D02*
X145355D01*
G01X154568D02*
X153229D01*
G01X162442D02*
X161103D01*
G01X178190D02*
X176851D01*
G01X186064D02*
X184725D01*
G01Y147618D02*
X186064D01*
G01X176851D02*
X178190D01*
G01X161103D02*
X162442D01*
G01X153229D02*
X154568D01*
G01X145355D02*
X146694D01*
G01X137481D02*
X138820D01*
G01X129607D02*
X130946D01*
G01X121733D02*
X123072D01*
G01X116497Y147126D02*
X112560D01*
G01X123205Y146999D02*
X121610D01*
G01X127137D02*
X125542D01*
G01X131079D02*
X129484D01*
G01X135011D02*
X133416D01*
G01X138953D02*
X137358D01*
G01X142885D02*
X141290D01*
G01X146827D02*
X145232D01*
G01X150759D02*
X149164D01*
G01X154701D02*
X153106D01*
G01X158633D02*
X157038D01*
G01X162575D02*
X160980D01*
G01X174381D02*
X172786D01*
G01X178323D02*
X176728D01*
G01X182255D02*
X180660D01*
G01X186197D02*
X184602D01*
G01X123505Y146889D02*
X121300D01*
G01X127442D02*
X125237D01*
G01X131379D02*
X129174D01*
G01X135316D02*
X133111D01*
G01X139253D02*
X137048D01*
G01X143190D02*
X140985D01*
G01X147127D02*
X144922D01*
G01X151064D02*
X148859D01*
G01X155001D02*
X152796D01*
G01X158938D02*
X156733D01*
G01X162875D02*
X160670D01*
G01X174686D02*
X172481D01*
G01X178623D02*
X176418D01*
G01X182560D02*
X180355D01*
G01X186497D02*
X184292D01*
G01X164933Y146732D02*
X116958D01*
G01X454618D02*
X170423D01*
G01X123277Y146239D02*
X121538D01*
G01X127209D02*
X125470D01*
G01X131151D02*
X129412D01*
G01X135083D02*
X133344D01*
G01X139025D02*
X137286D01*
G01X142957D02*
X141218D01*
G01X146899D02*
X145160D01*
G01X150831D02*
X149092D01*
G01X154773D02*
X153034D01*
G01X158705D02*
X156966D01*
G01X162647D02*
X160908D01*
G01X174453D02*
X172714D01*
G01X178395D02*
X176656D01*
G01X182327D02*
X180588D01*
G01X186269D02*
X184530D01*
G01X184604Y146037D02*
X186195D01*
G01X180662D02*
X182253D01*
G01X176730D02*
X178321D01*
G01X172788D02*
X174379D01*
G01X160982D02*
X162573D01*
G01X157040D02*
X158631D01*
G01X153108D02*
X154699D01*
G01X149166D02*
X150757D01*
G01X145234D02*
X146825D01*
G01X141292D02*
X142883D01*
G01X137360D02*
X138950D01*
G01X133418D02*
X135009D01*
G01X129486D02*
X131076D01*
G01X125544D02*
X127135D01*
G01X121612D02*
X123202D01*
G01X184551Y146012D02*
X186247D01*
G01X180610D02*
X182306D01*
G01X176677D02*
X178373D01*
G01X172736D02*
X174432D01*
G01X160929D02*
X162625D01*
G01X156988D02*
X158684D01*
G01X153055D02*
X154751D01*
G01X149114D02*
X150810D01*
G01X145181D02*
X146877D01*
G01X141239D02*
X142936D01*
G01X137307D02*
X139003D01*
G01X133365D02*
X135062D01*
G01X129433D02*
X131129D01*
G01X125491D02*
X127188D01*
G01X121559D02*
X123255D01*
G01X123262Y145945D02*
X121552D01*
G01X127195D02*
X125484D01*
G01X131136D02*
X129426D01*
G01X135069D02*
X133358D01*
G01X139010D02*
X137300D01*
G01X142943D02*
X141233D01*
G01X146884D02*
X145174D01*
G01X150817D02*
X149107D01*
G01X154758D02*
X153048D01*
G01X158691D02*
X156981D01*
G01X162632D02*
X160922D01*
G01X174439D02*
X172729D01*
G01X178380D02*
X176670D01*
G01X182313D02*
X180603D01*
G01X186254D02*
X184544D01*
G01X184525Y145353D02*
X186274D01*
G01X180583D02*
X182332D01*
G01X176651D02*
X178399D01*
G01X172709D02*
X174458D01*
G01X160903D02*
X162651D01*
G01X156961D02*
X158710D01*
G01X153029D02*
X154777D01*
G01X149087D02*
X150836D01*
G01X145155D02*
X146903D01*
G01X141213D02*
X142962D01*
G01X137281D02*
X139029D01*
G01X133339D02*
X135088D01*
G01X129407D02*
X131155D01*
G01X125465D02*
X127214D01*
G01X121533D02*
X123281D01*
G01X123253Y145050D02*
X121561D01*
G01X127185D02*
X125494D01*
G01X131127D02*
X129435D01*
G01X135059D02*
X133368D01*
G01X139001D02*
X137309D01*
G01X142933D02*
X141242D01*
G01X146875D02*
X145184D01*
G01X150807D02*
X149116D01*
G01X154749D02*
X153058D01*
G01X158681D02*
X156990D01*
G01X162623D02*
X160932D01*
G01X174429D02*
X172738D01*
G01X178371D02*
X176680D01*
G01X182303D02*
X180612D01*
G01X186245D02*
X184554D01*
G01X123262Y144960D02*
X121552D01*
G01X127195D02*
X125484D01*
G01X131136D02*
X129426D01*
G01X135069D02*
X133358D01*
G01X139010D02*
X137300D01*
G01X142943D02*
X141233D01*
G01X146884D02*
X145174D01*
G01X150817D02*
X149107D01*
G01X154758D02*
X153048D01*
G01X158691D02*
X156981D01*
G01X162632D02*
X160922D01*
G01X174439D02*
X172729D01*
G01X178380D02*
X176670D01*
G01X182313D02*
X180603D01*
G01X186254D02*
X184544D01*
G01X184292Y144634D02*
X186497D01*
G01X180355D02*
X182560D01*
G01X176418D02*
X178623D01*
G01X172481D02*
X174686D01*
G01X123505D02*
X121300D01*
G01X127442D02*
X125237D01*
G01X131379D02*
X129174D01*
G01X135316D02*
X133111D01*
G01X139253D02*
X137048D01*
G01X143190D02*
X140985D01*
G01X147127D02*
X144922D01*
G01X151064D02*
X148859D01*
G01X155001D02*
X152796D01*
G01X158938D02*
X156733D01*
G01X162875D02*
X160670D01*
G01X184292Y144467D02*
X186497D01*
G01X180355D02*
X182560D01*
G01X176418D02*
X178623D01*
G01X172481D02*
X174686D01*
G01X160670D02*
X162875D01*
G01X156733D02*
X158938D01*
G01X152796D02*
X155001D01*
G01X148859D02*
X151064D01*
G01X144922D02*
X147127D01*
G01X140985D02*
X143190D01*
G01X137048D02*
X139253D01*
G01X133111D02*
X135316D01*
G01X129174D02*
X131379D01*
G01X125237D02*
X127442D01*
G01X121300D02*
X123505D01*
G01Y141910D02*
X121300D01*
G01X127442D02*
X125237D01*
G01X131379D02*
X129174D01*
G01X135316D02*
X133111D01*
G01X139253D02*
X137048D01*
G01X143190D02*
X140985D01*
G01X147127D02*
X144922D01*
G01X151064D02*
X148859D01*
G01X155001D02*
X152796D01*
G01X158938D02*
X156733D01*
G01X162875D02*
X160670D01*
G01X174686D02*
X172481D01*
G01X178623D02*
X176418D01*
G01X182560D02*
X180355D01*
G01X186497D02*
X184292D01*
G01X160670Y141743D02*
X162875D01*
G01X156733D02*
X158938D01*
G01X152796D02*
X155001D01*
G01X148859D02*
X151064D01*
G01X144922D02*
X147127D01*
G01X140985D02*
X143190D01*
G01X137048D02*
X139253D01*
G01X133111D02*
X135316D01*
G01X129174D02*
X131379D01*
G01X125237D02*
X127442D01*
G01X121300D02*
X123505D01*
G01X174686D02*
X172481D01*
G01X178623D02*
X176418D01*
G01X182560D02*
X180355D01*
G01X186497D02*
X184292D01*
G01X184535Y141417D02*
X186245D01*
G01X180603D02*
X182313D01*
G01X176661D02*
X178371D01*
G01X172729D02*
X174439D01*
G01X160913D02*
X162623D01*
G01X156981D02*
X158691D01*
G01X153039D02*
X154749D01*
G01X149107D02*
X150817D01*
G01X145165D02*
X146875D01*
G01X141233D02*
X142943D01*
G01X137291D02*
X139001D01*
G01X133358D02*
X135069D01*
G01X129417D02*
X131127D01*
G01X125484D02*
X127195D01*
G01X121543D02*
X123253D01*
G01X184544Y141327D02*
X186236D01*
G01X180612D02*
X182303D01*
G01X176670D02*
X178362D01*
G01X172738D02*
X174429D01*
G01X160922D02*
X162614D01*
G01X156990D02*
X158681D01*
G01X153048D02*
X154740D01*
G01X149116D02*
X150807D01*
G01X145174D02*
X146866D01*
G01X141242D02*
X142933D01*
G01X137300D02*
X138992D01*
G01X133368D02*
X135059D01*
G01X129426D02*
X131118D01*
G01X125494D02*
X127185D01*
G01X121552D02*
X123244D01*
G01X123272Y141024D02*
X121524D01*
G01X127214D02*
X125465D01*
G01X131146D02*
X129398D01*
G01X135088D02*
X133339D01*
G01X139020D02*
X137272D01*
G01X142962D02*
X141213D01*
G01X146894D02*
X145146D01*
G01X150836D02*
X149087D01*
G01X154768D02*
X153020D01*
G01X158710D02*
X156961D01*
G01X162642D02*
X160894D01*
G01X174458D02*
X172709D01*
G01X178390D02*
X176642D01*
G01X182332D02*
X180583D01*
G01X186264D02*
X184516D01*
G01X184535Y140433D02*
X186245D01*
G01X180603D02*
X182313D01*
G01X176661D02*
X178371D01*
G01X172729D02*
X174439D01*
G01X160913D02*
X162623D01*
G01X156981D02*
X158691D01*
G01X153039D02*
X154749D01*
G01X149107D02*
X150817D01*
G01X145165D02*
X146875D01*
G01X141233D02*
X142943D01*
G01X137291D02*
X139001D01*
G01X133358D02*
X135069D01*
G01X129417D02*
X131127D01*
G01X125484D02*
X127195D01*
G01X121543D02*
X123253D01*
G01X123246Y140365D02*
X121550D01*
G01X127188D02*
X125491D01*
G01X131120D02*
X129424D01*
G01X135062D02*
X133365D01*
G01X138994D02*
X137298D01*
G01X142936D02*
X141239D01*
G01X146868D02*
X145172D01*
G01X150810D02*
X149114D01*
G01X154742D02*
X153046D01*
G01X158684D02*
X156988D01*
G01X162616D02*
X160920D01*
G01X174432D02*
X172736D01*
G01X178364D02*
X176668D01*
G01X182306D02*
X180610D01*
G01X186238D02*
X184542D01*
G01X123193Y140340D02*
X121603D01*
G01X127135D02*
X125544D01*
G01X131067D02*
X129477D01*
G01X135009D02*
X133418D01*
G01X138941D02*
X137351D01*
G01X142883D02*
X141292D01*
G01X146815D02*
X145225D01*
G01X150757D02*
X149166D01*
G01X154689D02*
X153099D01*
G01X158631D02*
X157040D01*
G01X162563D02*
X160973D01*
G01X174379D02*
X172788D01*
G01X178311D02*
X176721D01*
G01X182253D02*
X180662D01*
G01X186185D02*
X184595D01*
G01X184521Y140138D02*
X186259D01*
G01X180588D02*
X182327D01*
G01X176647D02*
X178385D01*
G01X172714D02*
X174453D01*
G01X160899D02*
X162637D01*
G01X156966D02*
X158705D01*
G01X153025D02*
X154763D01*
G01X149092D02*
X150831D01*
G01X145151D02*
X146889D01*
G01X141218D02*
X142957D01*
G01X137276D02*
X139015D01*
G01X133344D02*
X135083D01*
G01X129402D02*
X131141D01*
G01X125470D02*
X127209D01*
G01X121528D02*
X123267D01*
G01X170423Y139645D02*
X454618D01*
G01X116958D02*
X164933D01*
G01X184292Y139488D02*
X186497D01*
G01X180355D02*
X182560D01*
G01X176418D02*
X178623D01*
G01X172481D02*
X174686D01*
G01X160670D02*
X162875D01*
G01X156733D02*
X158938D01*
G01X152796D02*
X155001D01*
G01X148859D02*
X151064D01*
G01X144922D02*
X147127D01*
G01X140985D02*
X143190D01*
G01X137048D02*
X139253D01*
G01X133111D02*
X135316D01*
G01X129174D02*
X131379D01*
G01X125237D02*
X127442D01*
G01X121300D02*
X123505D01*
G01X184592Y139379D02*
X186188D01*
G01X180660D02*
X182255D01*
G01X176718D02*
X178314D01*
G01X172786D02*
X174381D01*
G01X160970D02*
X162566D01*
G01X157038D02*
X158633D01*
G01X153096D02*
X154692D01*
G01X149164D02*
X150759D01*
G01X145222D02*
X146817D01*
G01X141290D02*
X142885D01*
G01X137348D02*
X138943D01*
G01X133416D02*
X135011D01*
G01X129474D02*
X131069D01*
G01X125542D02*
X127137D01*
G01X121600D02*
X123195D01*
G01X112560Y139252D02*
X116497D01*
G01X123072Y138760D02*
X121733D01*
G01X130946D02*
X129607D01*
G01X138820D02*
X137481D01*
G01X146694D02*
X145355D01*
G01X154568D02*
X153229D01*
G01X162442D02*
X161103D01*
G01X178190D02*
X176851D01*
G01X186064D02*
X184725D01*
G01X123072Y137775D02*
X121733D01*
G01X130946D02*
X129607D01*
G01X138820D02*
X137481D01*
G01X146694D02*
X145355D01*
G01X154568D02*
X153229D01*
G01X162442D02*
X161103D01*
G01X178190D02*
X176851D01*
G01X186064D02*
X184725D01*
G01X184568Y137677D02*
X186221D01*
G01X176694D02*
X178347D01*
G01X160946D02*
X162599D01*
G01X153072D02*
X154725D01*
G01X145198D02*
X146851D01*
G01X137324D02*
X138977D01*
G01X129450D02*
X131103D01*
G01X121576D02*
X123229D01*
G01Y137185D02*
X121576D01*
G01X131103D02*
X129450D01*
G01X138977D02*
X137324D01*
G01X146851D02*
X145198D01*
G01X154725D02*
X153072D01*
G01X162599D02*
X160946D01*
G01X178347D02*
X176694D01*
G01X186221D02*
X184568D01*
G01X115158Y123676D02*
X115733Y123760D01*
G01X116241Y136988D02*
X111517D01*
G01X115001Y136693D02*
X456576D01*
G01X123159Y136570D02*
X121637D01*
G01X127100D02*
X125579D01*
G01X131033D02*
X129511D01*
G01X134974D02*
X133453D01*
G01X138907D02*
X137385D01*
G01X142848D02*
X141327D01*
G01X146781D02*
X145259D01*
G01X150722D02*
X149201D01*
G01X154655D02*
X153133D01*
G01X158596D02*
X157075D01*
G01X162529D02*
X161007D01*
G01X174344D02*
X172823D01*
G01X178277D02*
X176755D01*
G01X182218D02*
X180697D01*
G01X186151D02*
X184629D01*
G01X123170Y136551D02*
X121626D01*
G01X127111D02*
X125568D01*
G01X131044D02*
X129500D01*
G01X134985D02*
X133442D01*
G01X138918D02*
X137374D01*
G01X142859D02*
X141316D01*
G01X146792D02*
X145248D01*
G01X150733D02*
X149190D01*
G01X154666D02*
X153122D01*
G01X158607D02*
X157064D01*
G01X162540D02*
X160996D01*
G01X174355D02*
X172812D01*
G01X178288D02*
X176744D01*
G01X182229D02*
X180686D01*
G01X186162D02*
X184618D01*
G01X121300Y136515D02*
X120985D01*
G01X123820D02*
X123505D01*
G01X125237D02*
X124922D01*
G01X127757D02*
X127442D01*
G01X129174D02*
X128859D01*
G01X131694D02*
X131379D01*
G01X133111D02*
X132796D01*
G01X137048D02*
X136733D01*
G01X135631D02*
X135316D01*
G01X139568D02*
X139253D01*
G01X140985D02*
X140670D01*
G01X143505D02*
X143190D01*
G01X144922D02*
X144607D01*
G01X147442D02*
X147127D01*
G01X148859D02*
X148544D01*
G01X151379D02*
X151064D01*
G01X152796D02*
X152481D01*
G01X155316D02*
X155001D01*
G01X156733D02*
X156418D01*
G01X159253D02*
X158938D01*
G01X160670D02*
X160355D01*
G01X163190D02*
X162875D01*
G01X172481D02*
X172166D01*
G01X175001D02*
X174686D01*
G01X176418D02*
X176103D01*
G01X178938D02*
X178623D01*
G01X180355D02*
X180040D01*
G01X182875D02*
X182560D01*
G01X184292D02*
X183977D01*
G01X186812D02*
X186497D01*
G01X123584Y135984D02*
X121221D01*
G01X127521D02*
X125158D01*
G01X131458D02*
X129095D01*
G01X135395D02*
X133032D01*
G01X139332D02*
X136969D01*
G01X143269D02*
X140906D01*
G01X147206D02*
X144843D01*
G01X151143D02*
X148780D01*
G01X155080D02*
X152717D01*
G01X159017D02*
X156655D01*
G01X162954D02*
X160592D01*
G01X174765D02*
X172403D01*
G01X178702D02*
X176340D01*
G01X182639D02*
X180277D01*
G01X186576D02*
X184214D01*
G01X122926Y135937D02*
X121870D01*
G01X126868D02*
X125811D01*
G01X130800D02*
X129744D01*
G01X134742D02*
X133685D01*
G01X138674D02*
X137618D01*
G01X142616D02*
X141559D01*
G01X146548D02*
X145492D01*
G01X150490D02*
X149433D01*
G01X154422D02*
X153366D01*
G01X158364D02*
X157307D01*
G01X162296D02*
X161240D01*
G01X174112D02*
X173055D01*
G01X178044D02*
X176988D01*
G01X181986D02*
X180929D01*
G01X185918D02*
X184862D01*
G01X184642Y135615D02*
X186138D01*
G01X180709D02*
X182206D01*
G01X176768D02*
X178264D01*
G01X172835D02*
X174332D01*
G01X161020D02*
X162516D01*
G01X157087D02*
X158584D01*
G01X153146D02*
X154642D01*
G01X149213D02*
X150710D01*
G01X145272D02*
X146768D01*
G01X141339D02*
X142836D01*
G01X137398D02*
X138894D01*
G01X133465D02*
X134962D01*
G01X129524D02*
X131020D01*
G01X125591D02*
X127088D01*
G01X121650D02*
X123146D01*
G01X170178Y135610D02*
X165178D01*
G01X184640Y135605D02*
X186140D01*
G01X180708D02*
X182207D01*
G01X176766D02*
X178266D01*
G01X172834D02*
X174333D01*
G01X161018D02*
X162518D01*
G01X157086D02*
X158585D01*
G01X153144D02*
X154644D01*
G01X149212D02*
X150711D01*
G01X145270D02*
X146770D01*
G01X141338D02*
X142837D01*
G01X137396D02*
X138896D01*
G01X133464D02*
X134963D01*
G01X129522D02*
X131022D01*
G01X125590D02*
X127089D01*
G01X121648D02*
X123148D01*
G01X123229Y135413D02*
X121576D01*
G01X131103D02*
X129450D01*
G01X138977D02*
X137324D01*
G01X146851D02*
X145198D01*
G01X154725D02*
X153072D01*
G01X162599D02*
X160946D01*
G01X178347D02*
X176694D01*
G01X186221D02*
X184568D01*
G01X184380Y135117D02*
X186400D01*
G01X180447D02*
X182468D01*
G01X176506D02*
X178526D01*
G01X172573D02*
X174594D01*
G01X160758D02*
X162778D01*
G01X156825D02*
X158846D01*
G01X152884D02*
X154904D01*
G01X148951D02*
X150972D01*
G01X145009D02*
X147030D01*
G01X141077D02*
X143098D01*
G01X137135D02*
X139156D01*
G01X133203D02*
X135224D01*
G01X129261D02*
X131282D01*
G01X125329D02*
X127350D01*
G01X121387D02*
X123408D01*
G01X186497Y135019D02*
X186812D01*
G01X178623D02*
X178938D01*
G01X162875D02*
X163190D01*
G01X155001D02*
X155316D01*
G01X147127D02*
X147442D01*
G01X139253D02*
X139568D01*
G01X131379D02*
X131694D01*
G01X123505D02*
X123820D01*
G01X121300D02*
X120985D01*
G01X125237D02*
X124922D01*
G01X127757D02*
X127442D01*
G01X129174D02*
X128859D01*
G01X133111D02*
X132796D01*
G01X137048D02*
X136733D01*
G01X135631D02*
X135316D01*
G01X140985D02*
X140670D01*
G01X143505D02*
X143190D01*
G01X144922D02*
X144607D01*
G01X148859D02*
X148544D01*
G01X151379D02*
X151064D01*
G01X152796D02*
X152481D01*
G01X156733D02*
X156418D01*
G01X159253D02*
X158938D01*
G01X160670D02*
X160355D01*
G01X172481D02*
X172166D01*
G01X175001D02*
X174686D01*
G01X176418D02*
X176103D01*
G01X180355D02*
X180040D01*
G01X182875D02*
X182560D01*
G01X184292D02*
X183977D01*
G01X184907Y135009D02*
X185873D01*
G01X180975D02*
X181940D01*
G01X177033D02*
X177999D01*
G01X173101D02*
X174066D01*
G01X161285D02*
X162251D01*
G01X157353D02*
X158318D01*
G01X153411D02*
X154377D01*
G01X149479D02*
X150444D01*
G01X145537D02*
X146503D01*
G01X141605D02*
X142570D01*
G01X137663D02*
X138629D01*
G01X133731D02*
X134696D01*
G01X129789D02*
X130755D01*
G01X125857D02*
X126822D01*
G01X121915D02*
X122881D01*
G01X184568Y134921D02*
X186221D01*
G01X176694D02*
X178347D01*
G01X160946D02*
X162599D01*
G01X153072D02*
X154725D01*
G01X145198D02*
X146851D01*
G01X137324D02*
X138977D01*
G01X129450D02*
X131103D01*
G01X121576D02*
X123229D01*
G01X183977Y134822D02*
X186812D01*
G01X180040D02*
X182875D01*
G01X176103D02*
X178938D01*
G01X172166D02*
X175001D01*
G01X160355D02*
X163190D01*
G01X156418D02*
X159253D01*
G01X152481D02*
X155316D01*
G01X148544D02*
X151379D01*
G01X144607D02*
X147442D01*
G01X140670D02*
X143505D01*
G01X136733D02*
X139568D01*
G01X132796D02*
X135631D01*
G01X128859D02*
X131694D01*
G01X124922D02*
X127757D01*
G01X120985D02*
X123820D01*
G01X186221Y134665D02*
X186812D01*
G01X183977D02*
X184568D01*
G01X182284D02*
X182875D01*
G01X180040D02*
X180631D01*
G01X178347D02*
X178938D01*
G01X176103D02*
X176694D01*
G01X174410D02*
X175001D01*
G01X172166D02*
X172757D01*
G01X162599D02*
X163190D01*
G01X160355D02*
X160946D01*
G01X158662D02*
X159253D01*
G01X156418D02*
X157009D01*
G01X154725D02*
X155316D01*
G01X152481D02*
X153072D01*
G01X150788D02*
X151379D01*
G01X148544D02*
X149135D01*
G01X146851D02*
X147442D01*
G01X144607D02*
X145198D01*
G01X142914D02*
X143505D01*
G01X140670D02*
X141261D01*
G01X138977D02*
X139568D01*
G01X136733D02*
X137324D01*
G01X135040D02*
X135631D01*
G01X132796D02*
X133387D01*
G01X131103D02*
X131694D01*
G01X128859D02*
X129450D01*
G01X127166D02*
X127757D01*
G01X124922D02*
X125513D01*
G01X123229D02*
X123820D01*
G01X120985D02*
X121576D01*
G01X123134Y134640D02*
X121661D01*
G01X127076D02*
X125603D01*
G01X131008D02*
X129535D01*
G01X134950D02*
X133477D01*
G01X138882D02*
X137409D01*
G01X142824D02*
X141351D01*
G01X146756D02*
X145283D01*
G01X150698D02*
X149225D01*
G01X154630D02*
X153157D01*
G01X158572D02*
X157099D01*
G01X162504D02*
X161031D01*
G01X174320D02*
X172847D01*
G01X178252D02*
X176779D01*
G01X182194D02*
X180721D01*
G01X186126D02*
X184653D01*
G01X184640Y134621D02*
X186140D01*
G01X180708D02*
X182207D01*
G01X176766D02*
X178266D01*
G01X172834D02*
X174333D01*
G01X161018D02*
X162518D01*
G01X157086D02*
X158585D01*
G01X153144D02*
X154644D01*
G01X149212D02*
X150711D01*
G01X145270D02*
X146770D01*
G01X141338D02*
X142837D01*
G01X137396D02*
X138896D01*
G01X133464D02*
X134963D01*
G01X129522D02*
X131022D01*
G01X125590D02*
X127089D01*
G01X121648D02*
X123148D01*
G01X123403Y134231D02*
X121392D01*
G01X127345D02*
X125334D01*
G01X131278D02*
X129266D01*
G01X135219D02*
X133208D01*
G01X139152D02*
X137140D01*
G01X143093D02*
X141082D01*
G01X147026D02*
X145014D01*
G01X150967D02*
X148956D01*
G01X154900D02*
X152888D01*
G01X158841D02*
X156830D01*
G01X162774D02*
X160762D01*
G01X174589D02*
X172578D01*
G01X178522D02*
X176510D01*
G01X182463D02*
X180452D01*
G01X186396D02*
X184384D01*
G01X121576Y133996D02*
X120985D01*
G01X123820D02*
X123229D01*
G01X125513D02*
X124922D01*
G01X127757D02*
X127166D01*
G01X129450D02*
X128859D01*
G01X131694D02*
X131103D01*
G01X133387D02*
X132796D01*
G01X135631D02*
X135040D01*
G01X137324D02*
X136733D01*
G01X139568D02*
X138977D01*
G01X141261D02*
X140670D01*
G01X143505D02*
X142914D01*
G01X145198D02*
X144607D01*
G01X147442D02*
X146851D01*
G01X149135D02*
X148544D01*
G01X151379D02*
X150788D01*
G01X153072D02*
X152481D01*
G01X155316D02*
X154725D01*
G01X157009D02*
X156418D01*
G01X159253D02*
X158662D01*
G01X160946D02*
X160355D01*
G01X163190D02*
X162599D01*
G01X172757D02*
X172166D01*
G01X175001D02*
X174410D01*
G01X176694D02*
X176103D01*
G01X178938D02*
X178347D01*
G01X180631D02*
X180040D01*
G01X182875D02*
X182284D01*
G01X184568D02*
X183977D01*
G01X186812D02*
X186221D01*
G01X123820Y133838D02*
X120985D01*
G01X127757D02*
X124922D01*
G01X131694D02*
X128859D01*
G01X135631D02*
X132796D01*
G01X139568D02*
X136733D01*
G01X143505D02*
X140670D01*
G01X147442D02*
X144607D01*
G01X151379D02*
X148544D01*
G01X155316D02*
X152481D01*
G01X159253D02*
X156418D01*
G01X163190D02*
X160355D01*
G01X175001D02*
X172166D01*
G01X178938D02*
X176103D01*
G01X182875D02*
X180040D01*
G01X186812D02*
X183977D01*
G01X127166Y133740D02*
X125513D01*
G01X135040D02*
X133387D01*
G01X142914D02*
X141261D01*
G01X150788D02*
X149135D01*
G01X158662D02*
X157009D01*
G01X174410D02*
X172757D01*
G01X182284D02*
X180631D01*
G01Y133248D02*
X182284D01*
G01X172757D02*
X174410D01*
G01X157009D02*
X158662D01*
G01X149135D02*
X150788D01*
G01X141261D02*
X142914D01*
G01X133387D02*
X135040D01*
G01X125513D02*
X127166D01*
G01X183977Y132342D02*
X186812D01*
G01X180040D02*
X182875D01*
G01X176103D02*
X178938D01*
G01X172166D02*
X175001D01*
G01X160355D02*
X163190D01*
G01X156418D02*
X159253D01*
G01X152481D02*
X155316D01*
G01X148544D02*
X151379D01*
G01X144607D02*
X147442D01*
G01X140670D02*
X143505D01*
G01X136733D02*
X139568D01*
G01X132796D02*
X135631D01*
G01X128859D02*
X131694D01*
G01X124922D02*
X127757D01*
G01X120985D02*
X123820D01*
G01X180631Y131476D02*
X182284D01*
G01X172757D02*
X174410D01*
G01X157009D02*
X158662D01*
G01X149135D02*
X150788D01*
G01X141261D02*
X142914D01*
G01X133387D02*
X135040D01*
G01X125513D02*
X127166D01*
G01X184214Y131082D02*
X186576D01*
G01X180277D02*
X182639D01*
G01X172403D02*
X174765D01*
G01X160592D02*
X162954D01*
G01X156655D02*
X159017D01*
G01X152717D02*
X155080D01*
G01X148780D02*
X151143D01*
G01X144843D02*
X147206D01*
G01X140906D02*
X143269D01*
G01X136969D02*
X139332D01*
G01X133032D02*
X135395D01*
G01X129095D02*
X131458D01*
G01X125158D02*
X127521D01*
G01X121221D02*
X123584D01*
G01X116241D02*
X111517D01*
G01X178702D02*
X176340D01*
G01X127166Y130984D02*
X125513D01*
G01X135040D02*
X133387D01*
G01X142914D02*
X141261D01*
G01X150788D02*
X149135D01*
G01X158662D02*
X157009D01*
G01X174410D02*
X172757D01*
G01X182284D02*
X180631D01*
G01X165178Y130885D02*
X170178D01*
G01X127009D02*
X125670D01*
G01X134883D02*
X133544D01*
G01X142757D02*
X141418D01*
G01X150631D02*
X149292D01*
G01X158505D02*
X157166D01*
G01X174253D02*
X172914D01*
G01X182127D02*
X180788D01*
G01X184214Y129901D02*
X186576D01*
G01X180277D02*
X182639D01*
G01X176340D02*
X178702D01*
G01X172403D02*
X174765D01*
G01X160592D02*
X162954D01*
G01X156655D02*
X159017D01*
G01X152717D02*
X155080D01*
G01X148780D02*
X151143D01*
G01X144843D02*
X147206D01*
G01X140906D02*
X143269D01*
G01X136969D02*
X139332D01*
G01X133032D02*
X135395D01*
G01X129095D02*
X131458D01*
G01X125158D02*
X127521D01*
G01X121221D02*
X123584D01*
G01X460985Y128523D02*
X110592D01*
G01X115733Y123760D02*
X115897D01*
G01X112452D02*
X109663D01*
G01X110073Y123341D02*
X112452D01*
G01X115979D02*
X115651D01*
G01X181458Y123011D02*
X201143D01*
G01X157836D02*
X177521D01*
G01X134214D02*
X153899D01*
G01X130277D02*
X110592D01*
G01X114830Y122838D02*
X114420D01*
G01X123771Y122503D02*
X124099D01*
G01X122458D02*
X122786D01*
G01X121638D02*
X122048D01*
G01X120080D02*
X120408D01*
G01X118767D02*
X119095D01*
G01X117947D02*
X118357D01*
G01X111385Y122335D02*
X110893D01*
G01X118931Y122168D02*
X118767D01*
G01X120244D02*
X119998D01*
G01X122622D02*
X122458D01*
G01X123935D02*
X123689D01*
G01X115651Y122000D02*
X115979D01*
G01X110893Y121917D02*
X111385D01*
G01X115979Y121665D02*
X115651D01*
G01X109663Y121582D02*
X110237D01*
G01X110155Y120828D02*
X109663D01*
G01X114338Y120744D02*
X114748D01*
G01X115569Y120241D02*
X116061D01*
G01X113272D02*
X113682D01*
G01X111385D02*
X110893D01*
G01Y119822D02*
X111385D01*
G01X113682D02*
X113272D01*
G01X116143D02*
X115487D01*
G01X118357D02*
X117947D01*
G01X119670D02*
X119259D01*
G01X122048D02*
X121638D01*
G01X120982D02*
X120572D01*
G01X123361D02*
X122950D01*
G01X124673D02*
X124263D01*
G01X115897Y123760D02*
X116471Y123676D01*
G01X111385Y121917D02*
X111714Y121833D01*
G01X115487Y119822D02*
X115158Y119906D01*
G01X110893Y120241D02*
X110565Y120325D01*
G01X116389Y123257D02*
X115979Y123341D01*
G01X111796Y122252D02*
X111385Y122335D01*
G01X115158Y120325D02*
X115569Y120241D01*
G01X110483Y119906D02*
X110893Y119822D01*
G01X116471Y121582D02*
X115979Y121665D01*
G01X116635Y121833D02*
X117045Y121665D01*
G01X124099Y122503D02*
X124345Y122419D01*
G01X122786Y122503D02*
X123032Y122419D01*
G01X120408Y122503D02*
X120654Y122419D01*
G01X119095Y122503D02*
X119342Y122419D01*
G01X124099Y122084D02*
X123935Y122168D01*
G01X122786Y122084D02*
X122622Y122168D01*
G01X120408Y122084D02*
X120244Y122168D01*
G01X116471Y123676D02*
X116799Y123508D01*
G01X119095Y122084D02*
X118931Y122168D01*
G01X114994Y120409D02*
X115158Y120325D01*
G01Y119906D02*
X114830Y120074D01*
G01X107859Y121833D02*
X109007Y121247D01*
G01X184917Y151368D02*
X184663Y151737D01*
G01X184871Y150441D02*
X184650Y150762D01*
G01X180975Y151368D02*
X180721Y151737D01*
G01X180710Y150760D02*
X180929Y150441D01*
G01X177043Y151368D02*
X176789Y151737D01*
G01X176997Y150441D02*
X176776Y150762D01*
G01X185918Y135937D02*
X186140Y135615D01*
G01X185873Y135009D02*
X186126Y134640D01*
G01X173101Y151368D02*
X172847Y151737D01*
G01X172836Y150760D02*
X173055Y150441D01*
G01X182206Y135617D02*
X181986Y135937D01*
G01X181940Y135009D02*
X182194Y134640D01*
G01X178044Y135937D02*
X178266Y135615D01*
G01X116635Y123089D02*
X116389Y123257D01*
G01X116717Y121414D02*
X116471Y121582D01*
G01X114830Y120074D02*
X114584Y120241D01*
G01X111714Y121833D02*
X111960Y121665D01*
G01X110565Y120325D02*
X110319Y120493D01*
G01X112206Y122000D02*
X111796Y122252D01*
G01X110073Y120158D02*
X110483Y119906D01*
G01X108843Y120995D02*
X107284Y121833D01*
G01X170423Y146732D02*
X168936Y148975D01*
G01X164933Y139645D02*
X166421Y137402D01*
G01X177999Y135009D02*
X178252Y134640D01*
G01X174332Y135617D02*
X174112Y135937D01*
G01X174066Y135009D02*
X174320Y134640D01*
G01X161295Y151368D02*
X161041Y151737D01*
G01X161249Y150441D02*
X161028Y150762D01*
G01X157353Y151368D02*
X157099Y151737D01*
G01X157088Y150760D02*
X157307Y150441D01*
G01X153421Y151368D02*
X153167Y151737D01*
G01X153375Y150441D02*
X153154Y150762D01*
G01X162296Y135937D02*
X162518Y135615D01*
G01X162251Y135009D02*
X162504Y134640D01*
G01X149479Y151368D02*
X149225Y151737D01*
G01X149214Y150760D02*
X149433Y150441D01*
G01X158584Y135617D02*
X158364Y135937D01*
G01X158318Y135009D02*
X158572Y134640D01*
G01X145547Y151368D02*
X145293Y151737D01*
G01X145501Y150441D02*
X145280Y150762D01*
G01X154422Y135937D02*
X154644Y135615D01*
G01X154377Y135009D02*
X154630Y134640D01*
G01X141605Y151368D02*
X141351Y151737D01*
G01X141340Y150760D02*
X141559Y150441D01*
G01X150710Y135617D02*
X150490Y135937D01*
G01X150444Y135009D02*
X150698Y134640D01*
G01X137673Y151368D02*
X137419Y151737D01*
G01X124345Y122419D02*
X124509Y122252D01*
G01X123525Y122419D02*
X123771Y122503D01*
G01X122458Y122168D02*
X122212Y122084D01*
G01Y122419D02*
X122458Y122503D01*
G01X119834Y122419D02*
X120080Y122503D01*
G01X118767Y122168D02*
X118521Y122084D01*
G01Y122419D02*
X118767Y122503D01*
G01X115979Y122000D02*
X116471Y122168D01*
G01X184871Y150441D02*
X184881Y150393D01*
G01X185918Y135937D02*
X185909Y135984D01*
G01X180939Y150393D02*
X180929Y150441D01*
G01X181976Y135984D02*
X181986Y135937D01*
G01X176997Y150441D02*
X177007Y150393D01*
G01X178044Y135937D02*
X178035Y135984D01*
G01X173065Y150393D02*
X173055Y150441D01*
G01X174102Y135984D02*
X174112Y135937D01*
G01X115001Y149685D02*
X116958Y146732D01*
G01X137627Y150441D02*
X137406Y150762D01*
G01X146548Y135937D02*
X146770Y135615D01*
G01X146503Y135009D02*
X146756Y134640D01*
G01X133731Y151368D02*
X133477Y151737D01*
G01X133466Y150760D02*
X133685Y150441D01*
G01X142836Y135617D02*
X142616Y135937D01*
G01X142570Y135009D02*
X142824Y134640D01*
G01X129799Y151368D02*
X129545Y151737D01*
G01X129753Y150441D02*
X129532Y150762D01*
G01X138674Y135937D02*
X138896Y135615D01*
G01X138629Y135009D02*
X138882Y134640D01*
G01X125857Y151368D02*
X125603Y151737D01*
G01X125592Y150760D02*
X125811Y150441D01*
G01X134962Y135617D02*
X134742Y135937D01*
G01X134696Y135009D02*
X134950Y134640D01*
G01X121925Y151368D02*
X121671Y151737D01*
G01X121879Y150441D02*
X121658Y150762D01*
G01X130800Y135937D02*
X131022Y135615D01*
G01X130755Y135009D02*
X131008Y134640D01*
G01X127088Y135617D02*
X126868Y135937D01*
G01X126822Y135009D02*
X127076Y134640D01*
G01X122926Y135937D02*
X123147Y135615D01*
G01X122881Y135009D02*
X123134Y134640D01*
G01X124181Y122000D02*
X124099Y122084D01*
G01X123032Y122419D02*
X123279Y122168D01*
G01X122868Y122000D02*
X122786Y122084D01*
G01X120654Y122419D02*
X120818Y122252D01*
G01X120490Y122000D02*
X120408Y122084D01*
G01X119342Y122419D02*
X119588Y122168D01*
G01X119177Y122000D02*
X119095Y122084D01*
G01X116799Y123508D02*
X117127Y123173D01*
G01X114830Y120576D02*
X114994Y120409D01*
G01X123689Y122168D02*
X123525Y122084D01*
G01X116799Y120074D02*
X116471Y119906D01*
G01Y120325D02*
X116635Y120409D01*
G01X119998Y122168D02*
X119834Y122084D01*
G01X114830Y123508D02*
X115158Y123676D01*
G01X109007Y122419D02*
X107859Y121833D01*
G01X107284D02*
X108843Y122671D01*
G01X111796Y119906D02*
X112206Y120158D01*
G01X186274Y145353D02*
X186410Y151260D01*
G01X186405Y152147D02*
X186269Y146239D01*
G01X185886Y135984D02*
X185873Y135009D01*
G01X184904Y150393D02*
X184917Y151368D01*
G01X186777Y152539D02*
Y151555D01*
G01X186773Y134822D02*
Y133838D01*
G01X186768Y134822D02*
Y133838D01*
G01X186576Y135984D02*
Y129901D01*
G01Y156476D02*
Y150393D01*
G01X186497Y133838D02*
Y152539D01*
G01X186423Y152538D02*
Y151553D01*
G01X186414Y134824D02*
Y133840D01*
G01X186221Y147698D02*
Y152539D01*
G01Y133838D02*
Y138680D01*
G01X186147Y150760D02*
Y151750D01*
G01X186138Y134627D02*
Y135617D01*
G01X186064Y138760D02*
Y137696D01*
G01Y148681D02*
Y147618D01*
G01X185788D02*
Y148602D01*
G01Y138760D02*
Y137775D01*
G01X185001Y147618D02*
Y148602D01*
G01Y138760D02*
Y137775D01*
G01X184725Y138760D02*
Y137696D01*
G01Y148681D02*
Y147618D01*
G01X184651Y151750D02*
Y150760D01*
G01X184642Y135617D02*
Y134627D01*
G01X184607Y128523D02*
Y123011D01*
G01X184568Y147698D02*
Y152539D01*
G01Y133838D02*
Y138680D01*
G01X184376Y151553D02*
Y152538D01*
G01X184366Y133840D02*
Y134824D01*
G01X184292Y152539D02*
Y133838D01*
G01X184214Y135984D02*
Y129901D01*
G01Y156476D02*
Y150393D01*
G01X184021Y152539D02*
Y151555D01*
G01X184017Y152539D02*
Y151555D01*
G01X184012Y134822D02*
Y133838D01*
G01X183977Y136515D02*
Y132342D01*
G01Y154035D02*
Y149862D01*
G01X185882Y151368D02*
X185895Y150393D01*
G01X184907Y135009D02*
X184894Y135984D01*
G01X186400Y135117D02*
X186264Y141024D01*
G01X186259Y140138D02*
X186396Y134231D01*
G01X184530Y146239D02*
X184394Y152147D01*
G01X184389Y151260D02*
X184525Y145353D01*
G01X186247Y146012D02*
X186197Y146999D01*
G01X186195Y146037D02*
X186245Y145050D01*
G01X184595Y140340D02*
X184544Y141327D01*
G01X184542Y140365D02*
X184592Y139379D01*
G01X182306Y146012D02*
X182255Y146999D01*
G01X182253Y146037D02*
X182303Y145050D01*
G01X161249Y150441D02*
X161259Y150393D01*
G01X162296Y135937D02*
X162287Y135984D01*
G01X157317Y150393D02*
X157307Y150441D01*
G01X158354Y135984D02*
X158364Y135937D01*
G01X153375Y150441D02*
X153385Y150393D01*
G01X154422Y135937D02*
X154413Y135984D01*
G01X149443Y150393D02*
X149433Y150441D01*
G01X150480Y135984D02*
X150490Y135937D01*
G01X145501Y150441D02*
X145511Y150393D01*
G01X146548Y135937D02*
X146539Y135984D01*
G01X124263Y121833D02*
X124181Y122000D01*
G01X122950Y121833D02*
X122868Y122000D01*
G01X116799Y122838D02*
X116635Y123089D01*
G01X117045Y121665D02*
X117209Y121414D01*
G01X114584Y120241D02*
X114420Y120493D01*
G01X111960Y121665D02*
X112124Y121414D01*
G01X108843Y122671D02*
X109007Y122419D01*
G01X112452Y121665D02*
X112206Y122000D01*
G01X109827Y120493D02*
X110073Y120158D01*
G01X110483Y122252D02*
X110073Y122000D01*
G01X117045Y120241D02*
X116799Y120074D01*
G01X111960Y120493D02*
X111714Y120325D01*
G01X115240Y123257D02*
X114994Y123089D01*
G01X116963Y122084D02*
X116635Y121833D01*
G01X110237Y121582D02*
X110565Y121833D01*
G01X184653Y134640D02*
X184907Y135009D01*
G01X184640Y135615D02*
X184862Y135937D01*
G01X180721Y134640D02*
X180975Y135009D01*
G01X180929Y135937D02*
X180710Y135617D01*
G01X176779Y134640D02*
X177033Y135009D01*
G01X176766Y135615D02*
X176988Y135937D01*
G01X186149Y150762D02*
X185928Y150441D01*
G01X186136Y151737D02*
X185882Y151368D01*
G01X172847Y134640D02*
X173101Y135009D01*
G01X173055Y135937D02*
X172836Y135617D01*
G01X181986Y150441D02*
X182206Y150760D01*
G01X182194Y151737D02*
X181940Y151368D01*
G01X178275Y150762D02*
X178054Y150441D01*
G01X178262Y151737D02*
X178008Y151368D01*
G01X174112Y150441D02*
X174332Y150760D01*
G01X174320Y151737D02*
X174066Y151368D01*
G01X161031Y134640D02*
X161285Y135009D01*
G01X161018Y135615D02*
X161240Y135937D01*
G01X168936Y137402D02*
X170423Y139645D01*
G01X184871Y135984D02*
X184862Y135937D01*
G01X185918Y150393D02*
X185928Y150441D01*
G01X180929Y135937D02*
X180939Y135984D01*
G01X181986Y150441D02*
X181976Y150393D01*
G01X176997Y135984D02*
X176988Y135937D01*
G01X178044Y150393D02*
X178054Y150441D01*
G01X173055Y135937D02*
X173065Y135984D01*
G01X174112Y150441D02*
X174102Y150393D01*
G01X186188Y139379D02*
X186238Y140365D01*
G01X186236Y141327D02*
X186185Y140340D01*
G01X184554Y145050D02*
X184604Y146037D01*
G01X184602Y146999D02*
X184551Y146012D01*
G01X182255Y139379D02*
X182306Y140365D01*
G01X182303Y141327D02*
X182253Y140340D01*
G01X180612Y145050D02*
X180662Y146037D01*
G01X180660Y146999D02*
X180610Y146012D01*
G01X178314Y139379D02*
X178364Y140365D01*
G01X178362Y141327D02*
X178311Y140340D01*
G01X176680Y145050D02*
X176730Y146037D01*
G01X176728Y146999D02*
X176677Y146012D01*
G01X174381Y139379D02*
X174432Y140365D01*
G01X174429Y141327D02*
X174379Y140340D01*
G01X172738Y145050D02*
X172788Y146037D01*
G01X172786Y146999D02*
X172736Y146012D01*
G01X162566Y139379D02*
X162616Y140365D01*
G01X162614Y141327D02*
X162563Y140340D01*
G01X184384Y134231D02*
X184521Y140138D01*
G01X184516Y141024D02*
X184380Y135117D01*
G01X182332Y145353D02*
X182468Y151260D01*
G01X182463Y152147D02*
X182327Y146239D01*
G01X180452Y134231D02*
X180588Y140138D01*
G01X180583Y141024D02*
X180447Y135117D01*
G01X178399Y145353D02*
X178536Y151260D01*
G01X178531Y152147D02*
X178395Y146239D01*
G01X176510Y134231D02*
X176647Y140138D01*
G01X176642Y141024D02*
X176506Y135117D01*
G01X174458Y145353D02*
X174594Y151260D01*
G01X174589Y152147D02*
X174453Y146239D01*
G01X172578Y134231D02*
X172714Y140138D01*
G01X172709Y141024D02*
X172573Y135117D01*
G01X162651Y145353D02*
X162788Y151260D01*
G01X162783Y152147D02*
X162647Y146239D01*
G01X160762Y134231D02*
X160899Y140138D01*
G01X160894Y141024D02*
X160758Y135117D01*
G01X181953Y135984D02*
X181940Y135009D01*
G01X180962Y150393D02*
X180975Y151368D01*
G01X178012Y135984D02*
X177999Y135009D01*
G01X177030Y150393D02*
X177043Y151368D01*
G01X174079Y135984D02*
X174066Y135009D01*
G01X173088Y150393D02*
X173101Y151368D01*
G01X162264Y135984D02*
X162251Y135009D01*
G01X161281Y150393D02*
X161295Y151368D01*
G01X182875Y149862D02*
Y154035D01*
G01Y132342D02*
Y136515D01*
G01X182840Y134822D02*
Y133838D01*
G01X182836Y134822D02*
Y133838D01*
G01Y152539D02*
Y151555D01*
G01X182639Y135984D02*
Y129901D01*
G01Y156476D02*
Y150393D01*
G01X182560Y133838D02*
Y152539D01*
G01X182481Y134824D02*
Y133840D01*
G01Y152538D02*
Y151553D01*
G01X182284Y151555D02*
Y156396D01*
G01Y129981D02*
Y134822D01*
G01X182206Y150760D02*
Y151750D01*
G01Y134627D02*
Y135617D01*
G01X182127Y130965D02*
Y129901D01*
G01Y156476D02*
Y155412D01*
G01X181851Y129901D02*
Y130885D01*
G01Y156476D02*
Y155492D01*
G01X181458Y128523D02*
Y123011D01*
G01X181064Y130885D02*
Y129901D01*
G01Y156476D02*
Y155492D01*
G01X180788Y130965D02*
Y129901D01*
G01Y156476D02*
Y155412D01*
G01X180710Y135617D02*
Y134627D01*
G01Y151750D02*
Y150760D01*
G01X180631Y151555D02*
Y156396D01*
G01Y129981D02*
Y134822D01*
G01X180434Y133840D02*
Y134824D01*
G01Y151553D02*
Y152538D01*
G01X180355Y152539D02*
Y133838D01*
G01X180277Y135984D02*
Y129901D01*
G01Y156476D02*
Y150393D01*
G01X180080Y134822D02*
Y133838D01*
G01Y152539D02*
Y151555D01*
G01X180075Y152539D02*
Y151555D01*
G01X180040Y136515D02*
Y132342D01*
G01Y154035D02*
Y149862D01*
G01X178938D02*
Y154035D01*
G01Y132342D02*
Y136515D01*
G01X178903Y152539D02*
Y151555D01*
G01X178899Y134822D02*
Y133838D01*
G01X178894Y134822D02*
Y133838D01*
G01X178702Y135984D02*
Y129901D01*
G01Y156476D02*
Y150393D01*
G01X178623Y133838D02*
Y152539D01*
G01X178549Y152538D02*
Y151553D01*
G01X178540Y134824D02*
Y133840D01*
G01X178347Y147698D02*
Y152539D01*
G01Y133838D02*
Y138680D01*
G01X178273Y150760D02*
Y151750D01*
G01X178264Y134627D02*
Y135617D01*
G01X178190Y138760D02*
Y137696D01*
G01Y148681D02*
Y147618D01*
G01X177914D02*
Y148602D01*
G01Y138760D02*
Y137775D01*
G01X177521Y128523D02*
Y123011D01*
G01X177127Y147618D02*
Y148602D01*
G01Y138760D02*
Y137775D01*
G01X176851Y138760D02*
Y137696D01*
G01Y148681D02*
Y147618D01*
G01X176777Y151750D02*
Y150760D01*
G01X176768Y135617D02*
Y134627D01*
G01X176694Y147698D02*
Y152539D01*
G01Y133838D02*
Y138680D01*
G01X176502Y151553D02*
Y152538D01*
G01X176492Y133840D02*
Y134824D01*
G01X176418Y152539D02*
Y133838D01*
G01X176340Y135984D02*
Y129901D01*
G01Y156476D02*
Y150393D01*
G01X176147Y152539D02*
Y151555D01*
G01X176143Y152539D02*
Y151555D01*
G01X176138Y134822D02*
Y133838D01*
G01X176103Y136515D02*
Y132342D01*
G01Y154035D02*
Y149862D01*
G01X175001D02*
Y154035D01*
G01Y132342D02*
Y136515D01*
G01X174966Y134822D02*
Y133838D01*
G01X174962Y134822D02*
Y133838D01*
G01Y152539D02*
Y151555D01*
G01X174765Y135984D02*
Y129901D01*
G01Y156476D02*
Y150393D01*
G01X174686Y133838D02*
Y152539D01*
G01X174607Y134824D02*
Y133840D01*
G01Y152538D02*
Y151553D01*
G01X174410Y151555D02*
Y156396D01*
G01Y129981D02*
Y134822D01*
G01X174371Y128523D02*
Y123011D01*
G01X174332Y150760D02*
Y151750D01*
G01Y134627D02*
Y135617D01*
G01X174253Y130965D02*
Y129901D01*
G01Y156476D02*
Y155412D01*
G01X173977Y129901D02*
Y130885D01*
G01Y156476D02*
Y155492D01*
G01X173190Y130885D02*
Y129901D01*
G01Y156476D02*
Y155492D01*
G01X172914Y130965D02*
Y129901D01*
G01Y156476D02*
Y155412D01*
G01X172836Y135617D02*
Y134627D01*
G01Y151750D02*
Y150760D01*
G01X172757Y151555D02*
Y156396D01*
G01Y129981D02*
Y134822D01*
G01X172560Y151553D02*
Y152538D01*
G01Y133840D02*
Y134824D01*
G01X172481Y152539D02*
Y133838D01*
G01X172403Y135984D02*
Y129901D01*
G01Y156476D02*
Y150393D01*
G01X172206Y134822D02*
Y133838D01*
G01Y152539D02*
Y151555D01*
G01X172201Y152539D02*
Y151555D01*
G01X172166Y136515D02*
Y132342D01*
G01Y154035D02*
Y149862D01*
G01X171123Y140064D02*
Y146314D01*
G01X171084Y146732D02*
Y139645D01*
G01X170728Y146732D02*
Y139645D01*
G01X170178Y150767D02*
Y155492D01*
G01Y130885D02*
Y135610D01*
G01X170021Y140595D02*
Y145782D01*
G01X168936Y137402D02*
Y148975D01*
G01X166421D02*
Y137402D01*
G01X165178Y135610D02*
Y130885D01*
G01Y155492D02*
Y150767D01*
G01X164629Y139645D02*
Y146732D01*
G01X164273D02*
Y139645D01*
G01X163190Y149862D02*
Y154035D01*
G01Y132342D02*
Y136515D01*
G01X163155Y152539D02*
Y151555D01*
G01X163151Y134822D02*
Y133838D01*
G01X163146Y134822D02*
Y133838D01*
G01X162954Y135984D02*
Y129901D01*
G01Y156476D02*
Y150393D01*
G01X162875Y133838D02*
Y152539D01*
G01X162801Y152538D02*
Y151553D01*
G01X162792Y134824D02*
Y133840D01*
G01X162599Y147698D02*
Y152539D01*
G01Y133838D02*
Y138680D01*
G01X162525Y150760D02*
Y151750D01*
G01X162516Y134627D02*
Y135617D01*
G01X162442Y138760D02*
Y137696D01*
G01Y148681D02*
Y147618D01*
G01X162166D02*
Y148602D01*
G01Y138760D02*
Y137775D01*
G01X161379Y138760D02*
Y137775D01*
G01Y148602D02*
Y147618D01*
G01X161103Y138760D02*
Y137696D01*
G01Y148681D02*
Y147618D01*
G01X161029Y151750D02*
Y150760D01*
G01X161020Y135617D02*
Y134627D01*
G01X160985Y128523D02*
Y123011D01*
G01X160946Y147698D02*
Y152539D01*
G01Y133838D02*
Y138680D01*
G01X160754Y151553D02*
Y152538D01*
G01X160744Y133840D02*
Y134824D01*
G01X160670Y152539D02*
Y133838D01*
G01X160592Y135984D02*
Y129901D01*
G01Y156476D02*
Y150393D01*
G01X160399Y152539D02*
Y151555D01*
G01X160395Y152539D02*
Y151555D01*
G01X160390Y134822D02*
Y133838D01*
G01X160355Y136515D02*
Y132342D01*
G01Y154035D02*
Y149862D01*
G01X181940Y151368D02*
X181953Y150393D01*
G01X180975Y135009D02*
X180962Y135984D01*
G01X178008Y151368D02*
X178021Y150393D01*
G01X177033Y135009D02*
X177020Y135984D01*
G01X174066Y151368D02*
X174079Y150393D01*
G01X173101Y135009D02*
X173088Y135984D01*
G01X162260Y151368D02*
X162273Y150393D01*
G01X161285Y135009D02*
X161272Y135984D01*
G01X182468Y135117D02*
X182332Y141024D01*
G01X182327Y140138D02*
X182463Y134231D01*
G01X180588Y146239D02*
X180452Y152147D01*
G01X180447Y151260D02*
X180583Y145353D01*
G01X178526Y135117D02*
X178390Y141024D01*
G01X178385Y140138D02*
X178522Y134231D01*
G01X176656Y146239D02*
X176520Y152147D01*
G01X176515Y151260D02*
X176651Y145353D01*
G01X174594Y135117D02*
X174458Y141024D01*
G01X174453Y140138D02*
X174589Y134231D01*
G01X172714Y146239D02*
X172578Y152147D01*
G01X172573Y151260D02*
X172709Y145353D01*
G01X162778Y135117D02*
X162642Y141024D01*
G01X162637Y140138D02*
X162774Y134231D01*
G01X160908Y146239D02*
X160772Y152147D01*
G01X160767Y151260D02*
X160903Y145353D01*
G01X158846Y135117D02*
X158710Y141024D01*
G01X158705Y140138D02*
X158841Y134231D01*
G01X180662Y140340D02*
X180612Y141327D01*
G01X180610Y140365D02*
X180660Y139379D01*
G01X178373Y146012D02*
X178323Y146999D01*
G01X178321Y146037D02*
X178371Y145050D01*
G01X176721Y140340D02*
X176670Y141327D01*
G01X176668Y140365D02*
X176718Y139379D01*
G01X174432Y146012D02*
X174381Y146999D01*
G01X174379Y146037D02*
X174429Y145050D01*
G01X172788Y140340D02*
X172738Y141327D01*
G01X172736Y140365D02*
X172786Y139379D01*
G01X162625Y146012D02*
X162575Y146999D01*
G01X162573Y146037D02*
X162623Y145050D01*
G01X160973Y140340D02*
X160922Y141327D01*
G01X160920Y140365D02*
X160970Y139379D01*
G01X158684Y146012D02*
X158633Y146999D01*
G01X158631Y146037D02*
X158681Y145050D01*
G01X157040Y140340D02*
X156990Y141327D01*
G01X156988Y140365D02*
X157038Y139379D01*
G01X141569Y150393D02*
X141559Y150441D01*
G01X142606Y135984D02*
X142616Y135937D01*
G01X137627Y150441D02*
X137637Y150393D01*
G01X138674Y135937D02*
X138665Y135984D01*
G01X133695Y150393D02*
X133685Y150441D01*
G01X134732Y135984D02*
X134742Y135937D01*
G01X129753Y150441D02*
X129763Y150393D01*
G01X130800Y135937D02*
X130791Y135984D01*
G01X125821Y150393D02*
X125811Y150441D01*
G01X126858Y135984D02*
X126868Y135937D01*
G01X121879Y150441D02*
X121889Y150393D01*
G01X122926Y135937D02*
X122917Y135984D01*
G01X112232Y162854D02*
X112970Y160592D01*
G01X113380Y159252D02*
X113052Y160257D01*
G01X114420Y120493D02*
X114338Y120744D01*
G01X112560Y163189D02*
X113872Y159252D01*
G01X124509Y122252D02*
X124673Y121833D01*
G01X120818Y122252D02*
X120982Y121833D01*
G01X112616Y121247D02*
X112452Y121665D01*
G01X120572Y121833D02*
X120490Y122000D01*
G01X119259Y121833D02*
X119177Y122000D01*
G01X116881Y121079D02*
X116717Y121414D01*
G01X114748Y120744D02*
X114830Y120576D01*
G01X110319Y120493D02*
X110155Y120828D01*
G01X109663D02*
X109827Y120493D01*
G01X123525Y122084D02*
X123443Y122000D01*
G01X123279Y122168D02*
X123525Y122419D01*
G01X122212Y122084D02*
X122048Y121917D01*
G01Y122252D02*
X122212Y122419D01*
G01X119834Y122084D02*
X119752Y122000D01*
G01X119588Y122168D02*
X119834Y122419D01*
G01X118521Y122084D02*
X118357Y121917D01*
G01X116635Y120409D02*
X116799Y120576D01*
G01X118357Y122252D02*
X118521Y122419D01*
G01X116471Y122168D02*
X116635Y122335D01*
G01X114502Y123173D02*
X114830Y123508D01*
G01X157099Y134640D02*
X157353Y135009D01*
G01X157307Y135937D02*
X157088Y135617D01*
G01X153157Y134640D02*
X153411Y135009D01*
G01X153144Y135615D02*
X153366Y135937D01*
G01X162527Y150762D02*
X162306Y150441D01*
G01X162514Y151737D02*
X162260Y151368D01*
G01X149225Y134640D02*
X149479Y135009D01*
G01X149433Y135937D02*
X149214Y135617D01*
G01X158364Y150441D02*
X158584Y150760D01*
G01X158572Y151737D02*
X158318Y151368D01*
G01X145283Y134640D02*
X145537Y135009D01*
G01X145270Y135615D02*
X145492Y135937D01*
G01X154653Y150762D02*
X154432Y150441D01*
G01X154640Y151737D02*
X154386Y151368D01*
G01X141351Y134640D02*
X141605Y135009D01*
G01X141559Y135937D02*
X141340Y135617D01*
G01X150490Y150441D02*
X150710Y150760D01*
G01X150698Y151737D02*
X150444Y151368D01*
G01X137409Y134640D02*
X137663Y135009D01*
G01X137396Y135615D02*
X137618Y135937D01*
G01X146779Y150762D02*
X146558Y150441D01*
G01X146766Y151737D02*
X146512Y151368D01*
G01X133477Y134640D02*
X133731Y135009D01*
G01X133685Y135937D02*
X133466Y135617D01*
G01X142616Y150441D02*
X142836Y150760D01*
G01X142824Y151737D02*
X142570Y151368D01*
G01X129535Y134640D02*
X129789Y135009D01*
G01X129522Y135615D02*
X129744Y135937D01*
G01X166421Y148975D02*
X164933Y146732D01*
G01X161249Y135984D02*
X161240Y135937D01*
G01X162296Y150393D02*
X162306Y150441D01*
G01X157307Y135937D02*
X157317Y135984D01*
G01X158364Y150441D02*
X158354Y150393D01*
G01X153375Y135984D02*
X153366Y135937D01*
G01X154422Y150393D02*
X154432Y150441D01*
G01X149433Y135937D02*
X149443Y135984D01*
G01X150490Y150441D02*
X150480Y150393D01*
G01X145501Y135984D02*
X145492Y135937D01*
G01X146548Y150393D02*
X146558Y150441D01*
G01X141559Y135937D02*
X141569Y135984D01*
G01X160932Y145050D02*
X160982Y146037D01*
G01X160980Y146999D02*
X160929Y146012D01*
G01X158633Y139379D02*
X158684Y140365D01*
G01X158681Y141327D02*
X158631Y140340D01*
G01X156990Y145050D02*
X157040Y146037D01*
G01X157038Y146999D02*
X156988Y146012D01*
G01X154692Y139379D02*
X154742Y140365D01*
G01X154740Y141327D02*
X154689Y140340D01*
G01X153058Y145050D02*
X153108Y146037D01*
G01X153106Y146999D02*
X153055Y146012D01*
G01X150759Y139379D02*
X150810Y140365D01*
G01X150807Y141327D02*
X150757Y140340D01*
G01X149116Y145050D02*
X149166Y146037D01*
G01X149164Y146999D02*
X149114Y146012D01*
G01X146817Y139379D02*
X146868Y140365D01*
G01X146866Y141327D02*
X146815Y140340D01*
G01X145184Y145050D02*
X145234Y146037D01*
G01X145232Y146999D02*
X145181Y146012D01*
G01X142885Y139379D02*
X142936Y140365D01*
G01X142933Y141327D02*
X142883Y140340D01*
G01X141242Y145050D02*
X141292Y146037D01*
G01X141290Y146999D02*
X141239Y146012D01*
G01X138943Y139379D02*
X138994Y140365D01*
G01X138992Y141327D02*
X138941Y140340D01*
G01X158710Y145353D02*
X158846Y151260D01*
G01X158841Y152147D02*
X158705Y146239D01*
G01X156830Y134231D02*
X156966Y140138D01*
G01X156961Y141024D02*
X156825Y135117D01*
G01X154777Y145353D02*
X154914Y151260D01*
G01X154909Y152147D02*
X154773Y146239D01*
G01X152888Y134231D02*
X153025Y140138D01*
G01X153020Y141024D02*
X152884Y135117D01*
G01X150836Y145353D02*
X150972Y151260D01*
G01X150967Y152147D02*
X150831Y146239D01*
G01X148956Y134231D02*
X149092Y140138D01*
G01X149087Y141024D02*
X148951Y135117D01*
G01X146903Y145353D02*
X147040Y151260D01*
G01X147035Y152147D02*
X146899Y146239D01*
G01X145014Y134231D02*
X145151Y140138D01*
G01X145146Y141024D02*
X145009Y135117D01*
G01X142962Y145353D02*
X143098Y151260D01*
G01X143093Y152147D02*
X142957Y146239D01*
G01X141082Y134231D02*
X141218Y140138D01*
G01X141213Y141024D02*
X141077Y135117D01*
G01X139029Y145353D02*
X139166Y151260D01*
G01X139161Y152147D02*
X139025Y146239D01*
G01X137140Y134231D02*
X137276Y140138D01*
G01X137272Y141024D02*
X137135Y135117D01*
G01X158331Y135984D02*
X158318Y135009D01*
G01X157340Y150393D02*
X157353Y151368D01*
G01X154390Y135984D02*
X154377Y135009D01*
G01X153407Y150393D02*
X153421Y151368D01*
G01X150457Y135984D02*
X150444Y135009D01*
G01X149466Y150393D02*
X149479Y151368D01*
G01X146516Y135984D02*
X146503Y135009D01*
G01X145533Y150393D02*
X145547Y151368D01*
G01X142583Y135984D02*
X142570Y135009D01*
G01X141592Y150393D02*
X141605Y151368D01*
G01X138642Y135984D02*
X138629Y135009D01*
G01X137659Y150393D02*
X137673Y151368D01*
G01X159253Y149862D02*
Y154035D01*
G01Y132342D02*
Y136515D01*
G01X159218Y134822D02*
Y133838D01*
G01X159214Y134822D02*
Y133838D01*
G01Y152539D02*
Y151555D01*
G01X159017Y135984D02*
Y129901D01*
G01Y156476D02*
Y150393D01*
G01X158938Y133838D02*
Y152539D01*
G01X158859Y134824D02*
Y133840D01*
G01Y152538D02*
Y151553D01*
G01X158662Y151555D02*
Y156396D01*
G01Y129981D02*
Y134822D01*
G01X158584Y150760D02*
Y151750D01*
G01Y134627D02*
Y135617D01*
G01X158505Y130965D02*
Y129901D01*
G01Y156476D02*
Y155412D01*
G01X158229Y129901D02*
Y130885D01*
G01Y156476D02*
Y155492D01*
G01X157836Y128523D02*
Y123011D01*
G01X157442Y130885D02*
Y129901D01*
G01Y156476D02*
Y155492D01*
G01X157166Y130965D02*
Y129901D01*
G01Y156476D02*
Y155412D01*
G01X157088Y135617D02*
Y134627D01*
G01Y151750D02*
Y150760D01*
G01X157009Y151555D02*
Y156396D01*
G01Y129981D02*
Y134822D01*
G01X156812Y151553D02*
Y152538D01*
G01Y133840D02*
Y134824D01*
G01X156733Y152539D02*
Y133838D01*
G01X156655Y135984D02*
Y129901D01*
G01Y156476D02*
Y150393D01*
G01X156458Y134822D02*
Y133838D01*
G01Y152539D02*
Y151555D01*
G01X156453Y152539D02*
Y151555D01*
G01X156418Y136515D02*
Y132342D01*
G01Y154035D02*
Y149862D01*
G01X155316D02*
Y154035D01*
G01Y132342D02*
Y136515D01*
G01X155281Y152539D02*
Y151555D01*
G01X155277Y134822D02*
Y133838D01*
G01X155272Y134822D02*
Y133838D01*
G01X155080Y135984D02*
Y129901D01*
G01Y156476D02*
Y150393D01*
G01X155001Y133838D02*
Y152539D01*
G01X154927Y152538D02*
Y151553D01*
G01X154918Y134824D02*
Y133840D01*
G01X154725Y147698D02*
Y152539D01*
G01Y133838D02*
Y138680D01*
G01X154651Y150760D02*
Y151750D01*
G01X154642Y134627D02*
Y135617D01*
G01X154568Y138760D02*
Y137696D01*
G01Y148681D02*
Y147618D01*
G01X154292D02*
Y148602D01*
G01Y138760D02*
Y137775D01*
G01X153899Y128523D02*
Y123011D01*
G01X153505Y138760D02*
Y137775D01*
G01Y148602D02*
Y147618D01*
G01X153229Y138760D02*
Y137696D01*
G01Y148681D02*
Y147618D01*
G01X153155Y151750D02*
Y150760D01*
G01X153146Y135617D02*
Y134627D01*
G01X153072Y147698D02*
Y152539D01*
G01Y133838D02*
Y138680D01*
G01X152880Y151553D02*
Y152538D01*
G01X152870Y133840D02*
Y134824D01*
G01X152796Y152539D02*
Y133838D01*
G01X152717Y135984D02*
Y129901D01*
G01Y156476D02*
Y150393D01*
G01X152525Y152539D02*
Y151555D01*
G01X152521Y152539D02*
Y151555D01*
G01X152516Y134822D02*
Y133838D01*
G01X152481Y136515D02*
Y132342D01*
G01Y154035D02*
Y149862D01*
G01X151379D02*
Y154035D01*
G01Y132342D02*
Y136515D01*
G01X151344Y134822D02*
Y133838D01*
G01X151340Y134822D02*
Y133838D01*
G01Y152539D02*
Y151555D01*
G01X151143Y135984D02*
Y129901D01*
G01Y156476D02*
Y150393D01*
G01X151064Y133838D02*
Y152539D01*
G01X150985Y134824D02*
Y133840D01*
G01Y152538D02*
Y151553D01*
G01X150788Y151555D02*
Y156396D01*
G01Y129981D02*
Y134822D01*
G01X150749Y128523D02*
Y123011D01*
G01X150710Y150760D02*
Y151750D01*
G01Y134627D02*
Y135617D01*
G01X150631Y130965D02*
Y129901D01*
G01Y156476D02*
Y155412D01*
G01X150355Y129901D02*
Y130885D01*
G01Y156476D02*
Y155492D01*
G01X149568Y130885D02*
Y129901D01*
G01Y156476D02*
Y155492D01*
G01X149292Y130965D02*
Y129901D01*
G01Y156476D02*
Y155412D01*
G01X149214Y135617D02*
Y134627D01*
G01Y151750D02*
Y150760D01*
G01X149135Y151555D02*
Y156396D01*
G01Y129981D02*
Y134822D01*
G01X148938Y151553D02*
Y152538D01*
G01Y133840D02*
Y134824D01*
G01X148859Y152539D02*
Y133838D01*
G01X148780Y135984D02*
Y129901D01*
G01Y156476D02*
Y150393D01*
G01X148584Y134822D02*
Y133838D01*
G01Y152539D02*
Y151555D01*
G01X148579Y152539D02*
Y151555D01*
G01X148544Y136515D02*
Y132342D01*
G01Y154035D02*
Y149862D01*
G01X147442D02*
Y154035D01*
G01Y132342D02*
Y136515D01*
G01X147407Y152539D02*
Y151555D01*
G01X147403Y134822D02*
Y133838D01*
G01X147398Y134822D02*
Y133838D01*
G01X147206Y135984D02*
Y129901D01*
G01Y156476D02*
Y150393D01*
G01X147127Y133838D02*
Y152539D01*
G01X147053Y152538D02*
Y151553D01*
G01X147044Y134824D02*
Y133840D01*
G01X146851Y147698D02*
Y152539D01*
G01Y133838D02*
Y138680D01*
G01X146777Y150760D02*
Y151750D01*
G01X146768Y134627D02*
Y135617D01*
G01X146694Y138760D02*
Y137696D01*
G01Y148681D02*
Y147618D01*
G01X146418D02*
Y148602D01*
G01Y138760D02*
Y137775D01*
G01X145631Y138760D02*
Y137775D01*
G01Y148602D02*
Y147618D01*
G01X145355Y138760D02*
Y137696D01*
G01Y148681D02*
Y147618D01*
G01X145281Y151750D02*
Y150760D01*
G01X145272Y135617D02*
Y134627D01*
G01X145198Y147698D02*
Y152539D01*
G01Y133838D02*
Y138680D01*
G01X145006Y151553D02*
Y152538D01*
G01X144996Y133840D02*
Y134824D01*
G01X144922Y152539D02*
Y133838D01*
G01X144843Y135984D02*
Y129901D01*
G01Y156476D02*
Y150393D01*
G01X144651Y152539D02*
Y151555D01*
G01X144647Y152539D02*
Y151555D01*
G01X144642Y134822D02*
Y133838D01*
G01X144607Y136515D02*
Y132342D01*
G01Y154035D02*
Y149862D01*
G01X143505D02*
Y154035D01*
G01Y132342D02*
Y136515D01*
G01X143470Y134822D02*
Y133838D01*
G01X143466Y134822D02*
Y133838D01*
G01Y152539D02*
Y151555D01*
G01X143269Y135984D02*
Y129901D01*
G01Y156476D02*
Y150393D01*
G01X143190Y133838D02*
Y152539D01*
G01X143111Y134824D02*
Y133840D01*
G01Y152538D02*
Y151553D01*
G01X142914Y151555D02*
Y156396D01*
G01Y129981D02*
Y134822D01*
G01X142836Y150760D02*
Y151750D01*
G01Y134627D02*
Y135617D01*
G01X142757Y130965D02*
Y129901D01*
G01Y156476D02*
Y155412D01*
G01X142481Y129901D02*
Y130885D01*
G01Y156476D02*
Y155492D01*
G01X141694Y130885D02*
Y129901D01*
G01Y156476D02*
Y155492D01*
G01X141418Y130965D02*
Y129901D01*
G01Y156476D02*
Y155412D01*
G01X141340Y135617D02*
Y134627D01*
G01Y151750D02*
Y150760D01*
G01X141261Y151555D02*
Y156396D01*
G01Y129981D02*
Y134822D01*
G01X141064Y133840D02*
Y134824D01*
G01Y151553D02*
Y152538D01*
G01X140985Y152539D02*
Y133838D01*
G01X140906Y135984D02*
Y129901D01*
G01Y156476D02*
Y150393D01*
G01X140710Y134822D02*
Y133838D01*
G01Y152539D02*
Y151555D01*
G01X140705Y152539D02*
Y151555D01*
G01X140670Y136515D02*
Y132342D01*
G01Y154035D02*
Y149862D01*
G01X139568D02*
Y154035D01*
G01Y132342D02*
Y136515D01*
G01X139533Y152539D02*
Y151555D01*
G01X139529Y134822D02*
Y133838D01*
G01X139524Y134822D02*
Y133838D01*
G01X139332Y135984D02*
Y129901D01*
G01Y156476D02*
Y150393D01*
G01X139253Y133838D02*
Y152539D01*
G01X139179Y152538D02*
Y151553D01*
G01X139170Y134824D02*
Y133840D01*
G01X138977Y147698D02*
Y152539D01*
G01Y133838D02*
Y138680D01*
G01X138903Y150760D02*
Y151750D01*
G01X138894Y134627D02*
Y135617D01*
G01X138820Y138760D02*
Y137696D01*
G01Y148681D02*
Y147618D01*
G01X138544D02*
Y148602D01*
G01Y138760D02*
Y137775D01*
G01X137757Y147618D02*
Y148602D01*
G01Y138760D02*
Y137775D01*
G01X137481Y138760D02*
Y137696D01*
G01Y148681D02*
Y147618D01*
G01X137407Y151750D02*
Y150760D01*
G01X137398Y135617D02*
Y134627D01*
G01X137363Y128523D02*
Y123011D01*
G01X137324Y147698D02*
Y152539D01*
G01Y133838D02*
Y138680D01*
G01X137132Y151553D02*
Y152538D01*
G01X137122Y133840D02*
Y134824D01*
G01X137048Y152539D02*
Y133838D01*
G01X136969Y135984D02*
Y129901D01*
G01Y156476D02*
Y150393D01*
G01X136777Y152539D02*
Y151555D01*
G01X136773Y152539D02*
Y151555D01*
G01X136768Y134822D02*
Y133838D01*
G01X136733Y136515D02*
Y132342D01*
G01Y154035D02*
Y149862D01*
G01X135631D02*
Y154035D01*
G01Y132342D02*
Y136515D01*
G01X135596Y134822D02*
Y133838D01*
G01X135592Y134822D02*
Y133838D01*
G01Y152539D02*
Y151555D01*
G01X135395Y135984D02*
Y129901D01*
G01Y156476D02*
Y150393D01*
G01X135316Y133838D02*
Y152539D01*
G01X135237Y134824D02*
Y133840D01*
G01Y152538D02*
Y151553D01*
G01X135040Y151555D02*
Y156396D01*
G01Y129981D02*
Y134822D01*
G01X134962Y150760D02*
Y151750D01*
G01Y134627D02*
Y135617D01*
G01X134883Y130965D02*
Y129901D01*
G01Y156476D02*
Y155412D01*
G01X158318Y151368D02*
X158331Y150393D01*
G01X157353Y135009D02*
X157340Y135984D01*
G01X154386Y151368D02*
X154399Y150393D01*
G01X153411Y135009D02*
X153398Y135984D01*
G01X150444Y151368D02*
X150457Y150393D01*
G01X149479Y135009D02*
X149466Y135984D01*
G01X146512Y151368D02*
X146525Y150393D01*
G01X145537Y135009D02*
X145524Y135984D01*
G01X142570Y151368D02*
X142583Y150393D01*
G01X141605Y135009D02*
X141592Y135984D01*
G01X138638Y151368D02*
X138651Y150393D01*
G01X137663Y135009D02*
X137650Y135984D01*
G01X134696Y151368D02*
X134709Y150393D01*
G01X156966Y146239D02*
X156830Y152147D01*
G01X156825Y151260D02*
X156961Y145353D01*
G01X154904Y135117D02*
X154768Y141024D01*
G01X154763Y140138D02*
X154900Y134231D01*
G01X153034Y146239D02*
X152898Y152147D01*
G01X152893Y151260D02*
X153029Y145353D01*
G01X150972Y135117D02*
X150836Y141024D01*
G01X150831Y140138D02*
X150967Y134231D01*
G01X149092Y146239D02*
X148956Y152147D01*
G01X148951Y151260D02*
X149087Y145353D01*
G01X147030Y135117D02*
X146894Y141024D01*
G01X146889Y140138D02*
X147026Y134231D01*
G01X145160Y146239D02*
X145024Y152147D01*
G01X145019Y151260D02*
X145155Y145353D01*
G01X143098Y135117D02*
X142962Y141024D01*
G01X142957Y140138D02*
X143093Y134231D01*
G01X141218Y146239D02*
X141082Y152147D01*
G01X141077Y151260D02*
X141213Y145353D01*
G01X139156Y135117D02*
X139020Y141024D01*
G01X139015Y140138D02*
X139152Y134231D01*
G01X137286Y146239D02*
X137150Y152147D01*
G01X137145Y151260D02*
X137281Y145353D01*
G01X135224Y135117D02*
X135088Y141024D01*
G01X135083Y140138D02*
X135219Y134231D01*
G01X154751Y146012D02*
X154701Y146999D01*
G01X154699Y146037D02*
X154749Y145050D01*
G01X153099Y140340D02*
X153048Y141327D01*
G01X153046Y140365D02*
X153096Y139379D01*
G01X150810Y146012D02*
X150759Y146999D01*
G01X150757Y146037D02*
X150807Y145050D01*
G01X149166Y140340D02*
X149116Y141327D01*
G01X149114Y140365D02*
X149164Y139379D01*
G01X146877Y146012D02*
X146827Y146999D01*
G01X146825Y146037D02*
X146875Y145050D01*
G01X145225Y140340D02*
X145174Y141327D01*
G01X145172Y140365D02*
X145222Y139379D01*
G01X142936Y146012D02*
X142885Y146999D01*
G01X142883Y146037D02*
X142933Y145050D01*
G01X141292Y140340D02*
X141242Y141327D01*
G01X141239Y140365D02*
X141290Y139379D01*
G01X139003Y146012D02*
X138953Y146999D01*
G01X138950Y146037D02*
X139001Y145050D01*
G01X137351Y140340D02*
X137300Y141327D01*
G01X137298Y140365D02*
X137348Y139379D01*
G01X135062Y146012D02*
X135011Y146999D01*
G01X135009Y146037D02*
X135059Y145050D01*
G01X133418Y140340D02*
X133368Y141327D01*
G01X133365Y140365D02*
X133416Y139379D01*
G01X117127Y123173D02*
X117209Y122838D01*
G01Y121414D02*
X117291Y121079D01*
G01X112124Y121414D02*
X112206Y121163D01*
G01X115021Y162519D02*
X114529Y161932D01*
G01Y162602D02*
X115021Y163189D01*
G01X112206Y120158D02*
X112452Y120493D01*
G01X138905Y150762D02*
X138684Y150441D01*
G01X138892Y151737D02*
X138638Y151368D01*
G01X125603Y134640D02*
X125857Y135009D01*
G01X125811Y135937D02*
X125592Y135617D01*
G01X134742Y150441D02*
X134962Y150760D01*
G01X134950Y151737D02*
X134696Y151368D01*
G01X121661Y134640D02*
X121915Y135009D01*
G01X121648Y135615D02*
X121870Y135937D01*
G01X131031Y150762D02*
X130810Y150441D01*
G01X131018Y151737D02*
X130764Y151368D01*
G01X126868Y150441D02*
X127088Y150760D01*
G01X127076Y151737D02*
X126822Y151368D01*
G01X123157Y150762D02*
X122935Y150441D01*
G01X123144Y151737D02*
X122890Y151368D01*
G01X116958Y139645D02*
X115001Y136693D01*
G01X117209Y120493D02*
X117045Y120241D01*
G01X117127Y122335D02*
X116963Y122084D01*
G01X114994Y123089D02*
X114830Y122838D01*
G01X112124Y120744D02*
X111960Y120493D01*
G01X109007Y121247D02*
X108843Y120995D01*
G01X123443Y122000D02*
X123361Y121833D01*
G01X119752Y122000D02*
X119670Y121833D01*
G01X116799Y120576D02*
X116881Y120744D01*
G01X116635Y122335D02*
X116799Y122671D01*
G01X112452Y120493D02*
X112616Y120911D01*
G01X117291Y120744D02*
X117209Y120493D01*
G01X112206Y120995D02*
X112124Y120744D01*
G01X117209Y122671D02*
X117127Y122335D01*
G01X114420Y122838D02*
X114502Y123173D01*
G01X142616Y150441D02*
X142606Y150393D01*
G01X137627Y135984D02*
X137618Y135937D01*
G01X138674Y150393D02*
X138684Y150441D01*
G01X133685Y135937D02*
X133695Y135984D01*
G01X134742Y150441D02*
X134732Y150393D01*
G01X129753Y135984D02*
X129744Y135937D01*
G01X130800Y150393D02*
X130810Y150441D01*
G01X125811Y135937D02*
X125821Y135984D01*
G01X126868Y150441D02*
X126858Y150393D01*
G01X121879Y135984D02*
X121870Y135937D01*
G01X122926Y150393D02*
X122935Y150441D01*
G01X137309Y145050D02*
X137360Y146037D01*
G01X137358Y146999D02*
X137307Y146012D01*
G01X135011Y139379D02*
X135062Y140365D01*
G01X135059Y141327D02*
X135009Y140340D01*
G01X133368Y145050D02*
X133418Y146037D01*
G01X133416Y146999D02*
X133365Y146012D01*
G01X131069Y139379D02*
X131120Y140365D01*
G01X131118Y141327D02*
X131067Y140340D01*
G01X129435Y145050D02*
X129486Y146037D01*
G01X129484Y146999D02*
X129433Y146012D01*
G01X127137Y139379D02*
X127188Y140365D01*
G01X127185Y141327D02*
X127135Y140340D01*
G01X125494Y145050D02*
X125544Y146037D01*
G01X125542Y146999D02*
X125491Y146012D01*
G01X123195Y139379D02*
X123246Y140365D01*
G01X123244Y141327D02*
X123193Y140340D01*
G01X121561Y145050D02*
X121612Y146037D01*
G01X121610Y146999D02*
X121559Y146012D01*
G01X135088Y145353D02*
X135224Y151260D01*
G01X135219Y152147D02*
X135083Y146239D01*
G01X133208Y134231D02*
X133344Y140138D01*
G01X133339Y141024D02*
X133203Y135117D01*
G01X131155Y145353D02*
X131292Y151260D01*
G01X131287Y152147D02*
X131151Y146239D01*
G01X129266Y134231D02*
X129402Y140138D01*
G01X129398Y141024D02*
X129261Y135117D01*
G01X127214Y145353D02*
X127350Y151260D01*
G01X127345Y152147D02*
X127209Y146239D01*
G01X125334Y134231D02*
X125470Y140138D01*
G01X125465Y141024D02*
X125329Y135117D01*
G01X123281Y145353D02*
X123418Y151260D01*
G01X123413Y152147D02*
X123277Y146239D01*
G01X121392Y134231D02*
X121528Y140138D01*
G01X121524Y141024D02*
X121387Y135117D01*
G01X134709Y135984D02*
X134696Y135009D01*
G01X133718Y150393D02*
X133731Y151368D01*
G01X130768Y135984D02*
X130755Y135009D01*
G01X129785Y150393D02*
X129799Y151368D01*
G01X126835Y135984D02*
X126822Y135009D01*
G01X125844Y150393D02*
X125857Y151368D01*
G01X122894Y135984D02*
X122881Y135009D01*
G01X121911Y150393D02*
X121925Y151368D01*
G01X134607Y129901D02*
Y130885D01*
G01Y156476D02*
Y155492D01*
G01X134214Y128523D02*
Y123011D01*
G01X133820Y130885D02*
Y129901D01*
G01Y156476D02*
Y155492D01*
G01X133544Y130965D02*
Y129901D01*
G01Y156476D02*
Y155412D01*
G01X133466Y135617D02*
Y134627D01*
G01Y151750D02*
Y150760D01*
G01X133387Y151555D02*
Y156396D01*
G01Y129981D02*
Y134822D01*
G01X133190Y151553D02*
Y152538D01*
G01Y133840D02*
Y134824D01*
G01X133111Y152539D02*
Y133838D01*
G01X133032Y135984D02*
Y129901D01*
G01Y156476D02*
Y150393D01*
G01X132836Y134822D02*
Y133838D01*
G01Y152539D02*
Y151555D01*
G01X132831Y152539D02*
Y151555D01*
G01X132796Y136515D02*
Y132342D01*
G01Y154035D02*
Y149862D01*
G01X131694D02*
Y154035D01*
G01Y132342D02*
Y136515D01*
G01X131659Y152539D02*
Y151555D01*
G01X131655Y134822D02*
Y133838D01*
G01X131650Y134822D02*
Y133838D01*
G01X131458Y135984D02*
Y129901D01*
G01Y156476D02*
Y150393D01*
G01X131379Y133838D02*
Y152539D01*
G01X131305Y152538D02*
Y151553D01*
G01X131296Y134824D02*
Y133840D01*
G01X131103Y147698D02*
Y152539D01*
G01Y133838D02*
Y138680D01*
G01X131029Y150760D02*
Y151750D01*
G01X131020Y134627D02*
Y135617D01*
G01X130946Y138760D02*
Y137696D01*
G01Y148681D02*
Y147618D01*
G01X130670D02*
Y148602D01*
G01Y138760D02*
Y137775D01*
G01X130277Y128523D02*
Y123011D01*
G01X129883Y147618D02*
Y148602D01*
G01Y138760D02*
Y137775D01*
G01X129607Y138760D02*
Y137696D01*
G01Y148681D02*
Y147618D01*
G01X129533Y151750D02*
Y150760D01*
G01X129524Y135617D02*
Y134627D01*
G01X129450Y147698D02*
Y152539D01*
G01Y133838D02*
Y138680D01*
G01X129258Y151553D02*
Y152538D01*
G01X129248Y133840D02*
Y134824D01*
G01X129174Y152539D02*
Y133838D01*
G01X129095Y135984D02*
Y129901D01*
G01Y156476D02*
Y150393D01*
G01X128903Y152539D02*
Y151555D01*
G01X128899Y152539D02*
Y151555D01*
G01X128894Y134822D02*
Y133838D01*
G01X128859Y136515D02*
Y132342D01*
G01Y154035D02*
Y149862D01*
G01X127757D02*
Y154035D01*
G01Y132342D02*
Y136515D01*
G01X127722Y134822D02*
Y133838D01*
G01X127717Y134822D02*
Y133838D01*
G01Y152539D02*
Y151555D01*
G01X127521Y135984D02*
Y129901D01*
G01Y156476D02*
Y150393D01*
G01X127442Y133838D02*
Y152539D01*
G01X127363Y134824D02*
Y133840D01*
G01Y152538D02*
Y151553D01*
G01X127166Y151555D02*
Y156396D01*
G01Y129981D02*
Y134822D01*
G01X127127Y128523D02*
Y123011D01*
G01X127088Y150760D02*
Y151750D01*
G01Y134627D02*
Y135617D01*
G01X127009Y130965D02*
Y129901D01*
G01Y156476D02*
Y155412D01*
G01X126733Y129901D02*
Y130885D01*
G01Y156476D02*
Y155492D01*
G01X125946Y130885D02*
Y129901D01*
G01Y156476D02*
Y155492D01*
G01X125670Y130965D02*
Y129901D01*
G01Y156476D02*
Y155412D01*
G01X125592Y135617D02*
Y134627D01*
G01Y151750D02*
Y150760D01*
G01X125513Y151555D02*
Y156396D01*
G01Y129981D02*
Y134822D01*
G01X125316Y151553D02*
Y152538D01*
G01Y133840D02*
Y134824D01*
G01X125237Y152539D02*
Y133838D01*
G01X125158Y135984D02*
Y129901D01*
G01Y156476D02*
Y150393D01*
G01X124962Y134822D02*
Y133838D01*
G01Y152539D02*
Y151555D01*
G01X124957Y152539D02*
Y151555D01*
G01X124922Y136515D02*
Y132342D01*
G01Y154035D02*
Y149862D01*
G01X124673Y121833D02*
Y119822D01*
G01X124263D02*
Y121833D01*
G01X123820Y149862D02*
Y154035D01*
G01Y132342D02*
Y136515D01*
G01X123785Y152539D02*
Y151555D01*
G01X123780Y134822D02*
Y133838D01*
G01X123776Y134822D02*
Y133838D01*
G01X123584Y135984D02*
Y129901D01*
G01Y156476D02*
Y150393D01*
G01X123505Y133838D02*
Y152539D01*
G01X123431Y152538D02*
Y151553D01*
G01X123421Y134824D02*
Y133840D01*
G01X123361Y121833D02*
Y119822D01*
G01X123229Y147698D02*
Y152539D01*
G01Y133838D02*
Y138680D01*
G01X123155Y150760D02*
Y151750D01*
G01X123146Y134627D02*
Y135617D01*
G01X123072Y138760D02*
Y137696D01*
G01Y148681D02*
Y147618D01*
G01X122950Y119822D02*
Y121833D01*
G01X122796Y147618D02*
Y148602D01*
G01Y138760D02*
Y137775D01*
G01X122048Y121917D02*
Y119822D01*
G01Y122503D02*
Y122252D01*
G01X122009Y138760D02*
Y137775D01*
G01Y148602D02*
Y147618D01*
G01X121733Y138760D02*
Y137696D01*
G01Y148681D02*
Y147618D01*
G01X121659Y151750D02*
Y150760D01*
G01X121650Y135617D02*
Y134627D01*
G01X121638Y119822D02*
Y122503D01*
G01X121576Y147698D02*
Y152539D01*
G01Y133838D02*
Y138680D01*
G01X121384Y151553D02*
Y152538D01*
G01X121374Y133840D02*
Y134824D01*
G01X121300Y152539D02*
Y133838D01*
G01X121221Y135984D02*
Y129901D01*
G01Y156476D02*
Y150393D01*
G01X121029Y152539D02*
Y151555D01*
G01X121025Y152539D02*
Y151555D01*
G01X121020Y134822D02*
Y133838D01*
G01X120985Y136515D02*
Y132342D01*
G01Y154035D02*
Y149862D01*
G01X120982Y121833D02*
Y119822D01*
G01X120572D02*
Y121833D01*
G01X119670D02*
Y119822D01*
G01X119259D02*
Y121833D01*
G01X118406Y146732D02*
Y139645D01*
G01X118357Y121917D02*
Y119822D01*
G01Y122503D02*
Y122252D01*
G01X117947Y119822D02*
Y122503D01*
G01X117856Y157854D02*
Y154735D01*
G01X117291Y121079D02*
Y120744D01*
G01X117209Y122838D02*
Y122671D01*
G01X116881Y120744D02*
Y121079D01*
G01X116799Y122671D02*
Y122838D01*
G01X116497Y139252D02*
Y147126D01*
G01X116241Y136988D02*
Y131082D01*
G01Y155295D02*
Y149389D01*
G01X115651Y121665D02*
Y122000D01*
G01X115513Y163189D02*
Y159252D01*
G01X115021D02*
Y162519D01*
G01X115001Y149685D02*
Y136693D01*
G01X114529Y161932D02*
Y162602D01*
G01X114270Y157854D02*
Y154735D01*
G01X113741Y128523D02*
Y123011D01*
G01X113682Y120241D02*
Y119822D01*
G01X113272D02*
Y120241D01*
G01X112616Y120911D02*
Y121247D01*
G01X112560Y147126D02*
Y139252D01*
G01X112452Y123341D02*
Y123760D01*
G01X112206Y121163D02*
Y120995D01*
G01X111517Y136988D02*
Y131082D01*
G01Y155295D02*
Y149389D01*
G01X110592Y123011D02*
Y157854D01*
G01X133731Y135009D02*
X133718Y135984D01*
G01X130764Y151368D02*
X130777Y150393D01*
G01X129789Y135009D02*
X129776Y135984D01*
G01X126822Y151368D02*
X126835Y150393D01*
G01X125857Y135009D02*
X125844Y135984D01*
G01X122890Y151368D02*
X122903Y150393D01*
G01X121915Y135009D02*
X121902Y135984D01*
G01X133344Y146239D02*
X133208Y152147D01*
G01X133203Y151260D02*
X133339Y145353D01*
G01X131282Y135117D02*
X131146Y141024D01*
G01X131141Y140138D02*
X131278Y134231D01*
G01X129412Y146239D02*
X129276Y152147D01*
G01X129271Y151260D02*
X129407Y145353D01*
G01X127350Y135117D02*
X127214Y141024D01*
G01X127209Y140138D02*
X127345Y134231D01*
G01X125470Y146239D02*
X125334Y152147D01*
G01X125329Y151260D02*
X125465Y145353D01*
G01X123408Y135117D02*
X123272Y141024D01*
G01X123267Y140138D02*
X123403Y134231D01*
G01X121538Y146239D02*
X121402Y152147D01*
G01X121397Y151260D02*
X121533Y145353D01*
G01X131129Y146012D02*
X131079Y146999D01*
G01X131076Y146037D02*
X131127Y145050D01*
G01X129477Y140340D02*
X129426Y141327D01*
G01X129424Y140365D02*
X129474Y139379D01*
G01X127188Y146012D02*
X127137Y146999D01*
G01X127135Y146037D02*
X127185Y145050D01*
G01X125544Y140340D02*
X125494Y141327D01*
G01X125491Y140365D02*
X125542Y139379D01*
G01X123255Y146012D02*
X123205Y146999D01*
G01X123202Y146037D02*
X123253Y145050D01*
G01X121603Y140340D02*
X121552Y141327D01*
G01X121550Y140365D02*
X121600Y139379D01*
G01X110592Y159252D02*
X111904Y163189D01*
G01X111412Y160257D02*
X111084Y159252D01*
G01X111494Y160592D02*
X112232Y162854D01*
G01X110073Y122000D02*
Y123341D01*
G01X109663Y123760D02*
Y121582D01*
G01X172725Y225965D02*
X172736Y226012D01*
G01X172719Y226063D02*
X172725Y225965D01*
G01X172714Y226239D02*
X172719Y226063D01*
G01X172810Y228861D02*
X172812Y229826D01*
G01X172808Y228414D02*
X172810Y228861D01*
G01X172804Y228009D02*
X172808Y228414D01*
G01X172801Y227656D02*
X172804Y228009D01*
G01X172796Y227364D02*
X172801Y227656D01*
G01X172791Y227143D02*
X172796Y227364D01*
G01X172786Y226999D02*
X172791Y227143D01*
G01X172820Y228520D02*
X172823Y229807D01*
G01X172817Y227925D02*
X172820Y228520D01*
G01X172813Y227384D02*
X172817Y227925D01*
G01X172808Y226913D02*
X172813Y227384D01*
G01X172802Y226524D02*
X172808Y226913D01*
G01X172795Y226230D02*
X172802Y226524D01*
G01X172788Y226037D02*
X172795Y226230D01*
G01X172723Y224988D02*
X172738Y225050D01*
G01X172716Y225118D02*
X172723Y224988D01*
G01X172709Y225353D02*
X172716Y225118D01*
G01X174444Y224988D02*
X174458Y225353D01*
G01X174437Y224965D02*
X174444Y224988D01*
G01X174429Y225050D02*
X174437Y224965D01*
G01X174365Y226524D02*
X174379Y226037D01*
G01X174359Y226913D02*
X174365Y226524D01*
G01X174354Y227384D02*
X174359Y226913D01*
G01X174350Y227925D02*
X174354Y227384D01*
G01X174347Y228520D02*
X174350Y227925D01*
G01X174345Y229153D02*
X174347Y228520D01*
G01X174344Y229807D02*
X174345Y229153D01*
G01X174371Y227364D02*
X174381Y226999D01*
G01X174367Y227656D02*
X174371Y227364D01*
G01X174363Y228009D02*
X174367Y227656D01*
G01X174360Y228414D02*
X174363Y228009D01*
G01X174357Y228861D02*
X174360Y228414D01*
G01X174356Y229336D02*
X174357Y228861D01*
G01X174355Y229826D02*
X174356Y229336D01*
G01X174443Y225965D02*
X174453Y226239D01*
G01X174437Y225948D02*
X174443Y225965D01*
G01X174432Y226012D02*
X174437Y225948D01*
G01X174443Y220412D02*
X174432Y220365D01*
G01X174448Y220314D02*
X174443Y220412D01*
G01X174453Y220138D02*
X174448Y220314D01*
G01X174357Y217516D02*
X174355Y216551D01*
G01X174360Y217963D02*
X174357Y217516D01*
G01X174363Y218368D02*
X174360Y217963D01*
G01X174367Y218722D02*
X174363Y218368D01*
G01X174371Y219013D02*
X174367Y218722D01*
G01X174376Y219234D02*
X174371Y219013D01*
G01X174381Y219379D02*
X174376Y219234D01*
G01X174347Y217857D02*
X174344Y216570D01*
G01X174350Y218453D02*
X174347Y217857D01*
G01X174354Y218993D02*
X174350Y218453D01*
G01X174359Y219464D02*
X174354Y218993D01*
G01X174365Y219853D02*
X174359Y219464D01*
G01X174372Y220148D02*
X174365Y219853D01*
G01X174379Y220340D02*
X174372Y220148D01*
G01X174444Y221390D02*
X174429Y221327D01*
G01X174451Y221259D02*
X174444Y221390D01*
G01X174458Y221024D02*
X174451Y221259D01*
G01X172723Y221390D02*
X172709Y221024D01*
G01X172731Y221412D02*
X172723Y221390D01*
G01X172738Y221327D02*
X172731Y221412D01*
G01X172802Y219853D02*
X172788Y220340D01*
G01X172808Y219464D02*
X172802Y219853D01*
G01X172813Y218993D02*
X172808Y219464D01*
G01X172817Y218453D02*
X172813Y218993D01*
G01X172820Y217857D02*
X172817Y218453D01*
G01X172822Y217224D02*
X172820Y217857D01*
G01X172823Y216570D02*
X172822Y217224D01*
G01X172796Y219013D02*
X172786Y219379D01*
G01X172801Y218722D02*
X172796Y219013D01*
G01X172804Y218368D02*
X172801Y218722D01*
G01X172808Y217963D02*
X172804Y218368D01*
G01X172810Y217516D02*
X172808Y217963D01*
G01X172811Y217041D02*
X172810Y217516D01*
G01X172812Y216551D02*
X172811Y217041D01*
G01X172725Y220412D02*
X172714Y220138D01*
G01X172730Y220429D02*
X172725Y220412D01*
G01X172736Y220365D02*
X172730Y220429D01*
G01X135073Y220412D02*
X135062Y220365D01*
G01X135078Y220314D02*
X135073Y220412D01*
G01X135083Y220138D02*
X135078Y220314D01*
G01X134987Y217516D02*
X134985Y216551D01*
G01X134990Y217963D02*
X134987Y217516D01*
G01X134993Y218368D02*
X134990Y217963D01*
G01X134997Y218722D02*
X134993Y218368D01*
G01X135001Y219013D02*
X134997Y218722D01*
G01X135006Y219234D02*
X135001Y219013D01*
G01X135011Y219379D02*
X135006Y219234D01*
G01X134977Y217857D02*
X134974Y216570D01*
G01X134980Y218453D02*
X134977Y217857D01*
G01X134984Y218993D02*
X134980Y218453D01*
G01X134989Y219464D02*
X134984Y218993D01*
G01X134995Y219853D02*
X134989Y219464D01*
G01X135002Y220148D02*
X134995Y219853D01*
G01X135009Y220340D02*
X135002Y220148D01*
G01X135074Y221390D02*
X135059Y221327D01*
G01X135081Y221259D02*
X135074Y221390D01*
G01X135088Y221024D02*
X135081Y221259D01*
G01X133353Y221390D02*
X133339Y221024D01*
G01X133361Y221412D02*
X133353Y221390D01*
G01X133368Y221327D02*
X133361Y221412D01*
G01X133432Y219853D02*
X133418Y220340D01*
G01X133438Y219464D02*
X133432Y219853D01*
G01X133443Y218993D02*
X133438Y219464D01*
G01X133447Y218453D02*
X133443Y218993D01*
G01X133450Y217857D02*
X133447Y218453D01*
G01X133452Y217224D02*
X133450Y217857D01*
G01X133453Y216570D02*
X133452Y217224D01*
G01X133426Y219013D02*
X133416Y219379D01*
G01X133431Y218722D02*
X133426Y219013D01*
G01X133434Y218368D02*
X133431Y218722D01*
G01X133438Y217963D02*
X133434Y218368D01*
G01X133440Y217516D02*
X133438Y217963D01*
G01X133441Y217041D02*
X133440Y217516D01*
G01X133442Y216551D02*
X133441Y217041D01*
G01X133355Y220412D02*
X133344Y220138D01*
G01X133360Y220429D02*
X133355Y220412D01*
G01X133365Y220365D02*
X133360Y220429D01*
G01X133355Y225965D02*
X133365Y226012D01*
G01X133349Y226063D02*
X133355Y225965D01*
G01X133344Y226239D02*
X133349Y226063D01*
G01X133440Y228861D02*
X133442Y229826D01*
G01X133438Y228414D02*
X133440Y228861D01*
G01X133434Y228009D02*
X133438Y228414D01*
G01X133431Y227656D02*
X133434Y228009D01*
G01X133426Y227364D02*
X133431Y227656D01*
G01X133421Y227143D02*
X133426Y227364D01*
G01X133416Y226999D02*
X133421Y227143D01*
G01X133450Y228520D02*
X133453Y229807D01*
G01X133447Y227925D02*
X133450Y228520D01*
G01X133443Y227384D02*
X133447Y227925D01*
G01X133438Y226913D02*
X133443Y227384D01*
G01X133432Y226524D02*
X133438Y226913D01*
G01X133425Y226230D02*
X133432Y226524D01*
G01X133418Y226037D02*
X133425Y226230D01*
G01X133353Y224988D02*
X133368Y225050D01*
G01X133346Y225118D02*
X133353Y224988D01*
G01X133339Y225353D02*
X133346Y225118D01*
G01X135074Y224988D02*
X135088Y225353D01*
G01X135067Y224965D02*
X135074Y224988D01*
G01X135059Y225050D02*
X135067Y224965D01*
G01X134995Y226524D02*
X135009Y226037D01*
G01X134989Y226913D02*
X134995Y226524D01*
G01X134984Y227384D02*
X134989Y226913D01*
G01X134980Y227925D02*
X134984Y227384D01*
G01X134977Y228520D02*
X134980Y227925D01*
G01X134975Y229153D02*
X134977Y228520D01*
G01X134974Y229807D02*
X134975Y229153D01*
G01X135001Y227364D02*
X135011Y226999D01*
G01X134997Y227656D02*
X135001Y227364D01*
G01X134993Y228009D02*
X134997Y227656D01*
G01X134990Y228414D02*
X134993Y228009D01*
G01X134987Y228861D02*
X134990Y228414D01*
G01X134986Y229336D02*
X134987Y228861D01*
G01X134985Y229826D02*
X134986Y229336D01*
G01X135073Y225965D02*
X135083Y226239D01*
G01X135067Y225948D02*
X135073Y225965D01*
G01X135062Y226012D02*
X135067Y225948D01*
G01X139005Y220412D02*
X138994Y220365D01*
G01X139010Y220314D02*
X139005Y220412D01*
G01X139015Y220138D02*
X139010Y220314D01*
G01X138920Y217516D02*
X138918Y216551D01*
G01X138922Y217963D02*
X138920Y217516D01*
G01X138925Y218368D02*
X138922Y217963D01*
G01X138929Y218722D02*
X138925Y218368D01*
G01X138933Y219013D02*
X138929Y218722D01*
G01X138938Y219234D02*
X138933Y219013D01*
G01X138943Y219379D02*
X138938Y219234D01*
G01X138916Y215857D02*
X138918Y216551D01*
G01X138914Y215540D02*
X138916Y215857D01*
G01X138912Y215257D02*
X138914Y215540D01*
G01X138909Y215018D02*
X138912Y215257D01*
G01X138905Y214830D02*
X138909Y215018D01*
G01X138902Y214700D02*
X138905Y214830D01*
G01X138898Y214632D02*
X138902Y214700D01*
G01X138894Y214627D02*
X138898Y214632D01*
G01X138909Y217857D02*
X138907Y216570D01*
G01X138912Y218453D02*
X138909Y217857D01*
G01X138917Y218993D02*
X138912Y218453D01*
G01X138922Y219464D02*
X138917Y218993D01*
G01X138928Y219853D02*
X138922Y219464D01*
G01X138934Y220148D02*
X138928Y219853D01*
G01X138941Y220340D02*
X138934Y220148D01*
G01X139006Y221390D02*
X138992Y221327D01*
G01X139013Y221259D02*
X139006Y221390D01*
G01X139020Y221024D02*
X139013Y221259D01*
G01X137286Y221390D02*
X137272Y221024D01*
G01X137293Y221412D02*
X137286Y221390D01*
G01X137300Y221327D02*
X137293Y221412D01*
G01X137364Y219853D02*
X137351Y220340D01*
G01X137370Y219464D02*
X137364Y219853D01*
G01X137375Y218993D02*
X137370Y219464D01*
G01X137379Y218453D02*
X137375Y218993D01*
G01X137382Y217857D02*
X137379Y218453D01*
G01X137384Y217224D02*
X137382Y217857D01*
G01X137385Y216570D02*
X137384Y217224D01*
G01X137390Y214700D02*
X137398Y214627D01*
G01X137386Y214830D02*
X137390Y214700D01*
G01X137383Y215018D02*
X137386Y214830D01*
G01X137380Y215257D02*
X137383Y215018D01*
G01X137378Y215540D02*
X137380Y215257D01*
G01X137376Y215857D02*
X137378Y215540D01*
G01X137375Y216198D02*
X137376Y215857D01*
G01X137374Y216551D02*
X137375Y216198D01*
G01X137358Y219013D02*
X137348Y219379D01*
G01X137363Y218722D02*
X137358Y219013D01*
G01X137367Y218368D02*
X137363Y218722D01*
G01X137370Y217963D02*
X137367Y218368D01*
G01X137372Y217516D02*
X137370Y217963D01*
G01X137374Y217041D02*
X137372Y217516D01*
G01X137374Y216551D02*
Y217041D01*
G01X137287Y220412D02*
X137276Y220138D01*
G01X137292Y220429D02*
X137287Y220412D01*
G01X137298Y220365D02*
X137292Y220429D01*
G01X137296Y225965D02*
X137307Y226012D01*
G01X137291Y226063D02*
X137296Y225965D01*
G01X137286Y226239D02*
X137291Y226063D01*
G01X137382Y228861D02*
X137384Y229826D01*
G01X137379Y228414D02*
X137382Y228861D01*
G01X137376Y228009D02*
X137379Y228414D01*
G01X137372Y227656D02*
X137376Y228009D01*
G01X137368Y227364D02*
X137372Y227656D01*
G01X137363Y227143D02*
X137368Y227364D01*
G01X137358Y226999D02*
X137363Y227143D01*
G01X137385Y230521D02*
X137384Y229826D01*
G01X137387Y230838D02*
X137385Y230521D01*
G01X137389Y231120D02*
X137387Y230838D01*
G01X137392Y231359D02*
X137389Y231120D01*
G01X137396Y231547D02*
X137392Y231359D01*
G01X137399Y231677D02*
X137396Y231547D01*
G01X137403Y231746D02*
X137399Y231677D01*
G01X137407Y231750D02*
X137403Y231746D01*
G01X137392Y228520D02*
X137395Y229807D01*
G01X137389Y227925D02*
X137392Y228520D01*
G01X137385Y227384D02*
X137389Y227925D01*
G01X137379Y226913D02*
X137385Y227384D01*
G01X137374Y226524D02*
X137379Y226913D01*
G01X137367Y226230D02*
X137374Y226524D01*
G01X137360Y226037D02*
X137367Y226230D01*
G01X137295Y224988D02*
X137309Y225050D01*
G01X137288Y225118D02*
X137295Y224988D01*
G01X137281Y225353D02*
X137288Y225118D01*
G01X139015Y224988D02*
X139029Y225353D01*
G01X139008Y224965D02*
X139015Y224988D01*
G01X139001Y225050D02*
X139008Y224965D01*
G01X138937Y226524D02*
X138950Y226037D01*
G01X138931Y226913D02*
X138937Y226524D01*
G01X138926Y227384D02*
X138931Y226913D01*
G01X138922Y227925D02*
X138926Y227384D01*
G01X138919Y228520D02*
X138922Y227925D01*
G01X138917Y229153D02*
X138919Y228520D01*
G01X138916Y229807D02*
X138917Y229153D01*
G01X138911Y231677D02*
X138903Y231750D01*
G01X138915Y231547D02*
X138911Y231677D01*
G01X138918Y231359D02*
X138915Y231547D01*
G01X138921Y231120D02*
X138918Y231359D01*
G01X138924Y230838D02*
X138921Y231120D01*
G01X138925Y230521D02*
X138924Y230838D01*
G01X138926Y230180D02*
X138925Y230521D01*
G01X138927Y229826D02*
X138926Y230180D01*
G01X138943Y227364D02*
X138953Y226999D01*
G01X138938Y227656D02*
X138943Y227364D01*
G01X138934Y228009D02*
X138938Y227656D01*
G01X138931Y228414D02*
X138934Y228009D01*
G01X138929Y228861D02*
X138931Y228414D01*
G01X138927Y229336D02*
X138929Y228861D01*
G01X138927Y229826D02*
Y229336D01*
G01X139014Y225965D02*
X139025Y226239D01*
G01X139009Y225948D02*
X139014Y225965D01*
G01X139003Y226012D02*
X139009Y225948D01*
G01X142947Y220412D02*
X142936Y220365D01*
G01X142952Y220314D02*
X142947Y220412D01*
G01X142957Y220138D02*
X142952Y220314D01*
G01X142861Y217516D02*
X142859Y216551D01*
G01X142864Y217963D02*
X142861Y217516D01*
G01X142867Y218368D02*
X142864Y217963D01*
G01X142871Y218722D02*
X142867Y218368D01*
G01X142875Y219013D02*
X142871Y218722D01*
G01X142880Y219234D02*
X142875Y219013D01*
G01X142885Y219379D02*
X142880Y219234D01*
G01X142851Y217857D02*
X142848Y216570D01*
G01X142854Y218453D02*
X142851Y217857D01*
G01X142858Y218993D02*
X142854Y218453D01*
G01X142863Y219464D02*
X142858Y218993D01*
G01X142869Y219853D02*
X142863Y219464D01*
G01X142876Y220148D02*
X142869Y219853D01*
G01X142883Y220340D02*
X142876Y220148D01*
G01X142948Y221390D02*
X142933Y221327D01*
G01X142955Y221259D02*
X142948Y221390D01*
G01X142962Y221024D02*
X142955Y221259D01*
G01X141227Y221390D02*
X141213Y221024D01*
G01X141235Y221412D02*
X141227Y221390D01*
G01X141242Y221327D02*
X141235Y221412D01*
G01X141306Y219853D02*
X141292Y220340D01*
G01X141312Y219464D02*
X141306Y219853D01*
G01X141317Y218993D02*
X141312Y219464D01*
G01X141321Y218453D02*
X141317Y218993D01*
G01X141324Y217857D02*
X141321Y218453D01*
G01X141326Y217224D02*
X141324Y217857D01*
G01X141327Y216570D02*
X141326Y217224D01*
G01X141300Y219013D02*
X141290Y219379D01*
G01X141305Y218722D02*
X141300Y219013D01*
G01X141308Y218368D02*
X141305Y218722D01*
G01X141312Y217963D02*
X141308Y218368D01*
G01X141314Y217516D02*
X141312Y217963D01*
G01X141315Y217041D02*
X141314Y217516D01*
G01X141316Y216551D02*
X141315Y217041D01*
G01X141229Y220412D02*
X141218Y220138D01*
G01X141234Y220429D02*
X141229Y220412D01*
G01X141239Y220365D02*
X141234Y220429D01*
G01X141229Y225965D02*
X141239Y226012D01*
G01X141223Y226063D02*
X141229Y225965D01*
G01X141218Y226239D02*
X141223Y226063D01*
G01X141314Y228861D02*
X141316Y229826D01*
G01X141312Y228414D02*
X141314Y228861D01*
G01X141308Y228009D02*
X141312Y228414D01*
G01X141305Y227656D02*
X141308Y228009D01*
G01X141300Y227364D02*
X141305Y227656D01*
G01X141295Y227143D02*
X141300Y227364D01*
G01X141290Y226999D02*
X141295Y227143D01*
G01X141324Y228520D02*
X141327Y229807D01*
G01X141321Y227925D02*
X141324Y228520D01*
G01X141317Y227384D02*
X141321Y227925D01*
G01X141312Y226913D02*
X141317Y227384D01*
G01X141306Y226524D02*
X141312Y226913D01*
G01X141299Y226230D02*
X141306Y226524D01*
G01X141292Y226037D02*
X141299Y226230D01*
G01X141227Y224988D02*
X141242Y225050D01*
G01X141220Y225118D02*
X141227Y224988D01*
G01X141213Y225353D02*
X141220Y225118D01*
G01X142948Y224988D02*
X142962Y225353D01*
G01X142941Y224965D02*
X142948Y224988D01*
G01X142933Y225050D02*
X142941Y224965D01*
G01X142869Y226524D02*
X142883Y226037D01*
G01X142863Y226913D02*
X142869Y226524D01*
G01X142858Y227384D02*
X142863Y226913D01*
G01X142854Y227925D02*
X142858Y227384D01*
G01X142851Y228520D02*
X142854Y227925D01*
G01X142849Y229153D02*
X142851Y228520D01*
G01X142848Y229807D02*
X142849Y229153D01*
G01X142875Y227364D02*
X142885Y226999D01*
G01X142871Y227656D02*
X142875Y227364D01*
G01X142867Y228009D02*
X142871Y227656D01*
G01X142864Y228414D02*
X142867Y228009D01*
G01X142861Y228861D02*
X142864Y228414D01*
G01X142860Y229336D02*
X142861Y228861D01*
G01X142859Y229826D02*
X142860Y229336D01*
G01X142947Y225965D02*
X142957Y226239D01*
G01X142941Y225948D02*
X142947Y225965D01*
G01X142936Y226012D02*
X142941Y225948D01*
G01X146879Y220412D02*
X146868Y220365D01*
G01X146884Y220314D02*
X146879Y220412D01*
G01X146889Y220138D02*
X146884Y220314D01*
G01X146794Y217516D02*
X146792Y216551D01*
G01X146796Y217963D02*
X146794Y217516D01*
G01X146799Y218368D02*
X146796Y217963D01*
G01X146803Y218722D02*
X146799Y218368D01*
G01X146807Y219013D02*
X146803Y218722D01*
G01X146812Y219234D02*
X146807Y219013D01*
G01X146817Y219379D02*
X146812Y219234D01*
G01X146790Y215857D02*
X146792Y216551D01*
G01X146788Y215540D02*
X146790Y215857D01*
G01X146786Y215257D02*
X146788Y215540D01*
G01X146783Y215018D02*
X146786Y215257D01*
G01X146779Y214830D02*
X146783Y215018D01*
G01X146776Y214700D02*
X146779Y214830D01*
G01X146772Y214632D02*
X146776Y214700D01*
G01X146768Y214627D02*
X146772Y214632D01*
G01X146783Y217857D02*
X146781Y216570D01*
G01X146786Y218453D02*
X146783Y217857D01*
G01X146791Y218993D02*
X146786Y218453D01*
G01X146796Y219464D02*
X146791Y218993D01*
G01X146802Y219853D02*
X146796Y219464D01*
G01X146808Y220148D02*
X146802Y219853D01*
G01X146815Y220340D02*
X146808Y220148D01*
G01X146880Y221390D02*
X146866Y221327D01*
G01X146887Y221259D02*
X146880Y221390D01*
G01X146894Y221024D02*
X146887Y221259D01*
G01X145160Y221390D02*
X145146Y221024D01*
G01X145167Y221412D02*
X145160Y221390D01*
G01X145174Y221327D02*
X145167Y221412D01*
G01X145238Y219853D02*
X145225Y220340D01*
G01X145244Y219464D02*
X145238Y219853D01*
G01X145249Y218993D02*
X145244Y219464D01*
G01X145253Y218453D02*
X145249Y218993D01*
G01X145257Y217857D02*
X145253Y218453D01*
G01X145258Y217224D02*
X145257Y217857D01*
G01X145259Y216570D02*
X145258Y217224D01*
G01X145264Y214700D02*
X145272Y214627D01*
G01X145260Y214830D02*
X145264Y214700D01*
G01X145257Y215018D02*
X145260Y214830D01*
G01X145254Y215257D02*
X145257Y215018D01*
G01X145252Y215540D02*
X145254Y215257D01*
G01X145250Y215857D02*
X145252Y215540D01*
G01X145249Y216198D02*
X145250Y215857D01*
G01X145248Y216551D02*
X145249Y216198D01*
G01X145232Y219013D02*
X145222Y219379D01*
G01X145237Y218722D02*
X145232Y219013D01*
G01X145241Y218368D02*
X145237Y218722D01*
G01X145244Y217963D02*
X145241Y218368D01*
G01X145246Y217516D02*
X145244Y217963D01*
G01X145248Y217041D02*
X145246Y217516D01*
G01X145248Y216551D02*
Y217041D01*
G01X145161Y220412D02*
X145151Y220138D01*
G01X145166Y220429D02*
X145161Y220412D01*
G01X145172Y220365D02*
X145166Y220429D01*
G01X145170Y225965D02*
X145181Y226012D01*
G01X145165Y226063D02*
X145170Y225965D01*
G01X145160Y226239D02*
X145165Y226063D01*
G01X145256Y228861D02*
X145258Y229826D01*
G01X145253Y228414D02*
X145256Y228861D01*
G01X145250Y228009D02*
X145253Y228414D01*
G01X145246Y227656D02*
X145250Y228009D01*
G01X145242Y227364D02*
X145246Y227656D01*
G01X145237Y227143D02*
X145242Y227364D01*
G01X145232Y226999D02*
X145237Y227143D01*
G01X145259Y230521D02*
X145258Y229826D01*
G01X145261Y230838D02*
X145259Y230521D01*
G01X145263Y231120D02*
X145261Y230838D01*
G01X145266Y231359D02*
X145263Y231120D01*
G01X145270Y231547D02*
X145266Y231359D01*
G01X145273Y231677D02*
X145270Y231547D01*
G01X145277Y231746D02*
X145273Y231677D01*
G01X145281Y231750D02*
X145277Y231746D01*
G01X145266Y228520D02*
X145269Y229807D01*
G01X145263Y227925D02*
X145266Y228520D01*
G01X145259Y227384D02*
X145263Y227925D01*
G01X145253Y226913D02*
X145259Y227384D01*
G01X145248Y226524D02*
X145253Y226913D01*
G01X145241Y226230D02*
X145248Y226524D01*
G01X145234Y226037D02*
X145241Y226230D01*
G01X145169Y224988D02*
X145184Y225050D01*
G01X145162Y225118D02*
X145169Y224988D01*
G01X145155Y225353D02*
X145162Y225118D01*
G01X146889Y224988D02*
X146903Y225353D01*
G01X146882Y224965D02*
X146889Y224988D01*
G01X146875Y225050D02*
X146882Y224965D01*
G01X146811Y226524D02*
X146825Y226037D01*
G01X146805Y226913D02*
X146811Y226524D01*
G01X146800Y227384D02*
X146805Y226913D01*
G01X146796Y227925D02*
X146800Y227384D01*
G01X146793Y228520D02*
X146796Y227925D01*
G01X146791Y229153D02*
X146793Y228520D01*
G01X146790Y229807D02*
X146791Y229153D01*
G01X146785Y231677D02*
X146777Y231750D01*
G01X146789Y231547D02*
X146785Y231677D01*
G01X146792Y231359D02*
X146789Y231547D01*
G01X146795Y231120D02*
X146792Y231359D01*
G01X146798Y230838D02*
X146795Y231120D01*
G01X146799Y230521D02*
X146798Y230838D01*
G01X146801Y230180D02*
X146799Y230521D01*
G01X146801Y229826D02*
Y230180D01*
G01X146817Y227364D02*
X146827Y226999D01*
G01X146812Y227656D02*
X146817Y227364D01*
G01X146808Y228009D02*
X146812Y227656D01*
G01X146805Y228414D02*
X146808Y228009D01*
G01X146803Y228861D02*
X146805Y228414D01*
G01X146801Y229336D02*
X146803Y228861D01*
G01X146801Y229826D02*
Y229336D01*
G01X146888Y225965D02*
X146899Y226239D01*
G01X146883Y225948D02*
X146888Y225965D01*
G01X146877Y226012D02*
X146883Y225948D01*
G01X150821Y220412D02*
X150810Y220365D01*
G01X150826Y220314D02*
X150821Y220412D01*
G01X150831Y220138D02*
X150826Y220314D01*
G01X150735Y217516D02*
X150733Y216551D01*
G01X150738Y217963D02*
X150735Y217516D01*
G01X150741Y218368D02*
X150738Y217963D01*
G01X150745Y218722D02*
X150741Y218368D01*
G01X150749Y219013D02*
X150745Y218722D01*
G01X150754Y219234D02*
X150749Y219013D01*
G01X150759Y219379D02*
X150754Y219234D01*
G01X150725Y217857D02*
X150722Y216570D01*
G01X150728Y218453D02*
X150725Y217857D01*
G01X150732Y218993D02*
X150728Y218453D01*
G01X150737Y219464D02*
X150732Y218993D01*
G01X150743Y219853D02*
X150737Y219464D01*
G01X150750Y220148D02*
X150743Y219853D01*
G01X150757Y220340D02*
X150750Y220148D01*
G01X150822Y221390D02*
X150807Y221327D01*
G01X150829Y221259D02*
X150822Y221390D01*
G01X150836Y221024D02*
X150829Y221259D01*
G01X149101Y221390D02*
X149087Y221024D01*
G01X149109Y221412D02*
X149101Y221390D01*
G01X149116Y221327D02*
X149109Y221412D01*
G01X149180Y219853D02*
X149166Y220340D01*
G01X149186Y219464D02*
X149180Y219853D01*
G01X149191Y218993D02*
X149186Y219464D01*
G01X149195Y218453D02*
X149191Y218993D01*
G01X149198Y217857D02*
X149195Y218453D01*
G01X149200Y217224D02*
X149198Y217857D01*
G01X149201Y216570D02*
X149200Y217224D01*
G01X149174Y219013D02*
X149164Y219379D01*
G01X149179Y218722D02*
X149174Y219013D01*
G01X149182Y218368D02*
X149179Y218722D01*
G01X149186Y217963D02*
X149182Y218368D01*
G01X149188Y217516D02*
X149186Y217963D01*
G01X149189Y217041D02*
X149188Y217516D01*
G01X149190Y216551D02*
X149189Y217041D01*
G01X149103Y220412D02*
X149092Y220138D01*
G01X149108Y220429D02*
X149103Y220412D01*
G01X149114Y220365D02*
X149108Y220429D01*
G01X149103Y225965D02*
X149114Y226012D01*
G01X149097Y226063D02*
X149103Y225965D01*
G01X149092Y226239D02*
X149097Y226063D01*
G01X149188Y228861D02*
X149190Y229826D01*
G01X149186Y228414D02*
X149188Y228861D01*
G01X149182Y228009D02*
X149186Y228414D01*
G01X149179Y227656D02*
X149182Y228009D01*
G01X149174Y227364D02*
X149179Y227656D01*
G01X149169Y227143D02*
X149174Y227364D01*
G01X149164Y226999D02*
X149169Y227143D01*
G01X149198Y228520D02*
X149201Y229807D01*
G01X149195Y227925D02*
X149198Y228520D01*
G01X149191Y227384D02*
X149195Y227925D01*
G01X149186Y226913D02*
X149191Y227384D01*
G01X149180Y226524D02*
X149186Y226913D01*
G01X149173Y226230D02*
X149180Y226524D01*
G01X149166Y226037D02*
X149173Y226230D01*
G01X149101Y224988D02*
X149116Y225050D01*
G01X149094Y225118D02*
X149101Y224988D01*
G01X149087Y225353D02*
X149094Y225118D01*
G01X150822Y224988D02*
X150836Y225353D01*
G01X150815Y224965D02*
X150822Y224988D01*
G01X150807Y225050D02*
X150815Y224965D01*
G01X150743Y226524D02*
X150757Y226037D01*
G01X150737Y226913D02*
X150743Y226524D01*
G01X150732Y227384D02*
X150737Y226913D01*
G01X150728Y227925D02*
X150732Y227384D01*
G01X150725Y228520D02*
X150728Y227925D01*
G01X150723Y229153D02*
X150725Y228520D01*
G01X150722Y229807D02*
X150723Y229153D01*
G01X150749Y227364D02*
X150759Y226999D01*
G01X150745Y227656D02*
X150749Y227364D01*
G01X150741Y228009D02*
X150745Y227656D01*
G01X150738Y228414D02*
X150741Y228009D01*
G01X150735Y228861D02*
X150738Y228414D01*
G01X150734Y229336D02*
X150735Y228861D01*
G01X150733Y229826D02*
X150734Y229336D01*
G01X150821Y225965D02*
X150831Y226239D01*
G01X150815Y225948D02*
X150821Y225965D01*
G01X150810Y226012D02*
X150815Y225948D01*
G01X158695Y220412D02*
X158684Y220365D01*
G01X158700Y220314D02*
X158695Y220412D01*
G01X158705Y220138D02*
X158700Y220314D01*
G01X158609Y217516D02*
X158607Y216551D01*
G01X158612Y217963D02*
X158609Y217516D01*
G01X158615Y218368D02*
X158612Y217963D01*
G01X158619Y218722D02*
X158615Y218368D01*
G01X158623Y219013D02*
X158619Y218722D01*
G01X158628Y219234D02*
X158623Y219013D01*
G01X158633Y219379D02*
X158628Y219234D01*
G01X158599Y217857D02*
X158596Y216570D01*
G01X158602Y218453D02*
X158599Y217857D01*
G01X158606Y218993D02*
X158602Y218453D01*
G01X158611Y219464D02*
X158606Y218993D01*
G01X158617Y219853D02*
X158611Y219464D01*
G01X158624Y220148D02*
X158617Y219853D01*
G01X158631Y220340D02*
X158624Y220148D01*
G01X158696Y221390D02*
X158681Y221327D01*
G01X158703Y221259D02*
X158696Y221390D01*
G01X158710Y221024D02*
X158703Y221259D01*
G01X156975Y221390D02*
X156961Y221024D01*
G01X156983Y221412D02*
X156975Y221390D01*
G01X156990Y221327D02*
X156983Y221412D01*
G01X157054Y219853D02*
X157040Y220340D01*
G01X157060Y219464D02*
X157054Y219853D01*
G01X157065Y218993D02*
X157060Y219464D01*
G01X157069Y218453D02*
X157065Y218993D01*
G01X157072Y217857D02*
X157069Y218453D01*
G01X157074Y217224D02*
X157072Y217857D01*
G01X157075Y216570D02*
X157074Y217224D01*
G01X157048Y219013D02*
X157038Y219379D01*
G01X157053Y218722D02*
X157048Y219013D01*
G01X157056Y218368D02*
X157053Y218722D01*
G01X157060Y217963D02*
X157056Y218368D01*
G01X157062Y217516D02*
X157060Y217963D01*
G01X157063Y217041D02*
X157062Y217516D01*
G01X157064Y216551D02*
X157063Y217041D01*
G01X156977Y220412D02*
X156966Y220138D01*
G01X156982Y220429D02*
X156977Y220412D01*
G01X156988Y220365D02*
X156982Y220429D01*
G01X156977Y225965D02*
X156988Y226012D01*
G01X156971Y226063D02*
X156977Y225965D01*
G01X156966Y226239D02*
X156971Y226063D01*
G01X157062Y228861D02*
X157064Y229826D01*
G01X157060Y228414D02*
X157062Y228861D01*
G01X157056Y228009D02*
X157060Y228414D01*
G01X157053Y227656D02*
X157056Y228009D01*
G01X157048Y227364D02*
X157053Y227656D01*
G01X157043Y227143D02*
X157048Y227364D01*
G01X157038Y226999D02*
X157043Y227143D01*
G01X157072Y228520D02*
X157075Y229807D01*
G01X157069Y227925D02*
X157072Y228520D01*
G01X157065Y227384D02*
X157069Y227925D01*
G01X157060Y226913D02*
X157065Y227384D01*
G01X157054Y226524D02*
X157060Y226913D01*
G01X157047Y226230D02*
X157054Y226524D01*
G01X157040Y226037D02*
X157047Y226230D01*
G01X156975Y224988D02*
X156990Y225050D01*
G01X156968Y225118D02*
X156975Y224988D01*
G01X156961Y225353D02*
X156968Y225118D01*
G01X158696Y224988D02*
X158710Y225353D01*
G01X158689Y224965D02*
X158696Y224988D01*
G01X158681Y225050D02*
X158689Y224965D01*
G01X158617Y226524D02*
X158631Y226037D01*
G01X158611Y226913D02*
X158617Y226524D01*
G01X158606Y227384D02*
X158611Y226913D01*
G01X158602Y227925D02*
X158606Y227384D01*
G01X158599Y228520D02*
X158602Y227925D01*
G01X158597Y229153D02*
X158599Y228520D01*
G01X158596Y229807D02*
X158597Y229153D01*
G01X158623Y227364D02*
X158633Y226999D01*
G01X158619Y227656D02*
X158623Y227364D01*
G01X158615Y228009D02*
X158619Y227656D01*
G01X158612Y228414D02*
X158615Y228009D01*
G01X158609Y228861D02*
X158612Y228414D01*
G01X158608Y229336D02*
X158609Y228861D01*
G01X158607Y229826D02*
X158608Y229336D01*
G01X158695Y225965D02*
X158705Y226239D01*
G01X158689Y225948D02*
X158695Y225965D01*
G01X158684Y226012D02*
X158689Y225948D01*
G01X162627Y220412D02*
X162616Y220365D01*
G01X162632Y220314D02*
X162627Y220412D01*
G01X162637Y220138D02*
X162632Y220314D01*
G01X162542Y217516D02*
X162540Y216551D01*
G01X162544Y217963D02*
X162542Y217516D01*
G01X162547Y218368D02*
X162544Y217963D01*
G01X162551Y218722D02*
X162547Y218368D01*
G01X162555Y219013D02*
X162551Y218722D01*
G01X162560Y219234D02*
X162555Y219013D01*
G01X162566Y219379D02*
X162560Y219234D01*
G01X162538Y215857D02*
X162540Y216551D01*
G01X162536Y215540D02*
X162538Y215857D01*
G01X162534Y215257D02*
X162536Y215540D01*
G01X162531Y215018D02*
X162534Y215257D01*
G01X162528Y214830D02*
X162531Y215018D01*
G01X162524Y214700D02*
X162528Y214830D01*
G01X162520Y214632D02*
X162524Y214700D01*
G01X162516Y214627D02*
X162520Y214632D01*
G01X162531Y217857D02*
X162529Y216570D01*
G01X162534Y218453D02*
X162531Y217857D01*
G01X162539Y218993D02*
X162534Y218453D01*
G01X162544Y219464D02*
X162539Y218993D01*
G01X162550Y219853D02*
X162544Y219464D01*
G01X162556Y220148D02*
X162550Y219853D01*
G01X162563Y220340D02*
X162556Y220148D01*
G01X162628Y221390D02*
X162614Y221327D01*
G01X162635Y221259D02*
X162628Y221390D01*
G01X162642Y221024D02*
X162635Y221259D01*
G01X160908Y221390D02*
X160894Y221024D01*
G01X160915Y221412D02*
X160908Y221390D01*
G01X160922Y221327D02*
X160915Y221412D01*
G01X160986Y219853D02*
X160973Y220340D01*
G01X160992Y219464D02*
X160986Y219853D01*
G01X160997Y218993D02*
X160992Y219464D01*
G01X161001Y218453D02*
X160997Y218993D01*
G01X161005Y217857D02*
X161001Y218453D01*
G01X161006Y217224D02*
X161005Y217857D01*
G01X161007Y216570D02*
X161006Y217224D01*
G01X161012Y214700D02*
X161020Y214627D01*
G01X161008Y214830D02*
X161012Y214700D01*
G01X161005Y215018D02*
X161008Y214830D01*
G01X161002Y215257D02*
X161005Y215018D01*
G01X161000Y215540D02*
X161002Y215257D01*
G01X160998Y215857D02*
X161000Y215540D01*
G01X160997Y216198D02*
X160998Y215857D01*
G01X160996Y216551D02*
X160997Y216198D01*
G01X160981Y219013D02*
X160970Y219379D01*
G01X160985Y218722D02*
X160981Y219013D01*
G01X160989Y218368D02*
X160985Y218722D01*
G01X160992Y217963D02*
X160989Y218368D01*
G01X160994Y217516D02*
X160992Y217963D01*
G01X160996Y217041D02*
X160994Y217516D01*
G01X160996Y216551D02*
Y217041D01*
G01X160909Y220412D02*
X160899Y220138D01*
G01X160914Y220429D02*
X160909Y220412D01*
G01X160920Y220365D02*
X160914Y220429D01*
G01X160918Y225965D02*
X160929Y226012D01*
G01X160913Y226063D02*
X160918Y225965D01*
G01X160908Y226239D02*
X160913Y226063D01*
G01X161004Y228861D02*
X161006Y229826D01*
G01X161001Y228414D02*
X161004Y228861D01*
G01X160998Y228009D02*
X161001Y228414D01*
G01X160994Y227656D02*
X160998Y228009D01*
G01X160990Y227364D02*
X160994Y227656D01*
G01X160985Y227143D02*
X160990Y227364D01*
G01X160980Y226999D02*
X160985Y227143D01*
G01X161007Y230521D02*
X161006Y229826D01*
G01X161009Y230838D02*
X161007Y230521D01*
G01X161011Y231120D02*
X161009Y230838D01*
G01X161014Y231359D02*
X161011Y231120D01*
G01X161018Y231547D02*
X161014Y231359D01*
G01X161021Y231677D02*
X161018Y231547D01*
G01X161025Y231746D02*
X161021Y231677D01*
G01X161029Y231750D02*
X161025Y231746D01*
G01X161014Y228520D02*
X161017Y229807D01*
G01X161011Y227925D02*
X161014Y228520D01*
G01X161007Y227384D02*
X161011Y227925D01*
G01X161001Y226913D02*
X161007Y227384D01*
G01X160996Y226524D02*
X161001Y226913D01*
G01X160989Y226230D02*
X160996Y226524D01*
G01X160982Y226037D02*
X160989Y226230D01*
G01X160917Y224988D02*
X160932Y225050D01*
G01X160910Y225118D02*
X160917Y224988D01*
G01X160903Y225353D02*
X160910Y225118D01*
G01X162638Y224988D02*
X162651Y225353D01*
G01X162630Y224965D02*
X162638Y224988D01*
G01X162623Y225050D02*
X162630Y224965D01*
G01X162559Y226524D02*
X162573Y226037D01*
G01X162553Y226913D02*
X162559Y226524D01*
G01X162548Y227384D02*
X162553Y226913D01*
G01X162544Y227925D02*
X162548Y227384D01*
G01X162541Y228520D02*
X162544Y227925D01*
G01X162539Y229153D02*
X162541Y228520D01*
G01X162538Y229807D02*
X162539Y229153D01*
G01X162533Y231677D02*
X162525Y231750D01*
G01X162537Y231547D02*
X162533Y231677D01*
G01X162540Y231359D02*
X162537Y231547D01*
G01X162543Y231120D02*
X162540Y231359D01*
G01X162546Y230838D02*
X162543Y231120D01*
G01X162547Y230521D02*
X162546Y230838D01*
G01X162549Y230180D02*
X162547Y230521D01*
G01X162549Y229826D02*
Y230180D01*
G01X162565Y227364D02*
X162575Y226999D01*
G01X162560Y227656D02*
X162565Y227364D01*
G01X162556Y228009D02*
X162560Y227656D01*
G01X162553Y228414D02*
X162556Y228009D01*
G01X162551Y228861D02*
X162553Y228414D01*
G01X162550Y229336D02*
X162551Y228861D01*
G01X162549Y229826D02*
X162550Y229336D01*
G01X162636Y225965D02*
X162647Y226239D01*
G01X162631Y225948D02*
X162636Y225965D01*
G01X162625Y226012D02*
X162631Y225948D01*
G01X123257Y220412D02*
X123246Y220365D01*
G01X123262Y220314D02*
X123257Y220412D01*
G01X123267Y220138D02*
X123262Y220314D01*
G01X123172Y217516D02*
X123170Y216551D01*
G01X123174Y217963D02*
X123172Y217516D01*
G01X123177Y218368D02*
X123174Y217963D01*
G01X123181Y218722D02*
X123177Y218368D01*
G01X123185Y219013D02*
X123181Y218722D01*
G01X123190Y219234D02*
X123185Y219013D01*
G01X123195Y219379D02*
X123190Y219234D01*
G01X123168Y215857D02*
X123170Y216551D01*
G01X123166Y215540D02*
X123168Y215857D01*
G01X123164Y215257D02*
X123166Y215540D01*
G01X123161Y215018D02*
X123164Y215257D01*
G01X123157Y214830D02*
X123161Y215018D01*
G01X123154Y214700D02*
X123157Y214830D01*
G01X123150Y214632D02*
X123154Y214700D01*
G01X123146Y214627D02*
X123150Y214632D01*
G01X123161Y217857D02*
X123159Y216570D01*
G01X123164Y218453D02*
X123161Y217857D01*
G01X123169Y218993D02*
X123164Y218453D01*
G01X123174Y219464D02*
X123169Y218993D01*
G01X123180Y219853D02*
X123174Y219464D01*
G01X123186Y220148D02*
X123180Y219853D01*
G01X123193Y220340D02*
X123186Y220148D01*
G01X123258Y221390D02*
X123244Y221327D01*
G01X123265Y221259D02*
X123258Y221390D01*
G01X123272Y221024D02*
X123265Y221259D01*
G01X121538Y221390D02*
X121524Y221024D01*
G01X121545Y221412D02*
X121538Y221390D01*
G01X121552Y221327D02*
X121545Y221412D01*
G01X121616Y219853D02*
X121603Y220340D01*
G01X121622Y219464D02*
X121616Y219853D01*
G01X121627Y218993D02*
X121622Y219464D01*
G01X121631Y218453D02*
X121627Y218993D01*
G01X121634Y217857D02*
X121631Y218453D01*
G01X121636Y217224D02*
X121634Y217857D01*
G01X121637Y216570D02*
X121636Y217224D01*
G01X121642Y214700D02*
X121650Y214627D01*
G01X121638Y214830D02*
X121642Y214700D01*
G01X121635Y215018D02*
X121638Y214830D01*
G01X121632Y215257D02*
X121635Y215018D01*
G01X121630Y215540D02*
X121632Y215257D01*
G01X121628Y215857D02*
X121630Y215540D01*
G01X121627Y216198D02*
X121628Y215857D01*
G01X121626Y216551D02*
X121627Y216198D01*
G01X121610Y219013D02*
X121600Y219379D01*
G01X121615Y218722D02*
X121610Y219013D01*
G01X121619Y218368D02*
X121615Y218722D01*
G01X121622Y217963D02*
X121619Y218368D01*
G01X121624Y217516D02*
X121622Y217963D01*
G01X121626Y217041D02*
X121624Y217516D01*
G01X121626Y216551D02*
Y217041D01*
G01X121539Y220412D02*
X121528Y220138D01*
G01X121544Y220429D02*
X121539Y220412D01*
G01X121550Y220365D02*
X121544Y220429D01*
G01X121548Y225965D02*
X121559Y226012D01*
G01X121543Y226063D02*
X121548Y225965D01*
G01X121538Y226239D02*
X121543Y226063D01*
G01X121633Y228861D02*
X121636Y229826D01*
G01X121631Y228414D02*
X121633Y228861D01*
G01X121628Y228009D02*
X121631Y228414D01*
G01X121624Y227656D02*
X121628Y228009D01*
G01X121620Y227364D02*
X121624Y227656D01*
G01X121615Y227143D02*
X121620Y227364D01*
G01X121610Y226999D02*
X121615Y227143D01*
G01X121637Y230521D02*
X121636Y229826D01*
G01X121639Y230838D02*
X121637Y230521D01*
G01X121641Y231120D02*
X121639Y230838D01*
G01X121644Y231359D02*
X121641Y231120D01*
G01X121648Y231547D02*
X121644Y231359D01*
G01X121651Y231677D02*
X121648Y231547D01*
G01X121655Y231746D02*
X121651Y231677D01*
G01X121659Y231750D02*
X121655Y231746D01*
G01X121644Y228520D02*
X121647Y229807D01*
G01X121641Y227925D02*
X121644Y228520D01*
G01X121637Y227384D02*
X121641Y227925D01*
G01X121631Y226913D02*
X121637Y227384D01*
G01X121626Y226524D02*
X121631Y226913D01*
G01X121619Y226230D02*
X121626Y226524D01*
G01X121612Y226037D02*
X121619Y226230D01*
G01X121547Y224988D02*
X121561Y225050D01*
G01X121540Y225118D02*
X121547Y224988D01*
G01X121533Y225353D02*
X121540Y225118D01*
G01X123267Y224988D02*
X123281Y225353D01*
G01X123260Y224965D02*
X123267Y224988D01*
G01X123253Y225050D02*
X123260Y224965D01*
G01X123189Y226524D02*
X123202Y226037D01*
G01X123183Y226913D02*
X123189Y226524D01*
G01X123178Y227384D02*
X123183Y226913D01*
G01X123174Y227925D02*
X123178Y227384D01*
G01X123171Y228520D02*
X123174Y227925D01*
G01X123169Y229153D02*
X123171Y228520D01*
G01X123168Y229807D02*
X123169Y229153D01*
G01X123163Y231677D02*
X123155Y231750D01*
G01X123167Y231547D02*
X123163Y231677D01*
G01X123170Y231359D02*
X123167Y231547D01*
G01X123173Y231120D02*
X123170Y231359D01*
G01X123176Y230838D02*
X123173Y231120D01*
G01X123177Y230521D02*
X123176Y230838D01*
G01X123178Y230180D02*
X123177Y230521D01*
G01X123179Y229826D02*
X123178Y230180D01*
G01X123195Y227364D02*
X123205Y226999D01*
G01X123190Y227656D02*
X123195Y227364D01*
G01X123186Y228009D02*
X123190Y227656D01*
G01X123183Y228414D02*
X123186Y228009D01*
G01X123181Y228861D02*
X123183Y228414D01*
G01X123179Y229336D02*
X123181Y228861D01*
G01X123179Y229826D02*
Y229336D01*
G01X123266Y225965D02*
X123277Y226239D01*
G01X123261Y225948D02*
X123266Y225965D01*
G01X123255Y226012D02*
X123261Y225948D01*
G01X127199Y220412D02*
X127188Y220365D01*
G01X127204Y220314D02*
X127199Y220412D01*
G01X127209Y220138D02*
X127204Y220314D01*
G01X127113Y217516D02*
X127111Y216551D01*
G01X127116Y217963D02*
X127113Y217516D01*
G01X127119Y218368D02*
X127116Y217963D01*
G01X127123Y218722D02*
X127119Y218368D01*
G01X127127Y219013D02*
X127123Y218722D01*
G01X127132Y219234D02*
X127127Y219013D01*
G01X127137Y219379D02*
X127132Y219234D01*
G01X127103Y217857D02*
X127100Y216570D01*
G01X127106Y218453D02*
X127103Y217857D01*
G01X127110Y218993D02*
X127106Y218453D01*
G01X127115Y219464D02*
X127110Y218993D01*
G01X127121Y219853D02*
X127115Y219464D01*
G01X127128Y220148D02*
X127121Y219853D01*
G01X127135Y220340D02*
X127128Y220148D01*
G01X127200Y221390D02*
X127185Y221327D01*
G01X127207Y221259D02*
X127200Y221390D01*
G01X127214Y221024D02*
X127207Y221259D01*
G01X125479Y221390D02*
X125465Y221024D01*
G01X125487Y221412D02*
X125479Y221390D01*
G01X125494Y221327D02*
X125487Y221412D01*
G01X125558Y219853D02*
X125544Y220340D01*
G01X125564Y219464D02*
X125558Y219853D01*
G01X125569Y218993D02*
X125564Y219464D01*
G01X125573Y218453D02*
X125569Y218993D01*
G01X125576Y217857D02*
X125573Y218453D01*
G01X125578Y217224D02*
X125576Y217857D01*
G01X125579Y216570D02*
X125578Y217224D01*
G01X125552Y219013D02*
X125542Y219379D01*
G01X125557Y218722D02*
X125552Y219013D01*
G01X125560Y218368D02*
X125557Y218722D01*
G01X125564Y217963D02*
X125560Y218368D01*
G01X125566Y217516D02*
X125564Y217963D01*
G01X125567Y217041D02*
X125566Y217516D01*
G01X125568Y216551D02*
X125567Y217041D01*
G01X125481Y220412D02*
X125470Y220138D01*
G01X125486Y220429D02*
X125481Y220412D01*
G01X125491Y220365D02*
X125486Y220429D01*
G01X131131Y220412D02*
X131120Y220365D01*
G01X131136Y220314D02*
X131131Y220412D01*
G01X131141Y220138D02*
X131136Y220314D01*
G01X131046Y217516D02*
X131044Y216551D01*
G01X131048Y217963D02*
X131046Y217516D01*
G01X131051Y218368D02*
X131048Y217963D01*
G01X131055Y218722D02*
X131051Y218368D01*
G01X131059Y219013D02*
X131055Y218722D01*
G01X131064Y219234D02*
X131059Y219013D01*
G01X131069Y219379D02*
X131064Y219234D01*
G01X131042Y215857D02*
X131044Y216551D01*
G01X131040Y215540D02*
X131042Y215857D01*
G01X131038Y215257D02*
X131040Y215540D01*
G01X131035Y215018D02*
X131038Y215257D01*
G01X131031Y214830D02*
X131035Y215018D01*
G01X131028Y214700D02*
X131031Y214830D01*
G01X131024Y214632D02*
X131028Y214700D01*
G01X131020Y214627D02*
X131024Y214632D01*
G01X131035Y217857D02*
X131033Y216570D01*
G01X131038Y218453D02*
X131035Y217857D01*
G01X131043Y218993D02*
X131038Y218453D01*
G01X131048Y219464D02*
X131043Y218993D01*
G01X131054Y219853D02*
X131048Y219464D01*
G01X131060Y220148D02*
X131054Y219853D01*
G01X131067Y220340D02*
X131060Y220148D01*
G01X131132Y221390D02*
X131118Y221327D01*
G01X131139Y221259D02*
X131132Y221390D01*
G01X131146Y221024D02*
X131139Y221259D01*
G01X129412Y221390D02*
X129398Y221024D01*
G01X129419Y221412D02*
X129412Y221390D01*
G01X129426Y221327D02*
X129419Y221412D01*
G01X129490Y219853D02*
X129477Y220340D01*
G01X129496Y219464D02*
X129490Y219853D01*
G01X129501Y218993D02*
X129496Y219464D01*
G01X129505Y218453D02*
X129501Y218993D01*
G01X129508Y217857D02*
X129505Y218453D01*
G01X129510Y217224D02*
X129508Y217857D01*
G01X129511Y216570D02*
X129510Y217224D01*
G01X129516Y214700D02*
X129524Y214627D01*
G01X129512Y214830D02*
X129516Y214700D01*
G01X129509Y215018D02*
X129512Y214830D01*
G01X129506Y215257D02*
X129509Y215018D01*
G01X129504Y215540D02*
X129506Y215257D01*
G01X129502Y215857D02*
X129504Y215540D01*
G01X129501Y216198D02*
X129502Y215857D01*
G01X129500Y216551D02*
X129501Y216198D01*
G01X129484Y219013D02*
X129474Y219379D01*
G01X129489Y218722D02*
X129484Y219013D01*
G01X129493Y218368D02*
X129489Y218722D01*
G01X129496Y217963D02*
X129493Y218368D01*
G01X129498Y217516D02*
X129496Y217963D01*
G01X129500Y217041D02*
X129498Y217516D01*
G01X129500Y216551D02*
Y217041D01*
G01X129413Y220412D02*
X129402Y220138D01*
G01X129418Y220429D02*
X129413Y220412D01*
G01X129424Y220365D02*
X129418Y220429D01*
G01X129422Y225965D02*
X129433Y226012D01*
G01X129417Y226063D02*
X129422Y225965D01*
G01X129412Y226239D02*
X129417Y226063D01*
G01X129508Y228861D02*
X129510Y229826D01*
G01X129505Y228414D02*
X129508Y228861D01*
G01X129502Y228009D02*
X129505Y228414D01*
G01X129498Y227656D02*
X129502Y228009D01*
G01X129494Y227364D02*
X129498Y227656D01*
G01X129489Y227143D02*
X129494Y227364D01*
G01X129484Y226999D02*
X129489Y227143D01*
G01X129511Y230521D02*
X129510Y229826D01*
G01X129513Y230838D02*
X129511Y230521D01*
G01X129515Y231120D02*
X129513Y230838D01*
G01X129518Y231359D02*
X129515Y231120D01*
G01X129522Y231547D02*
X129518Y231359D01*
G01X129525Y231677D02*
X129522Y231547D01*
G01X129529Y231746D02*
X129525Y231677D01*
G01X129533Y231750D02*
X129529Y231746D01*
G01X129518Y228520D02*
X129521Y229807D01*
G01X129515Y227925D02*
X129518Y228520D01*
G01X129511Y227384D02*
X129515Y227925D01*
G01X129505Y226913D02*
X129511Y227384D01*
G01X129500Y226524D02*
X129505Y226913D01*
G01X129493Y226230D02*
X129500Y226524D01*
G01X129486Y226037D02*
X129493Y226230D01*
G01X129421Y224988D02*
X129435Y225050D01*
G01X129414Y225118D02*
X129421Y224988D01*
G01X129407Y225353D02*
X129414Y225118D01*
G01X131141Y224988D02*
X131155Y225353D01*
G01X131134Y224965D02*
X131141Y224988D01*
G01X131127Y225050D02*
X131134Y224965D01*
G01X131063Y226524D02*
X131076Y226037D01*
G01X131057Y226913D02*
X131063Y226524D01*
G01X131052Y227384D02*
X131057Y226913D01*
G01X131048Y227925D02*
X131052Y227384D01*
G01X131045Y228520D02*
X131048Y227925D01*
G01X131043Y229153D02*
X131045Y228520D01*
G01X131042Y229807D02*
X131043Y229153D01*
G01X131037Y231677D02*
X131029Y231750D01*
G01X131041Y231547D02*
X131037Y231677D01*
G01X131044Y231359D02*
X131041Y231547D01*
G01X131047Y231120D02*
X131044Y231359D01*
G01X131050Y230838D02*
X131047Y231120D01*
G01X131051Y230521D02*
X131050Y230838D01*
G01X131052Y230180D02*
X131051Y230521D01*
G01X131053Y229826D02*
X131052Y230180D01*
G01X131069Y227364D02*
X131079Y226999D01*
G01X131064Y227656D02*
X131069Y227364D01*
G01X131060Y228009D02*
X131064Y227656D01*
G01X131057Y228414D02*
X131060Y228009D01*
G01X131055Y228861D02*
X131057Y228414D01*
G01X131053Y229336D02*
X131055Y228861D01*
G01X131053Y229826D02*
Y229336D01*
G01X131140Y225965D02*
X131151Y226239D01*
G01X131135Y225948D02*
X131140Y225965D01*
G01X131129Y226012D02*
X131135Y225948D01*
G01X184540Y225965D02*
X184551Y226012D01*
G01X184535Y226063D02*
X184540Y225965D01*
G01X184530Y226239D02*
X184535Y226063D01*
G01X184626Y228861D02*
X184628Y229826D01*
G01X184623Y228414D02*
X184626Y228861D01*
G01X184620Y228009D02*
X184623Y228414D01*
G01X184616Y227656D02*
X184620Y228009D01*
G01X184612Y227364D02*
X184616Y227656D01*
G01X184607Y227143D02*
X184612Y227364D01*
G01X184602Y226999D02*
X184607Y227143D01*
G01X184629Y230521D02*
X184628Y229826D01*
G01X184631Y230838D02*
X184629Y230521D01*
G01X184633Y231120D02*
X184631Y230838D01*
G01X184636Y231359D02*
X184633Y231120D01*
G01X184640Y231547D02*
X184636Y231359D01*
G01X184643Y231677D02*
X184640Y231547D01*
G01X184647Y231746D02*
X184643Y231677D01*
G01X184651Y231750D02*
X184647Y231746D01*
G01X184636Y228520D02*
X184639Y229807D01*
G01X184633Y227925D02*
X184636Y228520D01*
G01X184629Y227384D02*
X184633Y227925D01*
G01X184624Y226913D02*
X184629Y227384D01*
G01X184618Y226524D02*
X184624Y226913D01*
G01X184611Y226230D02*
X184618Y226524D01*
G01X184604Y226037D02*
X184611Y226230D01*
G01X184539Y224988D02*
X184554Y225050D01*
G01X184532Y225118D02*
X184539Y224988D01*
G01X184525Y225353D02*
X184532Y225118D01*
G01X186260Y224988D02*
X186274Y225353D01*
G01X186252Y224965D02*
X186260Y224988D01*
G01X186245Y225050D02*
X186252Y224965D01*
G01X186181Y226524D02*
X186195Y226037D01*
G01X186175Y226913D02*
X186181Y226524D01*
G01X186170Y227384D02*
X186175Y226913D01*
G01X186166Y227925D02*
X186170Y227384D01*
G01X186163Y228520D02*
X186166Y227925D01*
G01X186161Y229153D02*
X186163Y228520D01*
G01X186160Y229807D02*
X186161Y229153D01*
G01X186155Y231677D02*
X186147Y231750D01*
G01X186159Y231547D02*
X186155Y231677D01*
G01X186162Y231359D02*
X186159Y231547D01*
G01X186165Y231120D02*
X186162Y231359D01*
G01X186168Y230838D02*
X186165Y231120D01*
G01X186169Y230521D02*
X186168Y230838D01*
G01X186171Y230180D02*
X186169Y230521D01*
G01X186171Y229826D02*
Y230180D01*
G01X186187Y227364D02*
X186197Y226999D01*
G01X186182Y227656D02*
X186187Y227364D01*
G01X186179Y228009D02*
X186182Y227656D01*
G01X186175Y228414D02*
X186179Y228009D01*
G01X186173Y228861D02*
X186175Y228414D01*
G01X186172Y229336D02*
X186173Y228861D01*
G01X186171Y229826D02*
X186172Y229336D01*
G01X186258Y225965D02*
X186269Y226239D01*
G01X186253Y225948D02*
X186258Y225965D01*
G01X186247Y226012D02*
X186253Y225948D01*
G01X186249Y220412D02*
X186238Y220365D01*
G01X186254Y220314D02*
X186249Y220412D01*
G01X186259Y220138D02*
X186254Y220314D01*
G01X186164Y217516D02*
X186162Y216551D01*
G01X186166Y217963D02*
X186164Y217516D01*
G01X186169Y218368D02*
X186166Y217963D01*
G01X186173Y218722D02*
X186169Y218368D01*
G01X186177Y219013D02*
X186173Y218722D01*
G01X186182Y219234D02*
X186177Y219013D01*
G01X186188Y219379D02*
X186182Y219234D01*
G01X186160Y215857D02*
X186162Y216551D01*
G01X186158Y215540D02*
X186160Y215857D01*
G01X186156Y215257D02*
X186158Y215540D01*
G01X186153Y215018D02*
X186156Y215257D01*
G01X186150Y214830D02*
X186153Y215018D01*
G01X186146Y214700D02*
X186150Y214830D01*
G01X186142Y214632D02*
X186146Y214700D01*
G01X186138Y214627D02*
X186142Y214632D01*
G01X186153Y217857D02*
X186151Y216570D01*
G01X186157Y218453D02*
X186153Y217857D01*
G01X186161Y218993D02*
X186157Y218453D01*
G01X186166Y219464D02*
X186161Y218993D01*
G01X186172Y219853D02*
X186166Y219464D01*
G01X186178Y220148D02*
X186172Y219853D01*
G01X186185Y220340D02*
X186178Y220148D01*
G01X186250Y221390D02*
X186236Y221327D01*
G01X186257Y221259D02*
X186250Y221390D01*
G01X186264Y221024D02*
X186257Y221259D01*
G01X184530Y221390D02*
X184516Y221024D01*
G01X184537Y221412D02*
X184530Y221390D01*
G01X184544Y221327D02*
X184537Y221412D01*
G01X184608Y219853D02*
X184595Y220340D01*
G01X184614Y219464D02*
X184608Y219853D01*
G01X184619Y218993D02*
X184614Y219464D01*
G01X184623Y218453D02*
X184619Y218993D01*
G01X184627Y217857D02*
X184623Y218453D01*
G01X184629Y217224D02*
X184627Y217857D01*
G01X184629Y216570D02*
Y217224D01*
G01X184634Y214700D02*
X184642Y214627D01*
G01X184630Y214830D02*
X184634Y214700D01*
G01X184627Y215018D02*
X184630Y214830D01*
G01X184624Y215257D02*
X184627Y215018D01*
G01X184622Y215540D02*
X184624Y215257D01*
G01X184620Y215857D02*
X184622Y215540D01*
G01X184619Y216198D02*
X184620Y215857D01*
G01X184618Y216551D02*
X184619Y216198D01*
G01X184603Y219013D02*
X184592Y219379D01*
G01X184607Y218722D02*
X184603Y219013D01*
G01X184611Y218368D02*
X184607Y218722D01*
G01X184614Y217963D02*
X184611Y218368D01*
G01X184616Y217516D02*
X184614Y217963D01*
G01X184618Y217041D02*
X184616Y217516D01*
G01X184618Y216551D02*
Y217041D01*
G01X184531Y220412D02*
X184521Y220138D01*
G01X184537Y220429D02*
X184531Y220412D01*
G01X184542Y220365D02*
X184537Y220429D01*
G01X180599Y225965D02*
X180610Y226012D01*
G01X180593Y226063D02*
X180599Y225965D01*
G01X180588Y226239D02*
X180593Y226063D01*
G01X180684Y228861D02*
X180686Y229826D01*
G01X180682Y228414D02*
X180684Y228861D01*
G01X180678Y228009D02*
X180682Y228414D01*
G01X180675Y227656D02*
X180678Y228009D01*
G01X180670Y227364D02*
X180675Y227656D01*
G01X180665Y227143D02*
X180670Y227364D01*
G01X180660Y226999D02*
X180665Y227143D01*
G01X180694Y228520D02*
X180697Y229807D01*
G01X180691Y227925D02*
X180694Y228520D01*
G01X180687Y227384D02*
X180691Y227925D01*
G01X180682Y226913D02*
X180687Y227384D01*
G01X180676Y226524D02*
X180682Y226913D01*
G01X180669Y226230D02*
X180676Y226524D01*
G01X180662Y226037D02*
X180669Y226230D01*
G01X180597Y224988D02*
X180612Y225050D01*
G01X180590Y225118D02*
X180597Y224988D01*
G01X180583Y225353D02*
X180590Y225118D01*
G01X182318Y224988D02*
X182332Y225353D01*
G01X182311Y224965D02*
X182318Y224988D01*
G01X182303Y225050D02*
X182311Y224965D01*
G01X182239Y226524D02*
X182253Y226037D01*
G01X182233Y226913D02*
X182239Y226524D01*
G01X182228Y227384D02*
X182233Y226913D01*
G01X182224Y227925D02*
X182228Y227384D01*
G01X182221Y228520D02*
X182224Y227925D01*
G01X182219Y229153D02*
X182221Y228520D01*
G01X182218Y229807D02*
X182219Y229153D01*
G01X182245Y227364D02*
X182255Y226999D01*
G01X182241Y227656D02*
X182245Y227364D01*
G01X182237Y228009D02*
X182241Y227656D01*
G01X182234Y228414D02*
X182237Y228009D01*
G01X182231Y228861D02*
X182234Y228414D01*
G01X182230Y229336D02*
X182231Y228861D01*
G01X182229Y229826D02*
X182230Y229336D01*
G01X182317Y225965D02*
X182327Y226239D01*
G01X182311Y225948D02*
X182317Y225965D01*
G01X182306Y226012D02*
X182311Y225948D01*
G01X182317Y220412D02*
X182306Y220365D01*
G01X182322Y220314D02*
X182317Y220412D01*
G01X182327Y220138D02*
X182322Y220314D01*
G01X182231Y217516D02*
X182229Y216551D01*
G01X182234Y217963D02*
X182231Y217516D01*
G01X182237Y218368D02*
X182234Y217963D01*
G01X182241Y218722D02*
X182237Y218368D01*
G01X182245Y219013D02*
X182241Y218722D01*
G01X182250Y219234D02*
X182245Y219013D01*
G01X182255Y219379D02*
X182250Y219234D01*
G01X182221Y217857D02*
X182218Y216570D01*
G01X182224Y218453D02*
X182221Y217857D01*
G01X182228Y218993D02*
X182224Y218453D01*
G01X182233Y219464D02*
X182228Y218993D01*
G01X182239Y219853D02*
X182233Y219464D01*
G01X182246Y220148D02*
X182239Y219853D01*
G01X182253Y220340D02*
X182246Y220148D01*
G01X182318Y221390D02*
X182303Y221327D01*
G01X182325Y221259D02*
X182318Y221390D01*
G01X182332Y221024D02*
X182325Y221259D01*
G01X180597Y221390D02*
X180583Y221024D01*
G01X180605Y221412D02*
X180597Y221390D01*
G01X180612Y221327D02*
X180605Y221412D01*
G01X180676Y219853D02*
X180662Y220340D01*
G01X180682Y219464D02*
X180676Y219853D01*
G01X180687Y218993D02*
X180682Y219464D01*
G01X180691Y218453D02*
X180687Y218993D01*
G01X180694Y217857D02*
X180691Y218453D01*
G01X180696Y217224D02*
X180694Y217857D01*
G01X180697Y216570D02*
X180696Y217224D01*
G01X180670Y219013D02*
X180660Y219379D01*
G01X180675Y218722D02*
X180670Y219013D01*
G01X180678Y218368D02*
X180675Y218722D01*
G01X180682Y217963D02*
X180678Y218368D01*
G01X180684Y217516D02*
X180682Y217963D01*
G01X180685Y217041D02*
X180684Y217516D01*
G01X180686Y216551D02*
X180685Y217041D01*
G01X180599Y220412D02*
X180588Y220138D01*
G01X180604Y220429D02*
X180599Y220412D01*
G01X180610Y220365D02*
X180604Y220429D01*
G01X176666Y225965D02*
X176677Y226012D01*
G01X176661Y226063D02*
X176666Y225965D01*
G01X176656Y226239D02*
X176661Y226063D01*
G01X176752Y228861D02*
X176754Y229826D01*
G01X176749Y228414D02*
X176752Y228861D01*
G01X176746Y228009D02*
X176749Y228414D01*
G01X176742Y227656D02*
X176746Y228009D01*
G01X176738Y227364D02*
X176742Y227656D01*
G01X176733Y227143D02*
X176738Y227364D01*
G01X176728Y226999D02*
X176733Y227143D01*
G01X176755Y230521D02*
X176754Y229826D01*
G01X176757Y230838D02*
X176755Y230521D01*
G01X176759Y231120D02*
X176757Y230838D01*
G01X176762Y231359D02*
X176759Y231120D01*
G01X176766Y231547D02*
X176762Y231359D01*
G01X176769Y231677D02*
X176766Y231547D01*
G01X176773Y231746D02*
X176769Y231677D01*
G01X176777Y231750D02*
X176773Y231746D01*
G01X176762Y228520D02*
X176765Y229807D01*
G01X176759Y227925D02*
X176762Y228520D01*
G01X176755Y227384D02*
X176759Y227925D01*
G01X176750Y226913D02*
X176755Y227384D01*
G01X176744Y226524D02*
X176750Y226913D01*
G01X176737Y226230D02*
X176744Y226524D01*
G01X176730Y226037D02*
X176737Y226230D01*
G01X176665Y224988D02*
X176680Y225050D01*
G01X176658Y225118D02*
X176665Y224988D01*
G01X176651Y225353D02*
X176658Y225118D01*
G01X178386Y224988D02*
X178399Y225353D01*
G01X178378Y224965D02*
X178386Y224988D01*
G01X178371Y225050D02*
X178378Y224965D01*
G01X178307Y226524D02*
X178321Y226037D01*
G01X178301Y226913D02*
X178307Y226524D01*
G01X178296Y227384D02*
X178301Y226913D01*
G01X178292Y227925D02*
X178296Y227384D01*
G01X178289Y228520D02*
X178292Y227925D01*
G01X178287Y229153D02*
X178289Y228520D01*
G01X178286Y229807D02*
X178287Y229153D01*
G01X178281Y231677D02*
X178273Y231750D01*
G01X178285Y231547D02*
X178281Y231677D01*
G01X178288Y231359D02*
X178285Y231547D01*
G01X178291Y231120D02*
X178288Y231359D01*
G01X178294Y230838D02*
X178291Y231120D01*
G01X178295Y230521D02*
X178294Y230838D01*
G01X178297Y230180D02*
X178295Y230521D01*
G01X178297Y229826D02*
Y230180D01*
G01X178313Y227364D02*
X178323Y226999D01*
G01X178308Y227656D02*
X178313Y227364D01*
G01X178304Y228009D02*
X178308Y227656D01*
G01X178301Y228414D02*
X178304Y228009D01*
G01X178299Y228861D02*
X178301Y228414D01*
G01X178298Y229336D02*
X178299Y228861D01*
G01X178297Y229826D02*
X178298Y229336D01*
G01X178384Y225965D02*
X178395Y226239D01*
G01X178379Y225948D02*
X178384Y225965D01*
G01X178373Y226012D02*
X178379Y225948D01*
G01X178375Y220412D02*
X178364Y220365D01*
G01X178380Y220314D02*
X178375Y220412D01*
G01X178385Y220138D02*
X178380Y220314D01*
G01X178290Y217516D02*
X178288Y216551D01*
G01X178292Y217963D02*
X178290Y217516D01*
G01X178295Y218368D02*
X178292Y217963D01*
G01X178299Y218722D02*
X178295Y218368D01*
G01X178303Y219013D02*
X178299Y218722D01*
G01X178308Y219234D02*
X178303Y219013D01*
G01X178314Y219379D02*
X178308Y219234D01*
G01X178286Y215857D02*
X178288Y216551D01*
G01X178284Y215540D02*
X178286Y215857D01*
G01X178282Y215257D02*
X178284Y215540D01*
G01X178279Y215018D02*
X178282Y215257D01*
G01X178276Y214830D02*
X178279Y215018D01*
G01X178272Y214700D02*
X178276Y214830D01*
G01X178268Y214632D02*
X178272Y214700D01*
G01X178264Y214627D02*
X178268Y214632D01*
G01X178279Y217857D02*
X178277Y216570D01*
G01X178283Y218453D02*
X178279Y217857D01*
G01X178287Y218993D02*
X178283Y218453D01*
G01X178292Y219464D02*
X178287Y218993D01*
G01X178298Y219853D02*
X178292Y219464D01*
G01X178304Y220148D02*
X178298Y219853D01*
G01X178311Y220340D02*
X178304Y220148D01*
G01X178376Y221390D02*
X178362Y221327D01*
G01X178383Y221259D02*
X178376Y221390D01*
G01X178390Y221024D02*
X178383Y221259D01*
G01X176656Y221390D02*
X176642Y221024D01*
G01X176663Y221412D02*
X176656Y221390D01*
G01X176670Y221327D02*
X176663Y221412D01*
G01X176734Y219853D02*
X176721Y220340D01*
G01X176740Y219464D02*
X176734Y219853D01*
G01X176745Y218993D02*
X176740Y219464D01*
G01X176749Y218453D02*
X176745Y218993D01*
G01X176753Y217857D02*
X176749Y218453D01*
G01X176755Y217224D02*
X176753Y217857D01*
G01X176755Y216570D02*
Y217224D01*
G01X176760Y214700D02*
X176768Y214627D01*
G01X176756Y214830D02*
X176760Y214700D01*
G01X176753Y215018D02*
X176756Y214830D01*
G01X176750Y215257D02*
X176753Y215018D01*
G01X176748Y215540D02*
X176750Y215257D01*
G01X176746Y215857D02*
X176748Y215540D01*
G01X176745Y216198D02*
X176746Y215857D01*
G01X176744Y216551D02*
X176745Y216198D01*
G01X176729Y219013D02*
X176718Y219379D01*
G01X176733Y218722D02*
X176729Y219013D01*
G01X176737Y218368D02*
X176733Y218722D01*
G01X176740Y217963D02*
X176737Y218368D01*
G01X176742Y217516D02*
X176740Y217963D01*
G01X176744Y217041D02*
X176742Y217516D01*
G01X176744Y216551D02*
Y217041D01*
G01X176657Y220412D02*
X176647Y220138D01*
G01X176662Y220429D02*
X176657Y220412D01*
G01X176668Y220365D02*
X176662Y220429D01*
G01X153044Y225965D02*
X153055Y226012D01*
G01X153039Y226063D02*
X153044Y225965D01*
G01X153034Y226239D02*
X153039Y226063D01*
G01X153130Y228861D02*
X153132Y229826D01*
G01X153127Y228414D02*
X153130Y228861D01*
G01X153124Y228009D02*
X153127Y228414D01*
G01X153120Y227656D02*
X153124Y228009D01*
G01X153116Y227364D02*
X153120Y227656D01*
G01X153111Y227143D02*
X153116Y227364D01*
G01X153106Y226999D02*
X153111Y227143D01*
G01X153133Y230521D02*
X153132Y229826D01*
G01X153135Y230838D02*
X153133Y230521D01*
G01X153137Y231120D02*
X153135Y230838D01*
G01X153140Y231359D02*
X153137Y231120D01*
G01X153144Y231547D02*
X153140Y231359D01*
G01X153147Y231677D02*
X153144Y231547D01*
G01X153151Y231746D02*
X153147Y231677D01*
G01X153155Y231750D02*
X153151Y231746D01*
G01X153140Y228520D02*
X153143Y229807D01*
G01X153137Y227925D02*
X153140Y228520D01*
G01X153133Y227384D02*
X153137Y227925D01*
G01X153127Y226913D02*
X153133Y227384D01*
G01X153122Y226524D02*
X153127Y226913D01*
G01X153115Y226230D02*
X153122Y226524D01*
G01X153108Y226037D02*
X153115Y226230D01*
G01X153043Y224988D02*
X153058Y225050D01*
G01X153036Y225118D02*
X153043Y224988D01*
G01X153029Y225353D02*
X153036Y225118D01*
G01X154764Y224988D02*
X154777Y225353D01*
G01X154756Y224965D02*
X154764Y224988D01*
G01X154749Y225050D02*
X154756Y224965D01*
G01X154685Y226524D02*
X154699Y226037D01*
G01X154679Y226913D02*
X154685Y226524D01*
G01X154674Y227384D02*
X154679Y226913D01*
G01X154670Y227925D02*
X154674Y227384D01*
G01X154667Y228520D02*
X154670Y227925D01*
G01X154665Y229153D02*
X154667Y228520D01*
G01X154664Y229807D02*
X154665Y229153D01*
G01X154659Y231677D02*
X154651Y231750D01*
G01X154663Y231547D02*
X154659Y231677D01*
G01X154666Y231359D02*
X154663Y231547D01*
G01X154669Y231120D02*
X154666Y231359D01*
G01X154672Y230838D02*
X154669Y231120D01*
G01X154673Y230521D02*
X154672Y230838D01*
G01X154675Y230180D02*
X154673Y230521D01*
G01X154675Y229826D02*
Y230180D01*
G01X154691Y227364D02*
X154701Y226999D01*
G01X154686Y227656D02*
X154691Y227364D01*
G01X154682Y228009D02*
X154686Y227656D01*
G01X154679Y228414D02*
X154682Y228009D01*
G01X154677Y228861D02*
X154679Y228414D01*
G01X154676Y229336D02*
X154677Y228861D01*
G01X154675Y229826D02*
X154676Y229336D01*
G01X154762Y225965D02*
X154773Y226239D01*
G01X154757Y225948D02*
X154762Y225965D01*
G01X154751Y226012D02*
X154757Y225948D01*
G01X154753Y220412D02*
X154742Y220365D01*
G01X154758Y220314D02*
X154753Y220412D01*
G01X154763Y220138D02*
X154758Y220314D01*
G01X154668Y217516D02*
X154666Y216551D01*
G01X154670Y217963D02*
X154668Y217516D01*
G01X154673Y218368D02*
X154670Y217963D01*
G01X154677Y218722D02*
X154673Y218368D01*
G01X154681Y219013D02*
X154677Y218722D01*
G01X154686Y219234D02*
X154681Y219013D01*
G01X154692Y219379D02*
X154686Y219234D01*
G01X154664Y215857D02*
X154666Y216551D01*
G01X154662Y215540D02*
X154664Y215857D01*
G01X154660Y215257D02*
X154662Y215540D01*
G01X154657Y215018D02*
X154660Y215257D01*
G01X154654Y214830D02*
X154657Y215018D01*
G01X154650Y214700D02*
X154654Y214830D01*
G01X154646Y214632D02*
X154650Y214700D01*
G01X154642Y214627D02*
X154646Y214632D01*
G01X154657Y217857D02*
X154655Y216570D01*
G01X154660Y218453D02*
X154657Y217857D01*
G01X154665Y218993D02*
X154660Y218453D01*
G01X154670Y219464D02*
X154665Y218993D01*
G01X154676Y219853D02*
X154670Y219464D01*
G01X154682Y220148D02*
X154676Y219853D01*
G01X154689Y220340D02*
X154682Y220148D01*
G01X154754Y221390D02*
X154740Y221327D01*
G01X154761Y221259D02*
X154754Y221390D01*
G01X154768Y221024D02*
X154761Y221259D01*
G01X153034Y221390D02*
X153020Y221024D01*
G01X153041Y221412D02*
X153034Y221390D01*
G01X153048Y221327D02*
X153041Y221412D01*
G01X153112Y219853D02*
X153099Y220340D01*
G01X153118Y219464D02*
X153112Y219853D01*
G01X153123Y218993D02*
X153118Y219464D01*
G01X153127Y218453D02*
X153123Y218993D01*
G01X153131Y217857D02*
X153127Y218453D01*
G01X153132Y217224D02*
X153131Y217857D01*
G01X153133Y216570D02*
X153132Y217224D01*
G01X153138Y214700D02*
X153146Y214627D01*
G01X153134Y214830D02*
X153138Y214700D01*
G01X153131Y215018D02*
X153134Y214830D01*
G01X153128Y215257D02*
X153131Y215018D01*
G01X153126Y215540D02*
X153128Y215257D01*
G01X153124Y215857D02*
X153126Y215540D01*
G01X153123Y216198D02*
X153124Y215857D01*
G01X153122Y216551D02*
X153123Y216198D01*
G01X153107Y219013D02*
X153096Y219379D01*
G01X153111Y218722D02*
X153107Y219013D01*
G01X153115Y218368D02*
X153111Y218722D01*
G01X153118Y217963D02*
X153115Y218368D01*
G01X153120Y217516D02*
X153118Y217963D01*
G01X153122Y217041D02*
X153120Y217516D01*
G01X153122Y216551D02*
Y217041D01*
G01X153035Y220412D02*
X153025Y220138D01*
G01X153040Y220429D02*
X153035Y220412D01*
G01X153046Y220365D02*
X153040Y220429D01*
G01X125481Y225965D02*
X125491Y226012D01*
G01X125475Y226063D02*
X125481Y225965D01*
G01X125470Y226239D02*
X125475Y226063D01*
G01X125566Y228861D02*
X125568Y229826D01*
G01X125564Y228414D02*
X125566Y228861D01*
G01X125560Y228009D02*
X125564Y228414D01*
G01X125557Y227656D02*
X125560Y228009D01*
G01X125552Y227364D02*
X125557Y227656D01*
G01X125547Y227143D02*
X125552Y227364D01*
G01X125542Y226999D02*
X125547Y227143D01*
G01X125576Y228520D02*
X125579Y229807D01*
G01X125573Y227925D02*
X125576Y228520D01*
G01X125569Y227384D02*
X125573Y227925D01*
G01X125564Y226913D02*
X125569Y227384D01*
G01X125558Y226524D02*
X125564Y226913D01*
G01X125551Y226230D02*
X125558Y226524D01*
G01X125544Y226037D02*
X125551Y226230D01*
G01X125479Y224988D02*
X125494Y225050D01*
G01X125472Y225118D02*
X125479Y224988D01*
G01X125465Y225353D02*
X125472Y225118D01*
G01X127200Y224988D02*
X127214Y225353D01*
G01X127193Y224965D02*
X127200Y224988D01*
G01X127185Y225050D02*
X127193Y224965D01*
G01X127121Y226524D02*
X127135Y226037D01*
G01X127115Y226913D02*
X127121Y226524D01*
G01X127110Y227384D02*
X127115Y226913D01*
G01X127106Y227925D02*
X127110Y227384D01*
G01X127103Y228520D02*
X127106Y227925D01*
G01X127101Y229153D02*
X127103Y228520D01*
G01X127100Y229807D02*
X127101Y229153D01*
G01X127127Y227364D02*
X127137Y226999D01*
G01X127123Y227656D02*
X127127Y227364D01*
G01X127119Y228009D02*
X127123Y227656D01*
G01X127116Y228414D02*
X127119Y228009D01*
G01X127113Y228861D02*
X127116Y228414D01*
G01X127112Y229336D02*
X127113Y228861D01*
G01X127111Y229826D02*
X127112Y229336D01*
G01X127199Y225965D02*
X127209Y226239D01*
G01X127193Y225948D02*
X127199Y225965D01*
G01X127188Y226012D02*
X127193Y225948D01*
G01X127088Y231754D02*
Y231750D01*
G01X127089Y231756D02*
X127088Y231754D01*
G01X134962D02*
Y231750D01*
G01X134963Y231756D02*
X134962Y231754D01*
G01X121383Y214965D02*
X121387Y215117D01*
G01X121379Y214866D02*
X121383Y214965D01*
G01X121374Y214824D02*
X121379Y214866D01*
G01X123422Y231413D02*
X123418Y231260D01*
G01X123426Y231511D02*
X123422Y231413D01*
G01X123431Y231553D02*
X123426Y231511D01*
G01X123419Y232353D02*
X123413Y232147D01*
G01X123425Y232484D02*
X123419Y232353D01*
G01X123431Y232538D02*
X123425Y232484D01*
G01X121386Y214024D02*
X121392Y214231D01*
G01X121380Y213893D02*
X121386Y214024D01*
G01X121374Y213840D02*
X121380Y213893D01*
G01X121648Y230209D02*
X121647Y229807D01*
G01X121650Y230537D02*
X121648Y230209D01*
G01X121654Y230733D02*
X121650Y230537D01*
G01X121659Y230762D02*
X121654Y230733D01*
G01X123158Y216168D02*
X123159Y216570D01*
G01X123155Y215841D02*
X123158Y216168D01*
G01X123151Y215645D02*
X123155Y215841D01*
G01X123146Y215615D02*
X123151Y215645D01*
G01X129522Y230209D02*
X129521Y229807D01*
G01X129524Y230537D02*
X129522Y230209D01*
G01X129528Y230733D02*
X129524Y230537D01*
G01X129533Y230762D02*
X129528Y230733D01*
G01X125591Y214624D02*
X125592Y214627D01*
G01X125590Y214622D02*
X125591Y214624D01*
G01X125590Y214621D02*
Y214622D01*
G01X142836Y231754D02*
Y231750D01*
G01X142837Y231756D02*
X142836Y231754D01*
G01X133465Y214624D02*
X133466Y214627D01*
G01X133464Y214622D02*
X133465Y214624D01*
G01X133464Y214621D02*
Y214622D01*
G01X150710Y231754D02*
Y231750D01*
G01X150711Y231756D02*
X150710Y231754D01*
G01X141339Y214624D02*
X141340Y214627D01*
G01X141338Y214622D02*
X141339Y214624D01*
G01X141338Y214621D02*
Y214622D01*
G01X158584Y231754D02*
Y231750D01*
G01X158585Y231756D02*
X158584Y231754D01*
G01X149213Y214624D02*
X149214Y214627D01*
G01X149212Y214622D02*
X149213Y214624D01*
G01X149212Y214621D02*
Y214622D01*
G01X125580Y216197D02*
X125579Y216570D01*
G01X125582Y215887D02*
X125580Y216197D01*
G01X125586Y215680D02*
X125582Y215887D01*
G01X125590Y215605D02*
X125586Y215680D01*
G01X121390Y232484D02*
X121384Y232538D01*
G01X121396Y232353D02*
X121390Y232484D01*
G01X121402Y232147D02*
X121396Y232353D01*
G01X123415Y213893D02*
X123421Y213840D01*
G01X123409Y214024D02*
X123415Y213893D01*
G01X123403Y214231D02*
X123409Y214024D01*
G01X125322Y232484D02*
X125316Y232538D01*
G01X125328Y232353D02*
X125322Y232484D01*
G01X125334Y232147D02*
X125328Y232353D01*
G01X127357Y213893D02*
X127363Y213840D01*
G01X127351Y214024D02*
X127357Y213893D01*
G01X127345Y214231D02*
X127351Y214024D01*
G01X129264Y232484D02*
X129258Y232538D01*
G01X129270Y232353D02*
X129264Y232484D01*
G01X129276Y232147D02*
X129270Y232353D01*
G01X121388Y231511D02*
X121384Y231553D01*
G01X121393Y231413D02*
X121388Y231511D01*
G01X121397Y231260D02*
X121393Y231413D01*
G01X123417Y214866D02*
X123421Y214824D01*
G01X123413Y214965D02*
X123417Y214866D01*
G01X123408Y215117D02*
X123413Y214965D01*
G01X125320Y231511D02*
X125316Y231553D01*
G01X125325Y231413D02*
X125320Y231511D01*
G01X125329Y231260D02*
X125325Y231413D01*
G01X127359Y214866D02*
X127363Y214824D01*
G01X127354Y214965D02*
X127359Y214866D01*
G01X127350Y215117D02*
X127354Y214965D01*
G01X129262Y231511D02*
X129258Y231553D01*
G01X129267Y231413D02*
X129262Y231511D01*
G01X129271Y231260D02*
X129267Y231413D01*
G01X121645Y215645D02*
X121650Y215615D01*
G01X121641Y215841D02*
X121645Y215645D01*
G01X121638Y216168D02*
X121641Y215841D01*
G01X121637Y216570D02*
X121638Y216168D01*
G01X123160Y230733D02*
X123155Y230762D01*
G01X123164Y230537D02*
X123160Y230733D01*
G01X123167Y230209D02*
X123164Y230537D01*
G01X123168Y229807D02*
X123167Y230209D01*
G01X129519Y215645D02*
X129524Y215615D01*
G01X129515Y215841D02*
X129519Y215645D01*
G01X129512Y216168D02*
X129515Y215841D01*
G01X129511Y216570D02*
X129512Y216168D01*
G01X131034Y230733D02*
X131029Y230762D01*
G01X131038Y230537D02*
X131034Y230733D01*
G01X131041Y230209D02*
X131038Y230537D01*
G01X131042Y229807D02*
X131041Y230209D01*
G01X125581Y214770D02*
X125590Y214621D01*
G01X125574Y215184D02*
X125581Y214770D01*
G01X125570Y215804D02*
X125574Y215184D01*
G01X125568Y216551D02*
X125570Y215804D01*
G01X127098Y231608D02*
X127089Y231756D01*
G01X127105Y231193D02*
X127098Y231608D01*
G01X127109Y230573D02*
X127105Y231193D01*
G01X127111Y229826D02*
X127109Y230573D01*
G01X133455Y214770D02*
X133464Y214621D01*
G01X133448Y215184D02*
X133455Y214770D01*
G01X133444Y215804D02*
X133448Y215184D01*
G01X133442Y216551D02*
X133444Y215804D01*
G01X125586Y230698D02*
X125590Y230772D01*
G01X125582Y230490D02*
X125586Y230698D01*
G01X125580Y230180D02*
X125582Y230490D01*
G01X125579Y229807D02*
X125580Y230180D01*
G01X127093Y215680D02*
X127089Y215605D01*
G01X127097Y215887D02*
X127093Y215680D01*
G01X127099Y216197D02*
X127097Y215887D01*
G01X127100Y216570D02*
X127099Y216197D01*
G01X133460Y230698D02*
X133464Y230772D01*
G01X133456Y230490D02*
X133460Y230698D01*
G01X133454Y230180D02*
X133456Y230490D01*
G01X133453Y229807D02*
X133454Y230180D01*
G01X134967Y215680D02*
X134963Y215605D01*
G01X134971Y215887D02*
X134967Y215680D01*
G01X134973Y216197D02*
X134971Y215887D01*
G01X134974Y216570D02*
X134973Y216197D01*
G01X125570Y230573D02*
X125568Y229826D01*
G01X125574Y231193D02*
X125570Y230573D01*
G01X125581Y231608D02*
X125574Y231193D01*
G01X125590Y231756D02*
X125581Y231608D01*
G01X127109Y215804D02*
X127111Y216551D01*
G01X127105Y215184D02*
X127109Y215804D01*
G01X127098Y214770D02*
X127105Y215184D01*
G01X127089Y214621D02*
X127098Y214770D01*
G01X133444Y230573D02*
X133442Y229826D01*
G01X133448Y231193D02*
X133444Y230573D01*
G01X133455Y231608D02*
X133448Y231193D01*
G01X133464Y231756D02*
X133455Y231608D01*
G01X134983Y215804D02*
X134985Y216551D01*
G01X134979Y215184D02*
X134983Y215804D01*
G01X134972Y214770D02*
X134979Y215184D01*
G01X134963Y214621D02*
X134972Y214770D01*
G01X141318Y230573D02*
X141316Y229826D01*
G01X141322Y231193D02*
X141318Y230573D01*
G01X141329Y231608D02*
X141322Y231193D01*
G01X141338Y231756D02*
X141329Y231608D01*
G01X125590Y215606D02*
Y215605D01*
G01X125591Y215610D02*
X125590Y215606D01*
G01X125592Y215617D02*
X125591Y215610D01*
G01X127089Y230771D02*
Y230772D01*
G01X127088Y230768D02*
X127089Y230771D01*
G01X127088Y230760D02*
Y230768D01*
G01X133464Y215606D02*
Y215605D01*
G01X133465Y215610D02*
X133464Y215606D01*
G01X133466Y215617D02*
X133465Y215610D01*
G01X134963Y230771D02*
Y230772D01*
G01X134962Y230768D02*
X134963Y230771D01*
G01X134962Y230760D02*
Y230768D01*
G01X141338Y215606D02*
Y215605D01*
G01X141339Y215610D02*
X141338Y215606D01*
G01X141340Y215617D02*
X141339Y215610D01*
G01X142837Y230771D02*
Y230772D01*
G01X142836Y230768D02*
X142837Y230771D01*
G01X142836Y230760D02*
Y230768D01*
G01X125325Y214965D02*
X125329Y215117D01*
G01X125320Y214866D02*
X125325Y214965D01*
G01X125316Y214824D02*
X125320Y214866D01*
G01X127354Y231413D02*
X127350Y231260D01*
G01X127359Y231511D02*
X127354Y231413D01*
G01X127363Y231553D02*
X127359Y231511D01*
G01X129257Y214965D02*
X129261Y215117D01*
G01X129253Y214866D02*
X129257Y214965D01*
G01X129248Y214824D02*
X129253Y214866D01*
G01X131296Y231413D02*
X131292Y231260D01*
G01X131300Y231511D02*
X131296Y231413D01*
G01X131305Y231553D02*
X131300Y231511D01*
G01X133199Y214965D02*
X133203Y215117D01*
G01X133194Y214866D02*
X133199Y214965D01*
G01X133190Y214824D02*
X133194Y214866D01*
G01X135228Y231413D02*
X135224Y231260D01*
G01X135233Y231511D02*
X135228Y231413D01*
G01X135237Y231553D02*
X135233Y231511D01*
G01X137131Y214965D02*
X137135Y215117D01*
G01X137127Y214866D02*
X137131Y214965D01*
G01X137122Y214824D02*
X137127Y214866D01*
G01X139170Y231413D02*
X139166Y231260D01*
G01X139174Y231511D02*
X139170Y231413D01*
G01X139179Y231553D02*
X139174Y231511D01*
G01X141073Y214965D02*
X141077Y215117D01*
G01X141069Y214866D02*
X141073Y214965D01*
G01X141064Y214824D02*
X141069Y214866D01*
G01X143102Y231413D02*
X143098Y231260D01*
G01X143107Y231511D02*
X143102Y231413D01*
G01X143111Y231553D02*
X143107Y231511D01*
G01X145005Y214965D02*
X145009Y215117D01*
G01X145001Y214866D02*
X145005Y214965D01*
G01X144996Y214824D02*
X145001Y214866D01*
G01X147044Y231413D02*
X147040Y231260D01*
G01X147048Y231511D02*
X147044Y231413D01*
G01X147053Y231553D02*
X147048Y231511D01*
G01X127351Y232353D02*
X127345Y232147D01*
G01X127357Y232484D02*
X127351Y232353D01*
G01X127363Y232538D02*
X127357Y232484D01*
G01X125328Y214024D02*
X125334Y214231D01*
G01X125322Y213893D02*
X125328Y214024D01*
G01X125316Y213840D02*
X125322Y213893D01*
G01X131293Y232353D02*
X131287Y232147D01*
G01X131299Y232484D02*
X131293Y232353D01*
G01X131305Y232538D02*
X131299Y232484D01*
G01X129260Y214024D02*
X129266Y214231D01*
G01X129254Y213893D02*
X129260Y214024D01*
G01X129248Y213840D02*
X129254Y213893D01*
G01X135225Y232353D02*
X135219Y232147D01*
G01X135231Y232484D02*
X135225Y232353D01*
G01X135237Y232538D02*
X135231Y232484D01*
G01X133202Y214024D02*
X133208Y214231D01*
G01X133196Y213893D02*
X133202Y214024D01*
G01X133190Y213840D02*
X133196Y213893D01*
G01X139167Y232353D02*
X139161Y232147D01*
G01X139173Y232484D02*
X139167Y232353D01*
G01X139179Y232538D02*
X139173Y232484D01*
G01X137135Y214024D02*
X137140Y214231D01*
G01X137128Y213893D02*
X137135Y214024D01*
G01X137122Y213840D02*
X137128Y213893D01*
G01X143099Y232353D02*
X143093Y232147D01*
G01X143105Y232484D02*
X143099Y232353D01*
G01X143111Y232538D02*
X143105Y232484D01*
G01X141076Y214024D02*
X141082Y214231D01*
G01X141070Y213893D02*
X141076Y214024D01*
G01X141064Y213840D02*
X141070Y213893D01*
G01X147041Y232353D02*
X147035Y232147D01*
G01X147047Y232484D02*
X147041Y232353D01*
G01X147053Y232538D02*
X147047Y232484D01*
G01X145009Y214024D02*
X145014Y214231D01*
G01X145002Y213893D02*
X145009Y214024D01*
G01X144996Y213840D02*
X145002Y213893D01*
G01X131032Y216168D02*
X131033Y216570D01*
G01X131029Y215841D02*
X131032Y216168D01*
G01X131025Y215645D02*
X131029Y215841D01*
G01X131020Y215615D02*
X131025Y215645D01*
G01X137396Y230209D02*
X137395Y229807D01*
G01X137398Y230537D02*
X137396Y230209D01*
G01X137402Y230733D02*
X137398Y230537D01*
G01X137407Y230762D02*
X137402Y230733D01*
G01X138906Y216168D02*
X138907Y216570D01*
G01X138903Y215841D02*
X138906Y216168D01*
G01X138899Y215645D02*
X138903Y215841D01*
G01X138894Y215615D02*
X138899Y215645D01*
G01X145270Y230209D02*
X145269Y229807D01*
G01X145272Y230537D02*
X145270Y230209D01*
G01X145276Y230733D02*
X145272Y230537D01*
G01X145281Y230762D02*
X145276Y230733D01*
G01X146780Y216168D02*
X146781Y216570D01*
G01X146777Y215841D02*
X146780Y216168D01*
G01X146773Y215645D02*
X146777Y215841D01*
G01X146768Y215615D02*
X146773Y215645D01*
G01X153144Y230209D02*
X153143Y229807D01*
G01X153146Y230537D02*
X153144Y230209D01*
G01X153150Y230733D02*
X153146Y230537D01*
G01X153155Y230762D02*
X153150Y230733D01*
G01X157087Y214624D02*
X157088Y214627D01*
G01X157086Y214622D02*
X157087Y214624D01*
G01X157086Y214621D02*
Y214622D01*
G01X174332Y231754D02*
Y231750D01*
G01X174333Y231756D02*
X174332Y231754D01*
G01X182206D02*
Y231750D01*
G01X182207Y231756D02*
X182206Y231754D01*
G01X172835Y214624D02*
X172836Y214627D01*
G01X172834Y214622D02*
X172835Y214624D01*
G01X172834Y214621D02*
Y214622D01*
G01X180709Y214624D02*
X180710Y214627D01*
G01X180708Y214622D02*
X180709Y214624D01*
G01X180708Y214621D02*
Y214622D01*
G01X170745Y226142D02*
X171123Y226314D01*
G01X170377Y225965D02*
X170745Y226142D01*
G01X170021Y225782D02*
X170377Y225965D01*
G01X127099Y230180D02*
X127100Y229807D01*
G01X127097Y230490D02*
X127099Y230180D01*
G01X127093Y230698D02*
X127097Y230490D01*
G01X127089Y230772D02*
X127093Y230698D01*
G01X133454Y216197D02*
X133453Y216570D01*
G01X133456Y215887D02*
X133454Y216197D01*
G01X133460Y215680D02*
X133456Y215887D01*
G01X133464Y215605D02*
X133460Y215680D01*
G01X134973Y230180D02*
X134974Y229807D01*
G01X134971Y230490D02*
X134973Y230180D01*
G01X134967Y230698D02*
X134971Y230490D01*
G01X134963Y230772D02*
X134967Y230698D01*
G01X141328Y216197D02*
X141327Y216570D01*
G01X141330Y215887D02*
X141328Y216197D01*
G01X141334Y215680D02*
X141330Y215887D01*
G01X141338Y215605D02*
X141334Y215680D01*
G01X142847Y230180D02*
X142848Y229807D01*
G01X142845Y230490D02*
X142847Y230180D01*
G01X142841Y230698D02*
X142845Y230490D01*
G01X142837Y230772D02*
X142841Y230698D01*
G01X149202Y216197D02*
X149201Y216570D01*
G01X149204Y215887D02*
X149202Y216197D01*
G01X149208Y215680D02*
X149204Y215887D01*
G01X149212Y215605D02*
X149208Y215680D01*
G01X150721Y230180D02*
X150722Y229807D01*
G01X150719Y230490D02*
X150721Y230180D01*
G01X150716Y230698D02*
X150719Y230490D01*
G01X150711Y230772D02*
X150716Y230698D01*
G01X131289Y213893D02*
X131295Y213840D01*
G01X131283Y214024D02*
X131289Y213893D01*
G01X131278Y214231D02*
X131283Y214024D01*
G01X133196Y232484D02*
X133190Y232538D01*
G01X133202Y232353D02*
X133196Y232484D01*
G01X133208Y232147D02*
X133202Y232353D01*
G01X135231Y213893D02*
X135237Y213840D01*
G01X135225Y214024D02*
X135231Y213893D01*
G01X135219Y214231D02*
X135225Y214024D01*
G01X137138Y232484D02*
X137132Y232538D01*
G01X137144Y232353D02*
X137138Y232484D01*
G01X137150Y232147D02*
X137144Y232353D01*
G01X139163Y213893D02*
X139170Y213840D01*
G01X139157Y214024D02*
X139163Y213893D01*
G01X139152Y214231D02*
X139157Y214024D01*
G01X141070Y232484D02*
X141064Y232538D01*
G01X141076Y232353D02*
X141070Y232484D01*
G01X141082Y232147D02*
X141076Y232353D01*
G01X143105Y213893D02*
X143111Y213840D01*
G01X143099Y214024D02*
X143105Y213893D01*
G01X143093Y214231D02*
X143099Y214024D01*
G01X145012Y232484D02*
X145006Y232538D01*
G01X145018Y232353D02*
X145012Y232484D01*
G01X145024Y232147D02*
X145018Y232353D01*
G01X147037Y213893D02*
X147044Y213840D01*
G01X147031Y214024D02*
X147037Y213893D01*
G01X147026Y214231D02*
X147031Y214024D01*
G01X148944Y232484D02*
X148938Y232538D01*
G01X148950Y232353D02*
X148944Y232484D01*
G01X148956Y232147D02*
X148950Y232353D01*
G01X150979Y213893D02*
X150985Y213840D01*
G01X150973Y214024D02*
X150979Y213893D01*
G01X150967Y214231D02*
X150973Y214024D01*
G01X152886Y232484D02*
X152880Y232538D01*
G01X152892Y232353D02*
X152886Y232484D01*
G01X152898Y232147D02*
X152892Y232353D01*
G01X154911Y213893D02*
X154918Y213840D01*
G01X154905Y214024D02*
X154911Y213893D01*
G01X154900Y214231D02*
X154905Y214024D01*
G01X131291Y214866D02*
X131296Y214824D01*
G01X131287Y214965D02*
X131291Y214866D01*
G01X131282Y215117D02*
X131287Y214965D01*
G01X133194Y231511D02*
X133190Y231553D01*
G01X133199Y231413D02*
X133194Y231511D01*
G01X133203Y231260D02*
X133199Y231413D01*
G01X135233Y214866D02*
X135237Y214824D01*
G01X135228Y214965D02*
X135233Y214866D01*
G01X135224Y215117D02*
X135228Y214965D01*
G01X137136Y231511D02*
X137132Y231553D01*
G01X137141Y231413D02*
X137136Y231511D01*
G01X137145Y231260D02*
X137141Y231413D01*
G01X139165Y214866D02*
X139170Y214824D01*
G01X139161Y214965D02*
X139165Y214866D01*
G01X139156Y215117D02*
X139161Y214965D01*
G01X141069Y231511D02*
X141064Y231553D01*
G01X141073Y231413D02*
X141069Y231511D01*
G01X141077Y231260D02*
X141073Y231413D01*
G01X143107Y214866D02*
X143111Y214824D01*
G01X143102Y214965D02*
X143107Y214866D01*
G01X143098Y215117D02*
X143102Y214965D01*
G01X145010Y231511D02*
X145006Y231553D01*
G01X145015Y231413D02*
X145010Y231511D01*
G01X145019Y231260D02*
X145015Y231413D01*
G01X147039Y214866D02*
X147044Y214824D01*
G01X147035Y214965D02*
X147039Y214866D01*
G01X147030Y215117D02*
X147035Y214965D01*
G01X148943Y231511D02*
X148938Y231553D01*
G01X148947Y231413D02*
X148943Y231511D01*
G01X148951Y231260D02*
X148947Y231413D01*
G01X150981Y214866D02*
X150985Y214824D01*
G01X150976Y214965D02*
X150981Y214866D01*
G01X150972Y215117D02*
X150976Y214965D01*
G01X152884Y231511D02*
X152880Y231553D01*
G01X152889Y231413D02*
X152884Y231511D01*
G01X152893Y231260D02*
X152889Y231413D01*
G01X154913Y214866D02*
X154918Y214824D01*
G01X154909Y214965D02*
X154913Y214866D01*
G01X154904Y215117D02*
X154909Y214965D01*
G01X137393Y215645D02*
X137398Y215615D01*
G01X137389Y215841D02*
X137393Y215645D01*
G01X137386Y216168D02*
X137389Y215841D01*
G01X137385Y216570D02*
X137386Y216168D01*
G01X138908Y230733D02*
X138903Y230762D01*
G01X138912Y230537D02*
X138908Y230733D01*
G01X138915Y230209D02*
X138912Y230537D01*
G01X138916Y229807D02*
X138915Y230209D01*
G01X145267Y215645D02*
X145272Y215615D01*
G01X145263Y215841D02*
X145267Y215645D01*
G01X145260Y216168D02*
X145263Y215841D01*
G01X145259Y216570D02*
X145260Y216168D01*
G01X146782Y230733D02*
X146777Y230762D01*
G01X146786Y230537D02*
X146782Y230733D01*
G01X146789Y230209D02*
X146786Y230537D01*
G01X146790Y229807D02*
X146789Y230209D01*
G01X153141Y215645D02*
X153146Y215615D01*
G01X153137Y215841D02*
X153141Y215645D01*
G01X153134Y216168D02*
X153137Y215841D01*
G01X153133Y216570D02*
X153134Y216168D01*
G01X154656Y230733D02*
X154651Y230762D01*
G01X154660Y230537D02*
X154656Y230733D01*
G01X154663Y230209D02*
X154660Y230537D01*
G01X154664Y229807D02*
X154663Y230209D01*
G01X134972Y231608D02*
X134963Y231756D01*
G01X134979Y231193D02*
X134972Y231608D01*
G01X134983Y230573D02*
X134979Y231193D01*
G01X134985Y229826D02*
X134983Y230573D01*
G01X141329Y214770D02*
X141338Y214621D01*
G01X141322Y215184D02*
X141329Y214770D01*
G01X141318Y215804D02*
X141322Y215184D01*
G01X141316Y216551D02*
X141318Y215804D01*
G01X142846Y231608D02*
X142837Y231756D01*
G01X142853Y231193D02*
X142846Y231608D01*
G01X142857Y230573D02*
X142853Y231193D01*
G01X142859Y229826D02*
X142857Y230573D01*
G01X149203Y214770D02*
X149212Y214621D01*
G01X149196Y215184D02*
X149203Y214770D01*
G01X149192Y215804D02*
X149196Y215184D01*
G01X149190Y216551D02*
X149192Y215804D01*
G01X150720Y231608D02*
X150711Y231756D01*
G01X150727Y231193D02*
X150720Y231608D01*
G01X150731Y230573D02*
X150727Y231193D01*
G01X150733Y229826D02*
X150731Y230573D01*
G01X157078Y214770D02*
X157086Y214621D01*
G01X157071Y215184D02*
X157078Y214770D01*
G01X157066Y215804D02*
X157071Y215184D01*
G01X157064Y216551D02*
X157066Y215804D01*
G01X158594Y231608D02*
X158585Y231756D01*
G01X158601Y231193D02*
X158594Y231608D01*
G01X158605Y230573D02*
X158601Y231193D01*
G01X158607Y229826D02*
X158605Y230573D01*
G01X141334Y230698D02*
X141338Y230772D01*
G01X141330Y230490D02*
X141334Y230698D01*
G01X141328Y230180D02*
X141330Y230490D01*
G01X141327Y229807D02*
X141328Y230180D01*
G01X142841Y215680D02*
X142837Y215605D01*
G01X142845Y215887D02*
X142841Y215680D01*
G01X142847Y216197D02*
X142845Y215887D01*
G01X142848Y216570D02*
X142847Y216197D01*
G01X149208Y230698D02*
X149212Y230772D01*
G01X149204Y230490D02*
X149208Y230698D01*
G01X149202Y230180D02*
X149204Y230490D01*
G01X149201Y229807D02*
X149202Y230180D01*
G01X150716Y215680D02*
X150711Y215605D01*
G01X150719Y215887D02*
X150716Y215680D01*
G01X150721Y216197D02*
X150719Y215887D01*
G01X150722Y216570D02*
X150721Y216197D01*
G01X157082Y230698D02*
X157086Y230772D01*
G01X157078Y230490D02*
X157082Y230698D01*
G01X157076Y230180D02*
X157078Y230490D01*
G01X157075Y229807D02*
X157076Y230180D01*
G01X158590Y215680D02*
X158585Y215605D01*
G01X158593Y215887D02*
X158590Y215680D01*
G01X158595Y216197D02*
X158593Y215887D01*
G01X158596Y216570D02*
X158595Y216197D01*
G01X142857Y215804D02*
X142859Y216551D01*
G01X142853Y215184D02*
X142857Y215804D01*
G01X142846Y214770D02*
X142853Y215184D01*
G01X142837Y214621D02*
X142846Y214770D01*
G01X149192Y230573D02*
X149190Y229826D01*
G01X149196Y231193D02*
X149192Y230573D01*
G01X149203Y231608D02*
X149196Y231193D01*
G01X149212Y231756D02*
X149203Y231608D01*
G01X150731Y215804D02*
X150733Y216551D01*
G01X150727Y215184D02*
X150731Y215804D01*
G01X150720Y214770D02*
X150727Y215184D01*
G01X150711Y214621D02*
X150720Y214770D01*
G01X157066Y230573D02*
X157064Y229826D01*
G01X157071Y231193D02*
X157066Y230573D01*
G01X157078Y231608D02*
X157071Y231193D01*
G01X157086Y231756D02*
X157078Y231608D01*
G01X158605Y215804D02*
X158607Y216551D01*
G01X158601Y215184D02*
X158605Y215804D01*
G01X158594Y214770D02*
X158601Y215184D01*
G01X158585Y214621D02*
X158594Y214770D01*
G01X149212Y215606D02*
Y215605D01*
G01X149213Y215610D02*
X149212Y215606D01*
G01X149214Y215617D02*
X149213Y215610D01*
G01X150711Y230771D02*
Y230772D01*
G01X150710Y230768D02*
X150711Y230771D01*
G01X150710Y230760D02*
Y230768D01*
G01X157086Y215606D02*
Y215605D01*
G01X157087Y215610D02*
X157086Y215606D01*
G01X157088Y215617D02*
X157087Y215610D01*
G01X158585Y230771D02*
Y230772D01*
G01X158584Y230768D02*
X158585Y230771D01*
G01X158584Y230760D02*
Y230768D01*
G01X148947Y214965D02*
X148951Y215117D01*
G01X148943Y214866D02*
X148947Y214965D01*
G01X148938Y214824D02*
X148943Y214866D01*
G01X150976Y231413D02*
X150972Y231260D01*
G01X150981Y231511D02*
X150976Y231413D01*
G01X150985Y231553D02*
X150981Y231511D01*
G01X152879Y214965D02*
X152884Y215117D01*
G01X152875Y214866D02*
X152879Y214965D01*
G01X152870Y214824D02*
X152875Y214866D01*
G01X154918Y231413D02*
X154914Y231260D01*
G01X154922Y231511D02*
X154918Y231413D01*
G01X154927Y231553D02*
X154922Y231511D01*
G01X156821Y214965D02*
X156825Y215117D01*
G01X156817Y214866D02*
X156821Y214965D01*
G01X156812Y214824D02*
X156817Y214866D01*
G01X158850Y231413D02*
X158846Y231260D01*
G01X158855Y231511D02*
X158850Y231413D01*
G01X158859Y231553D02*
X158855Y231511D01*
G01X160753Y214965D02*
X160758Y215117D01*
G01X160749Y214866D02*
X160753Y214965D01*
G01X160744Y214824D02*
X160749Y214866D01*
G01X162792Y231413D02*
X162788Y231260D01*
G01X162796Y231511D02*
X162792Y231413D01*
G01X162801Y231553D02*
X162796Y231511D01*
G01X150973Y232353D02*
X150967Y232147D01*
G01X150979Y232484D02*
X150973Y232353D01*
G01X150985Y232538D02*
X150979Y232484D01*
G01X148950Y214024D02*
X148956Y214231D01*
G01X148944Y213893D02*
X148950Y214024D01*
G01X148938Y213840D02*
X148944Y213893D01*
G01X154915Y232353D02*
X154909Y232147D01*
G01X154921Y232484D02*
X154915Y232353D01*
G01X154927Y232538D02*
X154921Y232484D01*
G01X152883Y214024D02*
X152888Y214231D01*
G01X152876Y213893D02*
X152883Y214024D01*
G01X152870Y213840D02*
X152876Y213893D01*
G01X158847Y232353D02*
X158841Y232147D01*
G01X158853Y232484D02*
X158847Y232353D01*
G01X158859Y232538D02*
X158853Y232484D01*
G01X156824Y214024D02*
X156830Y214231D01*
G01X156818Y213893D02*
X156824Y214024D01*
G01X156812Y213840D02*
X156818Y213893D01*
G01X162789Y232353D02*
X162783Y232147D01*
G01X162795Y232484D02*
X162789Y232353D01*
G01X162801Y232538D02*
X162795Y232484D01*
G01X160757Y214024D02*
X160762Y214231D01*
G01X160751Y213893D02*
X160757Y214024D01*
G01X160744Y213840D02*
X160751Y213893D01*
G01X174595Y232353D02*
X174589Y232147D01*
G01X174601Y232484D02*
X174595Y232353D01*
G01X174607Y232538D02*
X174601Y232484D01*
G01X172572Y214024D02*
X172578Y214231D01*
G01X172566Y213893D02*
X172572Y214024D01*
G01X172560Y213840D02*
X172566Y213893D01*
G01X154654Y216168D02*
X154655Y216570D01*
G01X154651Y215841D02*
X154654Y216168D01*
G01X154647Y215645D02*
X154651Y215841D01*
G01X154642Y215615D02*
X154647Y215645D01*
G01X161018Y230209D02*
X161017Y229807D01*
G01X161020Y230537D02*
X161018Y230209D01*
G01X161024Y230733D02*
X161020Y230537D01*
G01X161029Y230762D02*
X161024Y230733D01*
G01X162528Y216168D02*
X162529Y216570D01*
G01X162525Y215841D02*
X162528Y216168D01*
G01X162521Y215645D02*
X162525Y215841D01*
G01X162516Y215615D02*
X162521Y215645D01*
G01X176766Y230209D02*
X176765Y229807D01*
G01X176768Y230537D02*
X176766Y230209D01*
G01X176773Y230733D02*
X176768Y230537D01*
G01X176777Y230762D02*
X176773Y230733D01*
G01X127089Y214622D02*
Y214621D01*
G01X127088Y214624D02*
X127089Y214622D01*
G01X127088Y214627D02*
Y214624D01*
G01X125591Y231754D02*
X125590Y231756D01*
G01X125592Y231750D02*
X125591Y231754D01*
G01X157076Y216197D02*
X157075Y216570D01*
G01X157078Y215887D02*
X157076Y216197D01*
G01X157082Y215680D02*
X157078Y215887D01*
G01X157086Y215605D02*
X157082Y215680D01*
G01X158595Y230180D02*
X158596Y229807D01*
G01X158593Y230490D02*
X158595Y230180D01*
G01X158590Y230698D02*
X158593Y230490D01*
G01X158585Y230772D02*
X158590Y230698D01*
G01X172824Y216197D02*
X172823Y216570D01*
G01X172826Y215887D02*
X172824Y216197D01*
G01X172830Y215680D02*
X172826Y215887D01*
G01X172834Y215605D02*
X172830Y215680D01*
G01X174343Y230180D02*
X174344Y229807D01*
G01X174341Y230490D02*
X174343Y230180D01*
G01X174338Y230698D02*
X174341Y230490D01*
G01X174333Y230772D02*
X174338Y230698D01*
G01X156818Y232484D02*
X156812Y232538D01*
G01X156824Y232353D02*
X156818Y232484D01*
G01X156830Y232147D02*
X156824Y232353D01*
G01X158853Y213893D02*
X158859Y213840D01*
G01X158847Y214024D02*
X158853Y213893D01*
G01X158841Y214231D02*
X158847Y214024D01*
G01X160760Y232484D02*
X160754Y232538D01*
G01X160766Y232353D02*
X160760Y232484D01*
G01X160772Y232147D02*
X160766Y232353D01*
G01X162785Y213893D02*
X162792Y213840D01*
G01X162779Y214024D02*
X162785Y213893D01*
G01X162774Y214231D02*
X162779Y214024D01*
G01X172566Y232484D02*
X172560Y232538D01*
G01X172572Y232353D02*
X172566Y232484D01*
G01X172578Y232147D02*
X172572Y232353D01*
G01X174601Y213893D02*
X174607Y213840D01*
G01X174595Y214024D02*
X174601Y213893D01*
G01X174589Y214231D02*
X174595Y214024D01*
G01X176508Y232484D02*
X176502Y232538D01*
G01X176514Y232353D02*
X176508Y232484D01*
G01X176520Y232147D02*
X176514Y232353D01*
G01X178533Y213893D02*
X178540Y213840D01*
G01X178527Y214024D02*
X178533Y213893D01*
G01X178522Y214231D02*
X178527Y214024D01*
G01X156817Y231511D02*
X156812Y231553D01*
G01X156821Y231413D02*
X156817Y231511D01*
G01X156825Y231260D02*
X156821Y231413D01*
G01X158855Y214866D02*
X158859Y214824D01*
G01X158850Y214965D02*
X158855Y214866D01*
G01X158846Y215117D02*
X158850Y214965D01*
G01X160758Y231511D02*
X160754Y231553D01*
G01X160763Y231413D02*
X160758Y231511D01*
G01X160767Y231260D02*
X160763Y231413D01*
G01X162787Y214866D02*
X162792Y214824D01*
G01X162783Y214965D02*
X162787Y214866D01*
G01X162778Y215117D02*
X162783Y214965D01*
G01X172565Y231511D02*
X172560Y231553D01*
G01X172569Y231413D02*
X172565Y231511D01*
G01X172573Y231260D02*
X172569Y231413D01*
G01X174603Y214866D02*
X174607Y214824D01*
G01X174598Y214965D02*
X174603Y214866D01*
G01X174594Y215117D02*
X174598Y214965D01*
G01X176506Y231511D02*
X176502Y231553D01*
G01X176511Y231413D02*
X176506Y231511D01*
G01X176515Y231260D02*
X176511Y231413D01*
G01X178535Y214866D02*
X178540Y214824D01*
G01X178531Y214965D02*
X178535Y214866D01*
G01X178526Y215117D02*
X178531Y214965D01*
G01X161015Y215645D02*
X161020Y215615D01*
G01X161011Y215841D02*
X161015Y215645D01*
G01X161008Y216168D02*
X161011Y215841D01*
G01X161007Y216570D02*
X161008Y216168D01*
G01X162530Y230733D02*
X162525Y230762D01*
G01X162534Y230537D02*
X162530Y230733D01*
G01X162537Y230209D02*
X162534Y230537D01*
G01X162538Y229807D02*
X162537Y230209D01*
G01X176763Y215645D02*
X176768Y215615D01*
G01X176759Y215841D02*
X176763Y215645D01*
G01X176756Y216168D02*
X176759Y215841D01*
G01X176755Y216570D02*
X176756Y216168D01*
G01X178278Y230733D02*
X178274Y230762D01*
G01X178282Y230537D02*
X178278Y230733D01*
G01X178285Y230209D02*
X178282Y230537D01*
G01X178286Y229807D02*
X178285Y230209D01*
G01X172826Y214770D02*
X172834Y214621D01*
G01X172819Y215184D02*
X172826Y214770D01*
G01X172814Y215804D02*
X172819Y215184D01*
G01X172812Y216551D02*
X172814Y215804D01*
G01X174342Y231608D02*
X174333Y231756D01*
G01X174349Y231193D02*
X174342Y231608D01*
G01X174353Y230573D02*
X174349Y231193D01*
G01X174355Y229826D02*
X174353Y230573D01*
G01X180700Y214770D02*
X180708Y214621D01*
G01X180693Y215184D02*
X180700Y214770D01*
G01X180688Y215804D02*
X180693Y215184D01*
G01X180686Y216551D02*
X180688Y215804D01*
G01X182216Y231608D02*
X182207Y231756D01*
G01X182223Y231193D02*
X182216Y231608D01*
G01X182228Y230573D02*
X182223Y231193D01*
G01X182229Y229826D02*
X182228Y230573D01*
G01X172830Y230698D02*
X172834Y230772D01*
G01X172826Y230490D02*
X172830Y230698D01*
G01X172824Y230180D02*
X172826Y230490D01*
G01X172823Y229807D02*
X172824Y230180D01*
G01X174338Y215680D02*
X174333Y215605D01*
G01X174341Y215887D02*
X174338Y215680D01*
G01X174343Y216197D02*
X174341Y215887D01*
G01X174344Y216570D02*
X174343Y216197D01*
G01X180704Y230698D02*
X180708Y230772D01*
G01X180700Y230490D02*
X180704Y230698D01*
G01X180698Y230180D02*
X180700Y230490D01*
G01X180697Y229807D02*
X180698Y230180D01*
G01X182212Y215680D02*
X182207Y215605D01*
G01X182215Y215887D02*
X182212Y215680D01*
G01X182217Y216197D02*
X182215Y215887D01*
G01X182218Y216570D02*
X182217Y216197D01*
G01X172814Y230573D02*
X172812Y229826D01*
G01X172819Y231193D02*
X172814Y230573D01*
G01X172826Y231608D02*
X172819Y231193D01*
G01X172834Y231756D02*
X172826Y231608D01*
G01X174353Y215804D02*
X174355Y216551D01*
G01X174349Y215184D02*
X174353Y215804D01*
G01X174342Y214770D02*
X174349Y215184D01*
G01X174333Y214621D02*
X174342Y214770D01*
G01X180688Y230573D02*
X180686Y229826D01*
G01X180693Y231193D02*
X180688Y230573D01*
G01X180700Y231608D02*
X180693Y231193D01*
G01X180708Y231756D02*
X180700Y231608D01*
G01X182228Y215804D02*
X182229Y216551D01*
G01X182223Y215184D02*
X182228Y215804D01*
G01X182216Y214770D02*
X182223Y215184D01*
G01X182207Y214621D02*
X182216Y214770D01*
G01X172834Y215606D02*
Y215605D01*
G01X172835Y215610D02*
X172834Y215606D01*
G01X172836Y215617D02*
X172835Y215610D01*
G01X174333Y230771D02*
Y230772D01*
G01X174332Y230768D02*
X174333Y230771D01*
G01X174332Y230760D02*
Y230768D01*
G01X180708Y215606D02*
Y215605D01*
G01X180709Y215610D02*
X180708Y215606D01*
G01X180710Y215617D02*
X180709Y215610D01*
G01X182207Y230771D02*
Y230772D01*
G01X182206Y230768D02*
X182207Y230771D01*
G01X182206Y230760D02*
Y230768D01*
G01X172569Y214965D02*
X172573Y215117D01*
G01X172565Y214866D02*
X172569Y214965D01*
G01X172560Y214824D02*
X172565Y214866D01*
G01X174598Y231413D02*
X174594Y231260D01*
G01X174603Y231511D02*
X174598Y231413D01*
G01X174607Y231553D02*
X174603Y231511D01*
G01X176501Y214965D02*
X176506Y215117D01*
G01X176497Y214866D02*
X176501Y214965D01*
G01X176492Y214824D02*
X176497Y214866D01*
G01X178540Y231413D02*
X178536Y231260D01*
G01X178544Y231511D02*
X178540Y231413D01*
G01X178549Y231553D02*
X178544Y231511D01*
G01X180443Y214965D02*
X180447Y215117D01*
G01X180439Y214866D02*
X180443Y214965D01*
G01X180434Y214824D02*
X180439Y214866D01*
G01X182472Y231413D02*
X182468Y231260D01*
G01X182477Y231511D02*
X182472Y231413D01*
G01X182481Y231553D02*
X182477Y231511D01*
G01X184375Y214965D02*
X184380Y215117D01*
G01X184371Y214866D02*
X184375Y214965D01*
G01X184366Y214824D02*
X184371Y214866D01*
G01X186414Y231413D02*
X186410Y231260D01*
G01X186418Y231511D02*
X186414Y231413D01*
G01X186423Y231553D02*
X186418Y231511D01*
G01X178537Y232353D02*
X178531Y232147D01*
G01X178543Y232484D02*
X178537Y232353D01*
G01X178549Y232538D02*
X178543Y232484D01*
G01X176505Y214024D02*
X176510Y214231D01*
G01X176499Y213893D02*
X176505Y214024D01*
G01X176492Y213840D02*
X176499Y213893D01*
G01X182469Y232353D02*
X182463Y232147D01*
G01X182475Y232484D02*
X182469Y232353D01*
G01X182481Y232538D02*
X182475Y232484D01*
G01X180446Y214024D02*
X180452Y214231D01*
G01X180440Y213893D02*
X180446Y214024D01*
G01X180434Y213840D02*
X180440Y213893D01*
G01X186411Y232353D02*
X186405Y232147D01*
G01X186417Y232484D02*
X186411Y232353D01*
G01X186423Y232538D02*
X186417Y232484D01*
G01X184379Y214024D02*
X184384Y214231D01*
G01X184373Y213893D02*
X184379Y214024D01*
G01X184366Y213840D02*
X184373Y213893D01*
G01X178276Y216168D02*
X178277Y216570D01*
G01X178273Y215841D02*
X178276Y216168D01*
G01X178269Y215645D02*
X178273Y215841D01*
G01X178264Y215615D02*
X178269Y215645D01*
G01X184640Y230209D02*
X184639Y229807D01*
G01X184642Y230537D02*
X184640Y230209D01*
G01X184647Y230733D02*
X184642Y230537D01*
G01X184651Y230762D02*
X184647Y230733D01*
G01X186150Y216168D02*
X186151Y216570D01*
G01X186147Y215841D02*
X186150Y216168D01*
G01X186143Y215645D02*
X186147Y215841D01*
G01X186138Y215615D02*
X186143Y215645D01*
G01X134963Y214622D02*
Y214621D01*
G01X134962Y214624D02*
X134963Y214622D01*
G01X134962Y214627D02*
Y214624D01*
G01X133465Y231754D02*
X133464Y231756D01*
G01X133466Y231750D02*
X133465Y231754D01*
G01X142837Y214622D02*
Y214621D01*
G01X142836Y214624D02*
X142837Y214622D01*
G01X142836Y214627D02*
Y214624D01*
G01X141339Y231754D02*
X141338Y231756D01*
G01X141340Y231750D02*
X141339Y231754D01*
G01X150711Y214622D02*
Y214621D01*
G01X150710Y214624D02*
X150711Y214622D01*
G01X150710Y214627D02*
Y214624D01*
G01X149213Y231754D02*
X149212Y231756D01*
G01X149214Y231750D02*
X149213Y231754D01*
G01X158585Y214622D02*
Y214621D01*
G01X158584Y214624D02*
X158585Y214622D01*
G01X158584Y214627D02*
Y214624D01*
G01X180698Y216197D02*
X180697Y216570D01*
G01X180700Y215887D02*
X180698Y216197D01*
G01X180704Y215680D02*
X180700Y215887D01*
G01X180708Y215605D02*
X180704Y215680D01*
G01X182217Y230180D02*
X182218Y229807D01*
G01X182215Y230490D02*
X182217Y230180D01*
G01X182212Y230698D02*
X182215Y230490D01*
G01X182207Y230772D02*
X182212Y230698D01*
G01X180440Y232484D02*
X180434Y232538D01*
G01X180446Y232353D02*
X180440Y232484D01*
G01X180452Y232147D02*
X180446Y232353D01*
G01X182475Y213893D02*
X182481Y213840D01*
G01X182469Y214024D02*
X182475Y213893D01*
G01X182463Y214231D02*
X182469Y214024D01*
G01X184382Y232484D02*
X184376Y232538D01*
G01X184388Y232353D02*
X184382Y232484D01*
G01X184394Y232147D02*
X184388Y232353D01*
G01X186407Y213893D02*
X186414Y213840D01*
G01X186401Y214024D02*
X186407Y213893D01*
G01X186396Y214231D02*
X186401Y214024D01*
G01X180439Y231511D02*
X180434Y231553D01*
G01X180443Y231413D02*
X180439Y231511D01*
G01X180447Y231260D02*
X180443Y231413D01*
G01X182477Y214866D02*
X182481Y214824D01*
G01X182472Y214965D02*
X182477Y214866D01*
G01X182468Y215117D02*
X182472Y214965D01*
G01X184380Y231511D02*
X184376Y231553D01*
G01X184385Y231413D02*
X184380Y231511D01*
G01X184389Y231260D02*
X184385Y231413D01*
G01X186409Y214866D02*
X186414Y214824D01*
G01X186405Y214965D02*
X186409Y214866D01*
G01X186400Y215117D02*
X186405Y214965D01*
G01X184637Y215645D02*
X184642Y215615D01*
G01X184633Y215841D02*
X184637Y215645D01*
G01X184630Y216168D02*
X184633Y215841D01*
G01X184629Y216570D02*
X184630Y216168D01*
G01X186152Y230733D02*
X186148Y230762D01*
G01X186156Y230537D02*
X186152Y230733D01*
G01X186159Y230209D02*
X186156Y230537D01*
G01X186160Y229807D02*
X186159Y230209D01*
G01X127088Y215610D02*
Y215617D01*
G01X127089Y215606D02*
X127088Y215610D01*
G01X127089Y215605D02*
Y215606D01*
G01X157087Y231754D02*
X157086Y231756D01*
G01X157088Y231750D02*
X157087Y231754D01*
G01X174333Y214622D02*
Y214621D01*
G01X174332Y214624D02*
X174333Y214622D01*
G01X174332Y214627D02*
Y214624D01*
G01X172835Y231754D02*
X172834Y231756D01*
G01X172836Y231750D02*
X172835Y231754D01*
G01X182207Y214622D02*
Y214621D01*
G01X182206Y214624D02*
X182207Y214622D01*
G01X182206Y214627D02*
Y214624D01*
G01X180709Y231754D02*
X180708Y231756D01*
G01X180710Y231750D02*
X180709Y231754D01*
G01X125591Y230768D02*
X125592Y230760D01*
G01X125590Y230771D02*
X125591Y230768D01*
G01X125590Y230772D02*
Y230771D01*
G01X134962Y215610D02*
Y215617D01*
G01X134963Y215606D02*
X134962Y215610D01*
G01X134963Y215605D02*
Y215606D01*
G01X133465Y230768D02*
X133466Y230760D01*
G01X133464Y230771D02*
X133465Y230768D01*
G01X133464Y230772D02*
Y230771D01*
G01X142836Y215610D02*
Y215617D01*
G01X142837Y215606D02*
X142836Y215610D01*
G01X142837Y215605D02*
Y215606D01*
G01X141339Y230768D02*
X141340Y230760D01*
G01X141338Y230771D02*
X141339Y230768D01*
G01X141338Y230772D02*
Y230771D01*
G01X150710Y215610D02*
Y215617D01*
G01X150711Y215606D02*
X150710Y215610D01*
G01X150711Y215605D02*
Y215606D01*
G01X149213Y230768D02*
X149214Y230760D01*
G01X149212Y230771D02*
X149213Y230768D01*
G01X149212Y230772D02*
Y230771D01*
G01X158584Y215610D02*
Y215617D01*
G01X158585Y215606D02*
X158584Y215610D01*
G01X158585Y215605D02*
Y215606D01*
G01X157087Y230768D02*
X157088Y230760D01*
G01X157086Y230771D02*
X157087Y230768D01*
G01X157086Y230772D02*
Y230771D01*
G01X174332Y215610D02*
Y215617D01*
G01X174333Y215606D02*
X174332Y215610D01*
G01X174333Y215605D02*
Y215606D01*
G01X172835Y230768D02*
X172836Y230760D01*
G01X172834Y230771D02*
X172835Y230768D01*
G01X172834Y230772D02*
Y230771D01*
G01X182206Y215610D02*
Y215617D01*
G01X182207Y215606D02*
X182206Y215610D01*
G01X182207Y215605D02*
Y215606D01*
G01X180709Y230768D02*
X180710Y230760D01*
G01X180708Y230771D02*
X180709Y230768D01*
G01X180708Y230772D02*
Y230771D01*
G01X167458Y216714D02*
X167678Y216693D01*
G01X167235Y216770D02*
X167458Y216714D01*
G01X167015Y216864D02*
X167235Y216770D01*
G01X166801Y216998D02*
X167015Y216864D01*
G01X166600Y217176D02*
X166801Y216998D01*
G01X166421Y217402D02*
X166600Y217176D01*
G01X167898Y229663D02*
X167678Y229684D01*
G01X168121Y229607D02*
X167898Y229663D01*
G01X168341Y229514D02*
X168121Y229607D01*
G01X168555Y229379D02*
X168341Y229514D01*
G01X168756Y229201D02*
X168555Y229379D01*
G01X168936Y228975D02*
X168756Y229201D01*
G01X170745Y220235D02*
X171123Y220064D01*
G01X170377Y220412D02*
X170745Y220235D01*
G01X170021Y220595D02*
X170377Y220412D01*
G01X131326Y214823D02*
X131341Y214822D01*
G01X131311Y214823D02*
X131326D01*
G01X131296Y214824D02*
X131311Y214823D01*
G01X139200D02*
X139215Y214822D01*
G01X139185Y214823D02*
X139200D01*
G01X139170Y214824D02*
X139185Y214823D01*
G01X178570D02*
X178585Y214822D01*
G01X178555Y214823D02*
X178570D01*
G01X178540Y214824D02*
X178555Y214823D01*
G01X186444D02*
X186459Y214822D01*
G01X186429Y214823D02*
X186444D01*
G01X186414Y214824D02*
X186429Y214823D01*
G01X168756Y217176D02*
X168936Y217402D01*
G01X168556Y216998D02*
X168756Y217176D01*
G01X168342Y216864D02*
X168556Y216998D01*
G01X168122Y216770D02*
X168342Y216864D01*
G01X167899Y216714D02*
X168122Y216770D01*
G01X167678Y216693D02*
X167899Y216714D01*
G01X180404Y214823D02*
X180389Y214822D01*
G01X180419Y214823D02*
X180404D01*
G01X180434Y214824D02*
X180419Y214823D01*
G01X172530D02*
X172515Y214822D01*
G01X172545Y214823D02*
X172530D01*
G01X172560Y214824D02*
X172545Y214823D01*
G01X156782D02*
X156767Y214822D01*
G01X156797Y214823D02*
X156782D01*
G01X156812Y214824D02*
X156797Y214823D01*
G01X148908D02*
X148893Y214822D01*
G01X148923Y214823D02*
X148908D01*
G01X148938Y214824D02*
X148923Y214823D01*
G01X141034D02*
X141019Y214822D01*
G01X141049Y214823D02*
X141034D01*
G01X141064Y214824D02*
X141049Y214823D01*
G01X133160D02*
X133145Y214822D01*
G01X133175Y214823D02*
X133160D01*
G01X133190Y214824D02*
X133175Y214823D01*
G01X125286D02*
X125271Y214822D01*
G01X125301Y214823D02*
X125286D01*
G01X125316Y214824D02*
X125301Y214823D01*
G01X184336Y213838D02*
X184321D01*
G01X184351Y213839D02*
X184336Y213838D01*
G01X184366Y213840D02*
X184351Y213839D01*
G01X176462Y213838D02*
X176447D01*
G01X176477Y213839D02*
X176462Y213838D01*
G01X176492Y213840D02*
X176477Y213839D01*
G01X160714Y213838D02*
X160699D01*
G01X160729Y213839D02*
X160714Y213838D01*
G01X160744Y213840D02*
X160729Y213839D01*
G01X152840Y213838D02*
X152825D01*
G01X152855Y213839D02*
X152840Y213838D01*
G01X152870Y213840D02*
X152855Y213839D01*
G01X144966Y213838D02*
X144951D01*
G01X144981Y213839D02*
X144966Y213838D01*
G01X144996Y213840D02*
X144981Y213839D01*
G01X137092Y213838D02*
X137077D01*
G01X137107Y213839D02*
X137092Y213838D01*
G01X137122Y213840D02*
X137107Y213839D01*
G01X129218Y213838D02*
X129203D01*
G01X129233Y213839D02*
X129218Y213838D01*
G01X129248Y213840D02*
X129233Y213839D01*
G01X121344Y213838D02*
X121329D01*
G01X121359Y213839D02*
X121344Y213838D01*
G01X121374Y213840D02*
X121359Y213839D01*
G01X123437D02*
X123421Y213840D01*
G01X123451Y213838D02*
X123437Y213839D01*
G01X123467Y213838D02*
X123451D01*
G01X127378Y213839D02*
X127363Y213840D01*
G01X127393Y213838D02*
X127378Y213839D01*
G01X127408Y213838D02*
X127393D01*
G01X131311Y213839D02*
X131296Y213840D01*
G01X131326Y213838D02*
X131311Y213839D01*
G01X131341Y213838D02*
X131326D01*
G01X135252Y213839D02*
X135237Y213840D01*
G01X135267Y213838D02*
X135252Y213839D01*
G01X135282Y213838D02*
X135267D01*
G01X139185Y213839D02*
X139170Y213840D01*
G01X139200Y213838D02*
X139185Y213839D01*
G01X139215Y213838D02*
X139200D01*
G01X143126Y213839D02*
X143111Y213840D01*
G01X143141Y213838D02*
X143126Y213839D01*
G01X143156Y213838D02*
X143141D01*
G01X147059Y213839D02*
X147044Y213840D01*
G01X147074Y213838D02*
X147059Y213839D01*
G01X147089Y213838D02*
X147074D01*
G01X151000Y213839D02*
X150985Y213840D01*
G01X151015Y213838D02*
X151000Y213839D01*
G01X151030Y213838D02*
X151015D01*
G01X154933Y213839D02*
X154918Y213840D01*
G01X154948Y213838D02*
X154933Y213839D01*
G01X154963Y213838D02*
X154948D01*
G01X158874Y213839D02*
X158859Y213840D01*
G01X158889Y213838D02*
X158874Y213839D01*
G01X158904Y213838D02*
X158889D01*
G01X162807Y213839D02*
X162792Y213840D01*
G01X162822Y213838D02*
X162807Y213839D01*
G01X162837Y213838D02*
X162822D01*
G01X174622Y213839D02*
X174607Y213840D01*
G01X174637Y213838D02*
X174622Y213839D01*
G01X174652Y213838D02*
X174637D01*
G01X178555Y213839D02*
X178540Y213840D01*
G01X178570Y213838D02*
X178555Y213839D01*
G01X178585Y213838D02*
X178570D01*
G01X182496Y213839D02*
X182481Y213840D01*
G01X182511Y213838D02*
X182496Y213839D01*
G01X182526Y213838D02*
X182511D01*
G01X186429Y213839D02*
X186414Y213840D01*
G01X186444Y213838D02*
X186429Y213839D01*
G01X186459Y213838D02*
X186444D01*
G01X121369Y232538D02*
X121384D01*
G01X121354Y232539D02*
X121369Y232538D01*
G01X121339Y232539D02*
X121354D01*
G01X125301Y232538D02*
X125316D01*
G01X125286Y232539D02*
X125301Y232538D01*
G01X125271Y232539D02*
X125286D01*
G01X129243Y232538D02*
X129258D01*
G01X129228Y232539D02*
X129243Y232538D01*
G01X129213Y232539D02*
X129228D01*
G01X133175Y232538D02*
X133190D01*
G01X133160Y232539D02*
X133175Y232538D01*
G01X133145Y232539D02*
X133160D01*
G01X137117Y232538D02*
X137132D01*
G01X137102Y232539D02*
X137117Y232538D01*
G01X137087Y232539D02*
X137102D01*
G01X141049Y232538D02*
X141064D01*
G01X141034Y232539D02*
X141049Y232538D01*
G01X141019Y232539D02*
X141034D01*
G01X144991Y232538D02*
X145006D01*
G01X144976Y232539D02*
X144991Y232538D01*
G01X144961Y232539D02*
X144976D01*
G01X148923Y232538D02*
X148938D01*
G01X148908Y232539D02*
X148923Y232538D01*
G01X148893Y232539D02*
X148908D01*
G01X152865Y232538D02*
X152880D01*
G01X152850Y232539D02*
X152865Y232538D01*
G01X152835Y232539D02*
X152850D01*
G01X156797Y232538D02*
X156812D01*
G01X156782Y232539D02*
X156797Y232538D01*
G01X156767Y232539D02*
X156782D01*
G01X160739Y232538D02*
X160754D01*
G01X160724Y232539D02*
X160739Y232538D01*
G01X160709Y232539D02*
X160724D01*
G01X172545Y232538D02*
X172560D01*
G01X172530Y232539D02*
X172545Y232538D01*
G01X172515Y232539D02*
X172530D01*
G01X176487Y232538D02*
X176502D01*
G01X176472Y232539D02*
X176487Y232538D01*
G01X176457Y232539D02*
X176472D01*
G01X180419Y232538D02*
X180434D01*
G01X180404Y232539D02*
X180419Y232538D01*
G01X180389Y232539D02*
X180404D01*
G01X184361Y232538D02*
X184376D01*
G01X184346Y232539D02*
X184361Y232538D01*
G01X184331Y232539D02*
X184346D01*
G01X123437Y214823D02*
X123421Y214824D01*
G01X123451Y214823D02*
X123437D01*
G01X123467Y214822D02*
X123451Y214823D01*
G01X127378D02*
X127363Y214824D01*
G01X127393Y214823D02*
X127378D01*
G01X127408Y214822D02*
X127393Y214823D01*
G01X135252D02*
X135237Y214824D01*
G01X135267Y214823D02*
X135252D01*
G01X135282Y214822D02*
X135267Y214823D01*
G01X143126D02*
X143111Y214824D01*
G01X143141Y214823D02*
X143126D01*
G01X143156Y214822D02*
X143141Y214823D01*
G01X147059D02*
X147044Y214824D01*
G01X147074Y214823D02*
X147059D01*
G01X147089Y214822D02*
X147074Y214823D01*
G01X151000D02*
X150985Y214824D01*
G01X151015Y214823D02*
X151000D01*
G01X151030Y214822D02*
X151015Y214823D01*
G01X154933D02*
X154918Y214824D01*
G01X154948Y214823D02*
X154933D01*
G01X154963Y214822D02*
X154948Y214823D01*
G01X158874D02*
X158859Y214824D01*
G01X158889Y214823D02*
X158874D01*
G01X158904Y214822D02*
X158889Y214823D01*
G01X162807D02*
X162792Y214824D01*
G01X162822Y214823D02*
X162807D01*
G01X162837Y214822D02*
X162822Y214823D01*
G01X174622D02*
X174607Y214824D01*
G01X174637Y214823D02*
X174622D01*
G01X174652Y214822D02*
X174637Y214823D01*
G01X182496D02*
X182481Y214824D01*
G01X182511Y214823D02*
X182496D01*
G01X182526Y214822D02*
X182511Y214823D01*
G01X125301Y231554D02*
X125316Y231553D01*
G01X125286Y231555D02*
X125301Y231554D01*
G01X125271Y231555D02*
X125286D01*
G01X129243Y231554D02*
X129258Y231553D01*
G01X129228Y231555D02*
X129243Y231554D01*
G01X129213Y231555D02*
X129228D01*
G01X133175Y231554D02*
X133190Y231553D01*
G01X133160Y231555D02*
X133175Y231554D01*
G01X133145Y231555D02*
X133160D01*
G01X137117Y231554D02*
X137132Y231553D01*
G01X137102Y231555D02*
X137117Y231554D01*
G01X137087Y231555D02*
X137102D01*
G01X141049Y231554D02*
X141064Y231553D01*
G01X141034Y231555D02*
X141049Y231554D01*
G01X141019Y231555D02*
X141034D01*
G01X148923Y231554D02*
X148938Y231553D01*
G01X148908Y231555D02*
X148923Y231554D01*
G01X148893Y231555D02*
X148908D01*
G01X156797Y231554D02*
X156812Y231553D01*
G01X156782Y231555D02*
X156797Y231554D01*
G01X156767Y231555D02*
X156782D01*
G01X172545Y231554D02*
X172560Y231553D01*
G01X172530Y231555D02*
X172545Y231554D01*
G01X172515Y231555D02*
X172530D01*
G01X176487Y231554D02*
X176502Y231553D01*
G01X176472Y231555D02*
X176487Y231554D01*
G01X176457Y231555D02*
X176472D01*
G01X180419Y231554D02*
X180434Y231553D01*
G01X180404Y231555D02*
X180419Y231554D01*
G01X180389Y231555D02*
X180404D01*
G01X184361Y231554D02*
X184376Y231553D01*
G01X184346Y231555D02*
X184361Y231554D01*
G01X184331Y231555D02*
X184346D01*
G01X121354D02*
X121339D01*
G01X121369Y231554D02*
X121354Y231555D01*
G01X121384Y231553D02*
X121369Y231554D01*
G01X144976Y231555D02*
X144961D01*
G01X144991Y231554D02*
X144976Y231555D01*
G01X145006Y231553D02*
X144991Y231554D01*
G01X152850Y231555D02*
X152835D01*
G01X152865Y231554D02*
X152850Y231555D01*
G01X152880Y231553D02*
X152865Y231554D01*
G01X160724Y231555D02*
X160709D01*
G01X160739Y231554D02*
X160724Y231555D01*
G01X160754Y231553D02*
X160739Y231554D01*
G01X166600Y229201D02*
X166421Y228975D01*
G01X166801Y229379D02*
X166600Y229201D01*
G01X167015Y229514D02*
X166801Y229379D01*
G01X167235Y229607D02*
X167015Y229514D01*
G01X167458Y229663D02*
X167235Y229607D01*
G01X167678Y229684D02*
X167458Y229663D01*
G01X186453Y231555D02*
X186468D01*
G01X186438Y231554D02*
X186453Y231555D01*
G01X186423Y231553D02*
X186438Y231554D01*
G01X182511Y231555D02*
X182526D01*
G01X182496Y231554D02*
X182511Y231555D01*
G01X182481Y231553D02*
X182496Y231554D01*
G01X178579Y231555D02*
X178594D01*
G01X178564Y231554D02*
X178579Y231555D01*
G01X178549Y231553D02*
X178564Y231554D01*
G01X174637Y231555D02*
X174652D01*
G01X174622Y231554D02*
X174637Y231555D01*
G01X174607Y231553D02*
X174622Y231554D01*
G01X162831Y231555D02*
X162846D01*
G01X162816Y231554D02*
X162831Y231555D01*
G01X162801Y231553D02*
X162816Y231554D01*
G01X158889Y231555D02*
X158904D01*
G01X158874Y231554D02*
X158889Y231555D01*
G01X158859Y231553D02*
X158874Y231554D01*
G01X154957Y231555D02*
X154972D01*
G01X154942Y231554D02*
X154957Y231555D01*
G01X154927Y231553D02*
X154942Y231554D01*
G01X151015Y231555D02*
X151030D01*
G01X151000Y231554D02*
X151015Y231555D01*
G01X150985Y231553D02*
X151000Y231554D01*
G01X147083Y231555D02*
X147098D01*
G01X147068Y231554D02*
X147083Y231555D01*
G01X147053Y231553D02*
X147068Y231554D01*
G01X143141Y231555D02*
X143156D01*
G01X143126Y231554D02*
X143141Y231555D01*
G01X143111Y231553D02*
X143126Y231554D01*
G01X139209Y231555D02*
X139224D01*
G01X139194Y231554D02*
X139209Y231555D01*
G01X139179Y231553D02*
X139194Y231554D01*
G01X135267Y231555D02*
X135282D01*
G01X135252Y231554D02*
X135267Y231555D01*
G01X135237Y231553D02*
X135252Y231554D01*
G01X131335Y231555D02*
X131350D01*
G01X131320Y231554D02*
X131335Y231555D01*
G01X131305Y231553D02*
X131320Y231554D01*
G01X127393Y231555D02*
X127408D01*
G01X127378Y231554D02*
X127393Y231555D01*
G01X127363Y231553D02*
X127378Y231554D01*
G01X123461Y231555D02*
X123476D01*
G01X123446Y231554D02*
X123461Y231555D01*
G01X123431Y231553D02*
X123446Y231554D01*
G01X178579Y232539D02*
X178594D01*
G01X178564Y232538D02*
X178579Y232539D01*
G01X178549Y232538D02*
X178564D01*
G01X162831Y232539D02*
X162846D01*
G01X162816Y232538D02*
X162831Y232539D01*
G01X162801Y232538D02*
X162816D01*
G01X154957Y232539D02*
X154972D01*
G01X154942Y232538D02*
X154957Y232539D01*
G01X154927Y232538D02*
X154942D01*
G01X147083Y232539D02*
X147098D01*
G01X147068Y232538D02*
X147083Y232539D01*
G01X147053Y232538D02*
X147068D01*
G01X123461Y232539D02*
X123476D01*
G01X123446Y232538D02*
X123461Y232539D01*
G01X123431Y232538D02*
X123446D01*
G01X125670Y236434D02*
X125513Y236396D01*
G01X127166D02*
X127009Y236434D01*
G01X125670Y235412D02*
X125513Y235338D01*
G01X127166D02*
X127009Y235412D01*
G01X127408Y232539D02*
X127363Y232538D01*
G01X127088Y231750D02*
X127076Y231737D01*
G01X125603D02*
X125592Y231750D01*
G01X154725Y218680D02*
X154568Y218717D01*
G01X153229Y217696D02*
X153072Y217621D01*
G01X154725D02*
X154568Y217696D01*
G01X153229Y218717D02*
X153072Y218680D01*
G01X154630Y214640D02*
X154642Y214627D01*
G01X153146D02*
X153157Y214640D01*
G01X152825Y214822D02*
X152870Y214824D01*
G01X154568Y227660D02*
X154725Y227698D01*
G01X153072D02*
X153229Y227660D01*
G01X154568Y228681D02*
X154725Y228756D01*
G01X153072D02*
X153229Y228681D01*
G01X153167Y231737D02*
X153155Y231750D01*
G01X154651D02*
X154640Y231737D01*
G01X176851Y218717D02*
X176694Y218680D01*
G01X178347D02*
X178190Y218717D01*
G01X176851Y217696D02*
X176694Y217621D01*
G01X178347D02*
X178190Y217696D01*
G01X178252Y214640D02*
X178264Y214627D01*
G01X176768D02*
X176779Y214640D01*
G01X176447Y214822D02*
X176492Y214824D01*
G01X176789Y231737D02*
X176777Y231750D01*
G01X178273D02*
X178262Y231737D01*
G01X178190Y227660D02*
X178347Y227698D01*
G01X176694D02*
X176851Y227660D01*
G01X178190Y228681D02*
X178347Y228756D01*
G01X176694D02*
X176851Y228681D01*
G01X182127Y209943D02*
X182284Y209981D01*
G01X180631D02*
X180788Y209943D01*
G01X182127Y210965D02*
X182284Y211039D01*
G01X180631D02*
X180788Y210965D01*
G01X180389Y213838D02*
X180434Y213840D01*
G01X180710Y214627D02*
X180721Y214640D01*
G01X182194D02*
X182206Y214627D01*
G01X180788Y236434D02*
X180631Y236396D01*
G01X182284D02*
X182127Y236434D01*
G01X180788Y235412D02*
X180631Y235338D01*
G01X182284D02*
X182127Y235412D01*
G01X180721Y231737D02*
X180710Y231750D01*
G01X182206D02*
X182194Y231737D01*
G01X182526Y232539D02*
X182481Y232538D01*
G01X186221Y218680D02*
X186064Y218717D01*
G01X184725D02*
X184568Y218680D01*
G01X184725Y217696D02*
X184568Y217621D01*
G01X186221D02*
X186064Y217696D01*
G01X186126Y214640D02*
X186138Y214627D01*
G01X184642D02*
X184653Y214640D01*
G01X184321Y214822D02*
X184366Y214824D01*
G01X184568Y227698D02*
X184725Y227660D01*
G01X186064Y228681D02*
X186221Y228756D01*
G01X184568D02*
X184725Y228681D01*
G01X186064Y227660D02*
X186221Y227698D01*
G01X184663Y231737D02*
X184651Y231750D01*
G01X186147D02*
X186136Y231737D01*
G01X186468Y232539D02*
X186423Y232538D01*
G01X129450Y227698D02*
X129607Y227660D01*
G01X130946Y228681D02*
X131103Y228756D01*
G01X129450D02*
X129607Y228681D01*
G01X130946Y227660D02*
X131103Y227698D01*
G01X129545Y231737D02*
X129533Y231750D01*
G01X131029D02*
X131018Y231737D01*
G01X131350Y232539D02*
X131305Y232538D01*
G01X131008Y214640D02*
X131020Y214627D01*
G01X129524D02*
X129535Y214640D01*
G01X129203Y214822D02*
X129248Y214824D01*
G01X131103Y218680D02*
X130946Y218717D01*
G01X129607D02*
X129450Y218680D01*
G01X129607Y217696D02*
X129450Y217621D01*
G01X131103D02*
X130946Y217696D01*
G01X127009Y209943D02*
X127166Y209981D01*
G01X125513D02*
X125670Y209943D01*
G01X127009Y210965D02*
X127166Y211039D01*
G01X125513D02*
X125670Y210965D01*
G01X127076Y214640D02*
X127088Y214627D01*
G01X125592D02*
X125603Y214640D01*
G01X125271Y213838D02*
X125316Y213840D01*
G01X123072Y227660D02*
X123229Y227698D01*
G01X121576D02*
X121733Y227660D01*
G01X123072Y228681D02*
X123229Y228756D01*
G01X121576D02*
X121733Y228681D01*
G01X121671Y231737D02*
X121659Y231750D01*
G01X123155D02*
X123144Y231737D01*
G01X123134Y214640D02*
X123146Y214627D01*
G01X121650D02*
X121661Y214640D01*
G01X121329Y214822D02*
X121374Y214824D01*
G01X123229Y218680D02*
X123072Y218717D01*
G01X121733D02*
X121576Y218680D01*
G01X121733Y217696D02*
X121576Y217621D01*
G01X123229D02*
X123072Y217696D01*
G01X162442Y227660D02*
X162599Y227698D01*
G01X160946D02*
X161103Y227660D01*
G01X162442Y228681D02*
X162599Y228756D01*
G01X160946D02*
X161103Y228681D01*
G01X161041Y231737D02*
X161029Y231750D01*
G01X162525D02*
X162514Y231737D01*
G01X162504Y214640D02*
X162516Y214627D01*
G01X161020D02*
X161031Y214640D01*
G01X160699Y214822D02*
X160744Y214824D01*
G01X162599Y218680D02*
X162442Y218717D01*
G01X161103D02*
X160946Y218680D01*
G01X161103Y217696D02*
X160946Y217621D01*
G01X162599D02*
X162442Y217696D01*
G01X157166Y236434D02*
X157009Y236396D01*
G01X158662D02*
X158505Y236434D01*
G01X157166Y235412D02*
X157009Y235338D01*
G01X158662D02*
X158505Y235412D01*
G01X158904Y232539D02*
X158859Y232538D01*
G01X158584Y231750D02*
X158572Y231737D01*
G01X157099D02*
X157088Y231750D01*
G01X158505Y209943D02*
X158662Y209981D01*
G01X157009D02*
X157166Y209943D01*
G01X158505Y210965D02*
X158662Y211039D01*
G01X157009D02*
X157166Y210965D01*
G01X158572Y214640D02*
X158584Y214627D01*
G01X157088D02*
X157099Y214640D01*
G01X156767Y213838D02*
X156812Y213840D01*
G01X149292Y236434D02*
X149135Y236396D01*
G01X150788D02*
X150631Y236434D01*
G01X149292Y235412D02*
X149135Y235338D01*
G01X150788D02*
X150631Y235412D01*
G01X151030Y232539D02*
X150985Y232538D01*
G01X150710Y231750D02*
X150698Y231737D01*
G01X149225D02*
X149214Y231750D01*
G01X150631Y209943D02*
X150788Y209981D01*
G01X149135D02*
X149292Y209943D01*
G01X150631Y210965D02*
X150788Y211039D01*
G01X149135D02*
X149292Y210965D01*
G01X150698Y214640D02*
X150710Y214627D01*
G01X149214D02*
X149225Y214640D01*
G01X148893Y213838D02*
X148938Y213840D01*
G01X146694Y227660D02*
X146851Y227698D01*
G01X145198D02*
X145355Y227660D01*
G01X146694Y228681D02*
X146851Y228756D01*
G01X145198D02*
X145355Y228681D01*
G01X145293Y231737D02*
X145281Y231750D01*
G01X146777D02*
X146766Y231737D01*
G01X146756Y214640D02*
X146768Y214627D01*
G01X145272D02*
X145283Y214640D01*
G01X144951Y214822D02*
X144996Y214824D01*
G01X146851Y218680D02*
X146694Y218717D01*
G01X145355D02*
X145198Y218680D01*
G01X145355Y217696D02*
X145198Y217621D01*
G01X146851D02*
X146694Y217696D01*
G01X141418Y236434D02*
X141261Y236396D01*
G01X142914D02*
X142757Y236434D01*
G01X141418Y235412D02*
X141261Y235338D01*
G01X142914D02*
X142757Y235412D01*
G01X143156Y232539D02*
X143111Y232538D01*
G01X142836Y231750D02*
X142824Y231737D01*
G01X141351D02*
X141340Y231750D01*
G01X142757Y209943D02*
X142914Y209981D01*
G01X141261D02*
X141418Y209943D01*
G01X142757Y210965D02*
X142914Y211039D01*
G01X141261D02*
X141418Y210965D01*
G01X142824Y214640D02*
X142836Y214627D01*
G01X141340D02*
X141351Y214640D01*
G01X141019Y213838D02*
X141064Y213840D01*
G01X137324Y227698D02*
X137481Y227660D01*
G01X138820Y228681D02*
X138977Y228756D01*
G01X137324D02*
X137481Y228681D01*
G01X138820Y227660D02*
X138977Y227698D01*
G01X137419Y231737D02*
X137407Y231750D01*
G01X138903D02*
X138892Y231737D01*
G01X139224Y232539D02*
X139179Y232538D01*
G01X138882Y214640D02*
X138894Y214627D01*
G01X137398D02*
X137409Y214640D01*
G01X137077Y214822D02*
X137122Y214824D01*
G01X138977Y218680D02*
X138820Y218717D01*
G01X137481D02*
X137324Y218680D01*
G01X137481Y217696D02*
X137324Y217621D01*
G01X138977D02*
X138820Y217696D01*
G01X133544Y236434D02*
X133387Y236396D01*
G01X135040D02*
X134883Y236434D01*
G01X133544Y235412D02*
X133387Y235338D01*
G01X135040D02*
X134883Y235412D01*
G01X135282Y232539D02*
X135237Y232538D01*
G01X134962Y231750D02*
X134950Y231737D01*
G01X133477D02*
X133466Y231750D01*
G01X134883Y209943D02*
X135040Y209981D01*
G01X133387D02*
X133544Y209943D01*
G01X134883Y210965D02*
X135040Y211039D01*
G01X133387D02*
X133544Y210965D01*
G01X134950Y214640D02*
X134962Y214627D01*
G01X133466D02*
X133477Y214640D01*
G01X133145Y213838D02*
X133190Y213840D01*
G01X174253Y209943D02*
X174410Y209981D01*
G01X172757D02*
X172914Y209943D01*
G01X174253Y210965D02*
X174410Y211039D01*
G01X172757D02*
X172914Y210965D01*
G01X172515Y213838D02*
X172560Y213840D01*
G01X172836Y214627D02*
X172847Y214640D01*
G01X174320D02*
X174332Y214627D01*
G01X172914Y236434D02*
X172757Y236396D01*
G01X174410D02*
X174253Y236434D01*
G01X172914Y235412D02*
X172757Y235338D01*
G01X174410D02*
X174253Y235412D01*
G01X172847Y231737D02*
X172836Y231750D01*
G01X174332D02*
X174320Y231737D01*
G01X174652Y232539D02*
X174607Y232538D01*
G01X170021Y225782D02*
G03Y220595I-1752J-2594D01*
G01X171123Y226314D02*
G03Y220064I-2854J-3125D01*
G01X172895Y223189D02*
G03I-4626J0D01*
G01X115021Y243189D02*
X115513D01*
G01X111904D02*
X112560D01*
G01X112970Y240592D02*
X111494D01*
G01X113052Y240257D02*
X111412D01*
G01X111084Y239252D02*
X110592D01*
G01X113872D02*
X113380D01*
G01X115513D02*
X115021D01*
G01X460985Y237854D02*
X110592D01*
G01X123584Y236476D02*
X121221D01*
G01X127521D02*
X125158D01*
G01X131458D02*
X129095D01*
G01X135395D02*
X133032D01*
G01X139332D02*
X136969D01*
G01X143269D02*
X140906D01*
G01X147206D02*
X144843D01*
G01X151143D02*
X148780D01*
G01X155080D02*
X152717D01*
G01X159017D02*
X156655D01*
G01X162954D02*
X160592D01*
G01X174765D02*
X172403D01*
G01X178702D02*
X176340D01*
G01X182639D02*
X180277D01*
G01X186576D02*
X184214D01*
G01X127009Y235492D02*
X125670D01*
G01X134883D02*
X133544D01*
G01X142757D02*
X141418D01*
G01X150631D02*
X149292D01*
G01X158505D02*
X157166D01*
G01X170178D02*
X165178D01*
G01X174253D02*
X172914D01*
G01X182127D02*
X180788D01*
G01X180631Y235393D02*
X182284D01*
G01X172757D02*
X174410D01*
G01X157009D02*
X158662D01*
G01X149135D02*
X150788D01*
G01X141261D02*
X142914D01*
G01X133387D02*
X135040D01*
G01X125513D02*
X127166D01*
G01X116241Y235295D02*
X111517D01*
G01X123584D02*
X121221D01*
G01X127521D02*
X125158D01*
G01X131458D02*
X129095D01*
G01X135395D02*
X133032D01*
G01X139332D02*
X136969D01*
G01X143269D02*
X140906D01*
G01X147206D02*
X144843D01*
G01X151143D02*
X148780D01*
G01X155080D02*
X152717D01*
G01X159017D02*
X156655D01*
G01X162954D02*
X160592D01*
G01X174765D02*
X172403D01*
G01X178702D02*
X176340D01*
G01X182639D02*
X180277D01*
G01X186576D02*
X184214D01*
G01X115493Y203242D02*
X115083Y203158D01*
G01X110736Y202237D02*
X110326Y202153D01*
G01X111228Y199724D02*
X111638Y199808D01*
G01X115903Y200143D02*
X116313Y200227D01*
G01X110408Y201734D02*
X110736Y201818D01*
G01X111556Y200227D02*
X111228Y200143D01*
G01X116313Y199808D02*
X115985Y199724D01*
G01X127166Y234901D02*
X125513D01*
G01X135040D02*
X133387D01*
G01X142914D02*
X141261D01*
G01X150788D02*
X149135D01*
G01X158662D02*
X157009D01*
G01X174410D02*
X172757D01*
G01X182284D02*
X180631D01*
G01X117856Y234735D02*
X114270D01*
G01X123820Y234035D02*
X120985D01*
G01X127757D02*
X124922D01*
G01X131694D02*
X128859D01*
G01X135631D02*
X132796D01*
G01X139568D02*
X136733D01*
G01X143505D02*
X140670D01*
G01X147442D02*
X144607D01*
G01X151379D02*
X148544D01*
G01X155316D02*
X152481D01*
G01X159253D02*
X156418D01*
G01X163190D02*
X160355D01*
G01X175001D02*
X172166D01*
G01X178938D02*
X176103D01*
G01X182875D02*
X180040D01*
G01X186812D02*
X183977D01*
G01X127166Y233130D02*
X125513D01*
G01X135040D02*
X133387D01*
G01X142914D02*
X141261D01*
G01X150788D02*
X149135D01*
G01X158662D02*
X157009D01*
G01X174410D02*
X172757D01*
G01X182284D02*
X180631D01*
G01Y232637D02*
X182284D01*
G01X172757D02*
X174410D01*
G01X157009D02*
X158662D01*
G01X149135D02*
X150788D01*
G01X141261D02*
X142914D01*
G01X133387D02*
X135040D01*
G01X125513D02*
X127166D01*
G01X123820Y232539D02*
X120985D01*
G01X127757D02*
X124922D01*
G01X131694D02*
X128859D01*
G01X135631D02*
X132796D01*
G01X139568D02*
X136733D01*
G01X143505D02*
X140670D01*
G01X147442D02*
X144607D01*
G01X151379D02*
X148544D01*
G01X155316D02*
X152481D01*
G01X159253D02*
X156418D01*
G01X163190D02*
X160355D01*
G01X175001D02*
X172166D01*
G01X178938D02*
X176103D01*
G01X182875D02*
X180040D01*
G01X186812D02*
X183977D01*
G01X186221Y232382D02*
X186812D01*
G01X183977D02*
X184568D01*
G01X182284D02*
X182875D01*
G01X180040D02*
X180631D01*
G01X178347D02*
X178938D01*
G01X176103D02*
X176694D01*
G01X174410D02*
X175001D01*
G01X172166D02*
X172757D01*
G01X162599D02*
X163190D01*
G01X160355D02*
X160946D01*
G01X158662D02*
X159253D01*
G01X156418D02*
X157009D01*
G01X154725D02*
X155316D01*
G01X152481D02*
X153072D01*
G01X150788D02*
X151379D01*
G01X148544D02*
X149135D01*
G01X146851D02*
X147442D01*
G01X144607D02*
X145198D01*
G01X142914D02*
X143505D01*
G01X140670D02*
X141261D01*
G01X138977D02*
X139568D01*
G01X136733D02*
X137324D01*
G01X135040D02*
X135631D01*
G01X132796D02*
X133387D01*
G01X131103D02*
X131694D01*
G01X128859D02*
X129450D01*
G01X127166D02*
X127757D01*
G01X124922D02*
X125513D01*
G01X123229D02*
X123820D01*
G01X120985D02*
X121576D01*
G01X184394Y232147D02*
X186405D01*
G01X180452D02*
X182463D01*
G01X176520D02*
X178531D01*
G01X172578D02*
X174589D01*
G01X160772D02*
X162783D01*
G01X156830D02*
X158841D01*
G01X152898D02*
X154909D01*
G01X148956D02*
X150967D01*
G01X145024D02*
X147035D01*
G01X141082D02*
X143093D01*
G01X137150D02*
X139161D01*
G01X133208D02*
X135219D01*
G01X129276D02*
X131287D01*
G01X125334D02*
X127345D01*
G01X121402D02*
X123413D01*
G01X123157Y231756D02*
X121657D01*
G01X127089D02*
X125590D01*
G01X131031D02*
X129531D01*
G01X134963D02*
X133464D01*
G01X138905D02*
X137406D01*
G01X142837D02*
X141338D01*
G01X146779D02*
X145280D01*
G01X150711D02*
X149212D01*
G01X154653D02*
X153154D01*
G01X158585D02*
X157086D01*
G01X162527D02*
X161028D01*
G01X174333D02*
X172834D01*
G01X178275D02*
X176776D01*
G01X182207D02*
X180708D01*
G01X186149D02*
X184650D01*
G01X184663Y231737D02*
X186136D01*
G01X180721D02*
X182194D01*
G01X176789D02*
X178262D01*
G01X172847D02*
X174320D01*
G01X161041D02*
X162514D01*
G01X157099D02*
X158572D01*
G01X153167D02*
X154640D01*
G01X149225D02*
X150698D01*
G01X145293D02*
X146766D01*
G01X141351D02*
X142824D01*
G01X137419D02*
X138892D01*
G01X133477D02*
X134950D01*
G01X129545D02*
X131018D01*
G01X125603D02*
X127076D01*
G01X121671D02*
X123144D01*
G01X121576Y231712D02*
X120985D01*
G01X123820D02*
X123229D01*
G01X125513D02*
X124922D01*
G01X127757D02*
X127166D01*
G01X129450D02*
X128859D01*
G01X131694D02*
X131103D01*
G01X133387D02*
X132796D01*
G01X135631D02*
X135040D01*
G01X137324D02*
X136733D01*
G01X139568D02*
X138977D01*
G01X141261D02*
X140670D01*
G01X143505D02*
X142914D01*
G01X145198D02*
X144607D01*
G01X147442D02*
X146851D01*
G01X149135D02*
X148544D01*
G01X151379D02*
X150788D01*
G01X153072D02*
X152481D01*
G01X155316D02*
X154725D01*
G01X157009D02*
X156418D01*
G01X159253D02*
X158662D01*
G01X160946D02*
X160355D01*
G01X163190D02*
X162599D01*
G01X172757D02*
X172166D01*
G01X175001D02*
X174410D01*
G01X176694D02*
X176103D01*
G01X178938D02*
X178347D01*
G01X180631D02*
X180040D01*
G01X182875D02*
X182284D01*
G01X184568D02*
X183977D01*
G01X186812D02*
X186221D01*
G01X183977Y231555D02*
X186812D01*
G01X180040D02*
X182875D01*
G01X176103D02*
X178938D01*
G01X172166D02*
X175001D01*
G01X156418D02*
X159253D01*
G01X148544D02*
X151379D01*
G01X144607D02*
X147442D01*
G01X140670D02*
X143505D01*
G01X136733D02*
X139568D01*
G01X132796D02*
X135631D01*
G01X128859D02*
X131694D01*
G01X124922D02*
X127757D01*
G01X123820D02*
X120985D01*
G01X155316D02*
X152481D01*
G01X163190D02*
X160355D01*
G01X123229Y231456D02*
X121576D01*
G01X131103D02*
X129450D01*
G01X138977D02*
X137324D01*
G01X146851D02*
X145198D01*
G01X154725D02*
X153072D01*
G01X162599D02*
X160946D01*
G01X178347D02*
X176694D01*
G01X186221D02*
X184568D01*
G01X122890Y231368D02*
X121925D01*
G01X126822D02*
X125857D01*
G01X130764D02*
X129799D01*
G01X134696D02*
X133731D01*
G01X138638D02*
X137673D01*
G01X142570D02*
X141605D01*
G01X146512D02*
X145547D01*
G01X150444D02*
X149479D01*
G01X154386D02*
X153421D01*
G01X158318D02*
X157353D01*
G01X162260D02*
X161295D01*
G01X174066D02*
X173101D01*
G01X178008D02*
X177043D01*
G01X181940D02*
X180975D01*
G01X185882D02*
X184917D01*
G01X183977Y231358D02*
X184292D01*
G01X176103D02*
X176418D01*
G01X160355D02*
X160670D01*
G01X152481D02*
X152796D01*
G01X144607D02*
X144922D01*
G01X136733D02*
X137048D01*
G01X128859D02*
X129174D01*
G01X120985D02*
X121300D01*
G01X123820D02*
X123505D01*
G01X125237D02*
X124922D01*
G01X127757D02*
X127442D01*
G01X131694D02*
X131379D01*
G01X133111D02*
X132796D01*
G01X135631D02*
X135316D01*
G01X139568D02*
X139253D01*
G01X140985D02*
X140670D01*
G01X143505D02*
X143190D01*
G01X147442D02*
X147127D01*
G01X148859D02*
X148544D01*
G01X151379D02*
X151064D01*
G01X155316D02*
X155001D01*
G01X156733D02*
X156418D01*
G01X159253D02*
X158938D01*
G01X163190D02*
X162875D01*
G01X172481D02*
X172166D01*
G01X175001D02*
X174686D01*
G01X178938D02*
X178623D01*
G01X180355D02*
X180040D01*
G01X182875D02*
X182560D01*
G01X186812D02*
X186497D01*
G01X123418Y231260D02*
X121397D01*
G01X127350D02*
X125329D01*
G01X131292D02*
X129271D01*
G01X135224D02*
X133203D01*
G01X139166D02*
X137145D01*
G01X143098D02*
X141077D01*
G01X147040D02*
X145019D01*
G01X150972D02*
X148951D01*
G01X154914D02*
X152893D01*
G01X158846D02*
X156825D01*
G01X162788D02*
X160767D01*
G01X174594D02*
X172573D01*
G01X178536D02*
X176515D01*
G01X182468D02*
X180447D01*
G01X186410D02*
X184389D01*
G01X184568Y230964D02*
X186221D01*
G01X176694D02*
X178347D01*
G01X160946D02*
X162599D01*
G01X153072D02*
X154725D01*
G01X145198D02*
X146851D01*
G01X137324D02*
X138977D01*
G01X129450D02*
X131103D01*
G01X121576D02*
X123229D01*
G01X123157Y230772D02*
X121657D01*
G01X127089D02*
X125590D01*
G01X131031D02*
X129531D01*
G01X134963D02*
X133464D01*
G01X138905D02*
X137406D01*
G01X142837D02*
X141338D01*
G01X146779D02*
X145280D01*
G01X150711D02*
X149212D01*
G01X154653D02*
X153154D01*
G01X158585D02*
X157086D01*
G01X162527D02*
X161028D01*
G01X174333D02*
X172834D01*
G01X178275D02*
X176776D01*
G01X182207D02*
X180708D01*
G01X186149D02*
X184650D01*
G01X165178Y230767D02*
X170178D01*
G01X123155Y230762D02*
X121659D01*
G01X127088D02*
X125591D01*
G01X131029D02*
X129533D01*
G01X134962D02*
X133465D01*
G01X138903D02*
X137407D01*
G01X142836D02*
X141339D01*
G01X146777D02*
X145281D01*
G01X150710D02*
X149213D01*
G01X154651D02*
X153155D01*
G01X158584D02*
X157087D01*
G01X162525D02*
X161029D01*
G01X174332D02*
X172835D01*
G01X178274D02*
X176777D01*
G01X182206D02*
X180709D01*
G01X186148D02*
X184651D01*
G01X184871Y230441D02*
X185928D01*
G01X180929D02*
X181986D01*
G01X176997D02*
X178054D01*
G01X173055D02*
X174112D01*
G01X161249D02*
X162306D01*
G01X157307D02*
X158364D01*
G01X153375D02*
X154432D01*
G01X149433D02*
X150490D01*
G01X145501D02*
X146558D01*
G01X141559D02*
X142616D01*
G01X137627D02*
X138684D01*
G01X133685D02*
X134742D01*
G01X129753D02*
X130810D01*
G01X125811D02*
X126868D01*
G01X121879D02*
X122935D01*
G01X184214Y230393D02*
X186576D01*
G01X180277D02*
X182639D01*
G01X176340D02*
X178702D01*
G01X172403D02*
X174765D01*
G01X160592D02*
X162954D01*
G01X156655D02*
X159017D01*
G01X152717D02*
X155080D01*
G01X148780D02*
X151143D01*
G01X144843D02*
X147206D01*
G01X140906D02*
X143269D01*
G01X136969D02*
X139332D01*
G01X133032D02*
X135395D01*
G01X129095D02*
X131458D01*
G01X125158D02*
X127521D01*
G01X121221D02*
X123584D01*
G01X186497Y229862D02*
X186812D01*
G01X183977D02*
X184292D01*
G01X182560D02*
X182875D01*
G01X180040D02*
X180355D01*
G01X178623D02*
X178938D01*
G01X176103D02*
X176418D01*
G01X174686D02*
X175001D01*
G01X172166D02*
X172481D01*
G01X162875D02*
X163190D01*
G01X160355D02*
X160670D01*
G01X158938D02*
X159253D01*
G01X155001D02*
X155316D01*
G01X156418D02*
X156733D01*
G01X152481D02*
X152796D01*
G01X151064D02*
X151379D01*
G01X148544D02*
X148859D01*
G01X147127D02*
X147442D01*
G01X144607D02*
X144922D01*
G01X143190D02*
X143505D01*
G01X140670D02*
X140985D01*
G01X139253D02*
X139568D01*
G01X136733D02*
X137048D01*
G01X135316D02*
X135631D01*
G01X132796D02*
X133111D01*
G01X131379D02*
X131694D01*
G01X128859D02*
X129174D01*
G01X127442D02*
X127757D01*
G01X124922D02*
X125237D01*
G01X123505D02*
X123820D01*
G01X120985D02*
X121300D01*
G01X184628Y229826D02*
X186171D01*
G01X180686D02*
X182229D01*
G01X176754D02*
X178297D01*
G01X172812D02*
X174355D01*
G01X161006D02*
X162549D01*
G01X157064D02*
X158607D01*
G01X153132D02*
X154675D01*
G01X149190D02*
X150733D01*
G01X145258D02*
X146801D01*
G01X141316D02*
X142859D01*
G01X137384D02*
X138927D01*
G01X133442D02*
X134985D01*
G01X129510D02*
X131053D01*
G01X125568D02*
X127111D01*
G01X121636D02*
X123179D01*
G01X184639Y229807D02*
X186160D01*
G01X180697D02*
X182218D01*
G01X176765D02*
X178286D01*
G01X172823D02*
X174344D01*
G01X161017D02*
X162538D01*
G01X157075D02*
X158596D01*
G01X153143D02*
X154664D01*
G01X149201D02*
X150722D01*
G01X145269D02*
X146790D01*
G01X141327D02*
X142848D01*
G01X137395D02*
X138916D01*
G01X133453D02*
X134974D01*
G01X129521D02*
X131042D01*
G01X125579D02*
X127100D01*
G01X121647D02*
X123168D01*
G01X456576Y229685D02*
X115001D01*
G01X116241Y229389D02*
X111517D01*
G01X184568Y229193D02*
X186221D01*
G01X176694D02*
X178347D01*
G01X160946D02*
X162599D01*
G01X153072D02*
X154725D01*
G01X145198D02*
X146851D01*
G01X137324D02*
X138977D01*
G01X129450D02*
X131103D01*
G01X121576D02*
X123229D01*
G01Y228700D02*
X121576D01*
G01X131103D02*
X129450D01*
G01X138977D02*
X137324D01*
G01X146851D02*
X145198D01*
G01X154725D02*
X153072D01*
G01X162599D02*
X160946D01*
G01X178347D02*
X176694D01*
G01X186221D02*
X184568D01*
G01X123072Y228602D02*
X121733D01*
G01X130946D02*
X129607D01*
G01X138820D02*
X137481D01*
G01X146694D02*
X145355D01*
G01X154568D02*
X153229D01*
G01X162442D02*
X161103D01*
G01X178190D02*
X176851D01*
G01X186064D02*
X184725D01*
G01Y227618D02*
X186064D01*
G01X176851D02*
X178190D01*
G01X161103D02*
X162442D01*
G01X153229D02*
X154568D01*
G01X145355D02*
X146694D01*
G01X137481D02*
X138820D01*
G01X129607D02*
X130946D01*
G01X121733D02*
X123072D01*
G01X116497Y227126D02*
X112560D01*
G01X123205Y226999D02*
X121610D01*
G01X127137D02*
X125542D01*
G01X131079D02*
X129484D01*
G01X135011D02*
X133416D01*
G01X138953D02*
X137358D01*
G01X142885D02*
X141290D01*
G01X146827D02*
X145232D01*
G01X150759D02*
X149164D01*
G01X154701D02*
X153106D01*
G01X158633D02*
X157038D01*
G01X162575D02*
X160980D01*
G01X174381D02*
X172786D01*
G01X178323D02*
X176728D01*
G01X182255D02*
X180660D01*
G01X186197D02*
X184602D01*
G01X123505Y226889D02*
X121300D01*
G01X127442D02*
X125237D01*
G01X131379D02*
X129174D01*
G01X135316D02*
X133111D01*
G01X139253D02*
X137048D01*
G01X143190D02*
X140985D01*
G01X147127D02*
X144922D01*
G01X151064D02*
X148859D01*
G01X155001D02*
X152796D01*
G01X158938D02*
X156733D01*
G01X162875D02*
X160670D01*
G01X174686D02*
X172481D01*
G01X178623D02*
X176418D01*
G01X182560D02*
X180355D01*
G01X186497D02*
X184292D01*
G01X164933Y226732D02*
X116958D01*
G01X454618D02*
X170423D01*
G01X123277Y226239D02*
X121538D01*
G01X127209D02*
X125470D01*
G01X131151D02*
X129412D01*
G01X135083D02*
X133344D01*
G01X139025D02*
X137286D01*
G01X142957D02*
X141218D01*
G01X146899D02*
X145160D01*
G01X150831D02*
X149092D01*
G01X154773D02*
X153034D01*
G01X158705D02*
X156966D01*
G01X162647D02*
X160908D01*
G01X174453D02*
X172714D01*
G01X178395D02*
X176656D01*
G01X182327D02*
X180588D01*
G01X186269D02*
X184530D01*
G01X184604Y226037D02*
X186195D01*
G01X180662D02*
X182253D01*
G01X176730D02*
X178321D01*
G01X172788D02*
X174379D01*
G01X160982D02*
X162573D01*
G01X157040D02*
X158631D01*
G01X153108D02*
X154699D01*
G01X149166D02*
X150757D01*
G01X145234D02*
X146825D01*
G01X141292D02*
X142883D01*
G01X137360D02*
X138950D01*
G01X133418D02*
X135009D01*
G01X129486D02*
X131076D01*
G01X125544D02*
X127135D01*
G01X121612D02*
X123202D01*
G01X184551Y226012D02*
X186247D01*
G01X180610D02*
X182306D01*
G01X176677D02*
X178373D01*
G01X172736D02*
X174432D01*
G01X160929D02*
X162625D01*
G01X156988D02*
X158684D01*
G01X153055D02*
X154751D01*
G01X149114D02*
X150810D01*
G01X145181D02*
X146877D01*
G01X141239D02*
X142936D01*
G01X137307D02*
X139003D01*
G01X133365D02*
X135062D01*
G01X129433D02*
X131129D01*
G01X125491D02*
X127188D01*
G01X121559D02*
X123255D01*
G01X123262Y225945D02*
X121552D01*
G01X127195D02*
X125484D01*
G01X131136D02*
X129426D01*
G01X135069D02*
X133358D01*
G01X139010D02*
X137300D01*
G01X142943D02*
X141233D01*
G01X146884D02*
X145174D01*
G01X150817D02*
X149107D01*
G01X154758D02*
X153048D01*
G01X158691D02*
X156981D01*
G01X162632D02*
X160922D01*
G01X174439D02*
X172729D01*
G01X178380D02*
X176670D01*
G01X182313D02*
X180603D01*
G01X186254D02*
X184544D01*
G01X184525Y225353D02*
X186274D01*
G01X180583D02*
X182332D01*
G01X176651D02*
X178399D01*
G01X172709D02*
X174458D01*
G01X160903D02*
X162651D01*
G01X156961D02*
X158710D01*
G01X153029D02*
X154777D01*
G01X149087D02*
X150836D01*
G01X145155D02*
X146903D01*
G01X141213D02*
X142962D01*
G01X137281D02*
X139029D01*
G01X133339D02*
X135088D01*
G01X129407D02*
X131155D01*
G01X125465D02*
X127214D01*
G01X121533D02*
X123281D01*
G01X123253Y225050D02*
X121561D01*
G01X127185D02*
X125494D01*
G01X131127D02*
X129435D01*
G01X135059D02*
X133368D01*
G01X139001D02*
X137309D01*
G01X142933D02*
X141242D01*
G01X146875D02*
X145184D01*
G01X150807D02*
X149116D01*
G01X154749D02*
X153058D01*
G01X158681D02*
X156990D01*
G01X162623D02*
X160932D01*
G01X174429D02*
X172738D01*
G01X178371D02*
X176680D01*
G01X182303D02*
X180612D01*
G01X186245D02*
X184554D01*
G01X123262Y224960D02*
X121552D01*
G01X127195D02*
X125484D01*
G01X131136D02*
X129426D01*
G01X135069D02*
X133358D01*
G01X139010D02*
X137300D01*
G01X142943D02*
X141233D01*
G01X146884D02*
X145174D01*
G01X150817D02*
X149107D01*
G01X154758D02*
X153048D01*
G01X158691D02*
X156981D01*
G01X162632D02*
X160922D01*
G01X174439D02*
X172729D01*
G01X178380D02*
X176670D01*
G01X182313D02*
X180603D01*
G01X186254D02*
X184544D01*
G01X184292Y224634D02*
X186497D01*
G01X180355D02*
X182560D01*
G01X176418D02*
X178623D01*
G01X172481D02*
X174686D01*
G01X123505D02*
X121300D01*
G01X127442D02*
X125237D01*
G01X131379D02*
X129174D01*
G01X135316D02*
X133111D01*
G01X139253D02*
X137048D01*
G01X143190D02*
X140985D01*
G01X147127D02*
X144922D01*
G01X151064D02*
X148859D01*
G01X155001D02*
X152796D01*
G01X158938D02*
X156733D01*
G01X162875D02*
X160670D01*
G01X184292Y224467D02*
X186497D01*
G01X180355D02*
X182560D01*
G01X176418D02*
X178623D01*
G01X172481D02*
X174686D01*
G01X160670D02*
X162875D01*
G01X156733D02*
X158938D01*
G01X152796D02*
X155001D01*
G01X148859D02*
X151064D01*
G01X144922D02*
X147127D01*
G01X140985D02*
X143190D01*
G01X137048D02*
X139253D01*
G01X133111D02*
X135316D01*
G01X129174D02*
X131379D01*
G01X125237D02*
X127442D01*
G01X121300D02*
X123505D01*
G01Y221910D02*
X121300D01*
G01X127442D02*
X125237D01*
G01X131379D02*
X129174D01*
G01X135316D02*
X133111D01*
G01X139253D02*
X137048D01*
G01X143190D02*
X140985D01*
G01X147127D02*
X144922D01*
G01X151064D02*
X148859D01*
G01X155001D02*
X152796D01*
G01X158938D02*
X156733D01*
G01X162875D02*
X160670D01*
G01X174686D02*
X172481D01*
G01X178623D02*
X176418D01*
G01X182560D02*
X180355D01*
G01X186497D02*
X184292D01*
G01X160670Y221743D02*
X162875D01*
G01X156733D02*
X158938D01*
G01X152796D02*
X155001D01*
G01X148859D02*
X151064D01*
G01X144922D02*
X147127D01*
G01X140985D02*
X143190D01*
G01X137048D02*
X139253D01*
G01X133111D02*
X135316D01*
G01X129174D02*
X131379D01*
G01X125237D02*
X127442D01*
G01X121300D02*
X123505D01*
G01X174686D02*
X172481D01*
G01X178623D02*
X176418D01*
G01X182560D02*
X180355D01*
G01X186497D02*
X184292D01*
G01X184535Y221417D02*
X186245D01*
G01X180603D02*
X182313D01*
G01X176661D02*
X178371D01*
G01X172729D02*
X174439D01*
G01X160913D02*
X162623D01*
G01X156981D02*
X158691D01*
G01X153039D02*
X154749D01*
G01X149107D02*
X150817D01*
G01X145165D02*
X146875D01*
G01X141233D02*
X142943D01*
G01X137291D02*
X139001D01*
G01X133358D02*
X135069D01*
G01X129417D02*
X131127D01*
G01X125484D02*
X127195D01*
G01X121543D02*
X123253D01*
G01X184544Y221327D02*
X186236D01*
G01X180612D02*
X182303D01*
G01X176670D02*
X178362D01*
G01X172738D02*
X174429D01*
G01X160922D02*
X162614D01*
G01X156990D02*
X158681D01*
G01X153048D02*
X154740D01*
G01X149116D02*
X150807D01*
G01X145174D02*
X146866D01*
G01X141242D02*
X142933D01*
G01X137300D02*
X138992D01*
G01X133368D02*
X135059D01*
G01X129426D02*
X131118D01*
G01X125494D02*
X127185D01*
G01X121552D02*
X123244D01*
G01X123272Y221024D02*
X121524D01*
G01X127214D02*
X125465D01*
G01X131146D02*
X129398D01*
G01X135088D02*
X133339D01*
G01X139020D02*
X137272D01*
G01X142962D02*
X141213D01*
G01X146894D02*
X145146D01*
G01X150836D02*
X149087D01*
G01X154768D02*
X153020D01*
G01X158710D02*
X156961D01*
G01X162642D02*
X160894D01*
G01X174458D02*
X172709D01*
G01X178390D02*
X176642D01*
G01X182332D02*
X180583D01*
G01X186264D02*
X184516D01*
G01X184535Y220433D02*
X186245D01*
G01X180603D02*
X182313D01*
G01X176661D02*
X178371D01*
G01X172729D02*
X174439D01*
G01X160913D02*
X162623D01*
G01X156981D02*
X158691D01*
G01X153039D02*
X154749D01*
G01X149107D02*
X150817D01*
G01X145165D02*
X146875D01*
G01X141233D02*
X142943D01*
G01X137291D02*
X139001D01*
G01X133358D02*
X135069D01*
G01X129417D02*
X131127D01*
G01X125484D02*
X127195D01*
G01X121543D02*
X123253D01*
G01X123246Y220365D02*
X121550D01*
G01X127188D02*
X125491D01*
G01X131120D02*
X129424D01*
G01X135062D02*
X133365D01*
G01X138994D02*
X137298D01*
G01X142936D02*
X141239D01*
G01X146868D02*
X145172D01*
G01X150810D02*
X149114D01*
G01X154742D02*
X153046D01*
G01X158684D02*
X156988D01*
G01X162616D02*
X160920D01*
G01X174432D02*
X172736D01*
G01X178364D02*
X176668D01*
G01X182306D02*
X180610D01*
G01X186238D02*
X184542D01*
G01X123193Y220340D02*
X121603D01*
G01X127135D02*
X125544D01*
G01X131067D02*
X129477D01*
G01X135009D02*
X133418D01*
G01X138941D02*
X137351D01*
G01X142883D02*
X141292D01*
G01X146815D02*
X145225D01*
G01X150757D02*
X149166D01*
G01X154689D02*
X153099D01*
G01X158631D02*
X157040D01*
G01X162563D02*
X160973D01*
G01X174379D02*
X172788D01*
G01X178311D02*
X176721D01*
G01X182253D02*
X180662D01*
G01X186185D02*
X184595D01*
G01X184521Y220138D02*
X186259D01*
G01X180588D02*
X182327D01*
G01X176647D02*
X178385D01*
G01X172714D02*
X174453D01*
G01X160899D02*
X162637D01*
G01X156966D02*
X158705D01*
G01X153025D02*
X154763D01*
G01X149092D02*
X150831D01*
G01X145151D02*
X146889D01*
G01X141218D02*
X142957D01*
G01X137276D02*
X139015D01*
G01X133344D02*
X135083D01*
G01X129402D02*
X131141D01*
G01X125470D02*
X127209D01*
G01X121528D02*
X123267D01*
G01X170423Y219645D02*
X454618D01*
G01X116958D02*
X164933D01*
G01X184292Y219488D02*
X186497D01*
G01X180355D02*
X182560D01*
G01X176418D02*
X178623D01*
G01X172481D02*
X174686D01*
G01X160670D02*
X162875D01*
G01X156733D02*
X158938D01*
G01X152796D02*
X155001D01*
G01X148859D02*
X151064D01*
G01X144922D02*
X147127D01*
G01X140985D02*
X143190D01*
G01X137048D02*
X139253D01*
G01X133111D02*
X135316D01*
G01X129174D02*
X131379D01*
G01X125237D02*
X127442D01*
G01X121300D02*
X123505D01*
G01X184592Y219379D02*
X186188D01*
G01X180660D02*
X182255D01*
G01X176718D02*
X178314D01*
G01X172786D02*
X174381D01*
G01X160970D02*
X162566D01*
G01X157038D02*
X158633D01*
G01X153096D02*
X154692D01*
G01X149164D02*
X150759D01*
G01X145222D02*
X146817D01*
G01X141290D02*
X142885D01*
G01X137348D02*
X138943D01*
G01X133416D02*
X135011D01*
G01X129474D02*
X131069D01*
G01X125542D02*
X127137D01*
G01X121600D02*
X123195D01*
G01X112560Y219252D02*
X116497D01*
G01X123072Y218760D02*
X121733D01*
G01X130946D02*
X129607D01*
G01X138820D02*
X137481D01*
G01X146694D02*
X145355D01*
G01X154568D02*
X153229D01*
G01X162442D02*
X161103D01*
G01X178190D02*
X176851D01*
G01X186064D02*
X184725D01*
G01X123072Y217775D02*
X121733D01*
G01X130946D02*
X129607D01*
G01X138820D02*
X137481D01*
G01X146694D02*
X145355D01*
G01X154568D02*
X153229D01*
G01X162442D02*
X161103D01*
G01X178190D02*
X176851D01*
G01X186064D02*
X184725D01*
G01X184568Y217677D02*
X186221D01*
G01X176694D02*
X178347D01*
G01X160946D02*
X162599D01*
G01X153072D02*
X154725D01*
G01X145198D02*
X146851D01*
G01X137324D02*
X138977D01*
G01X129450D02*
X131103D01*
G01X121576D02*
X123229D01*
G01Y217185D02*
X121576D01*
G01X131103D02*
X129450D01*
G01X138977D02*
X137324D01*
G01X146851D02*
X145198D01*
G01X154725D02*
X153072D01*
G01X162599D02*
X160946D01*
G01X178347D02*
X176694D01*
G01X186221D02*
X184568D01*
G01X116241Y216988D02*
X111517D01*
G01X115001Y216693D02*
X456576D01*
G01X123159Y216570D02*
X121637D01*
G01X127100D02*
X125579D01*
G01X131033D02*
X129511D01*
G01X134974D02*
X133453D01*
G01X138907D02*
X137385D01*
G01X142848D02*
X141327D01*
G01X146781D02*
X145259D01*
G01X150722D02*
X149201D01*
G01X154655D02*
X153133D01*
G01X158596D02*
X157075D01*
G01X162529D02*
X161007D01*
G01X174344D02*
X172823D01*
G01X178277D02*
X176755D01*
G01X182218D02*
X180697D01*
G01X186151D02*
X184629D01*
G01X123170Y216551D02*
X121626D01*
G01X127111D02*
X125568D01*
G01X131044D02*
X129500D01*
G01X134985D02*
X133442D01*
G01X138918D02*
X137374D01*
G01X142859D02*
X141316D01*
G01X146792D02*
X145248D01*
G01X150733D02*
X149190D01*
G01X154666D02*
X153122D01*
G01X158607D02*
X157064D01*
G01X162540D02*
X160996D01*
G01X174355D02*
X172812D01*
G01X178288D02*
X176744D01*
G01X182229D02*
X180686D01*
G01X186162D02*
X184618D01*
G01X121300Y216515D02*
X120985D01*
G01X123820D02*
X123505D01*
G01X125237D02*
X124922D01*
G01X127757D02*
X127442D01*
G01X129174D02*
X128859D01*
G01X131694D02*
X131379D01*
G01X133111D02*
X132796D01*
G01X137048D02*
X136733D01*
G01X135631D02*
X135316D01*
G01X139568D02*
X139253D01*
G01X140985D02*
X140670D01*
G01X143505D02*
X143190D01*
G01X144922D02*
X144607D01*
G01X147442D02*
X147127D01*
G01X148859D02*
X148544D01*
G01X151379D02*
X151064D01*
G01X152796D02*
X152481D01*
G01X155316D02*
X155001D01*
G01X156733D02*
X156418D01*
G01X159253D02*
X158938D01*
G01X160670D02*
X160355D01*
G01X163190D02*
X162875D01*
G01X172481D02*
X172166D01*
G01X175001D02*
X174686D01*
G01X176418D02*
X176103D01*
G01X178938D02*
X178623D01*
G01X180355D02*
X180040D01*
G01X182875D02*
X182560D01*
G01X184292D02*
X183977D01*
G01X186812D02*
X186497D01*
G01X123584Y215984D02*
X121221D01*
G01X127521D02*
X125158D01*
G01X131458D02*
X129095D01*
G01X135395D02*
X133032D01*
G01X139332D02*
X136969D01*
G01X143269D02*
X140906D01*
G01X147206D02*
X144843D01*
G01X151143D02*
X148780D01*
G01X155080D02*
X152717D01*
G01X159017D02*
X156655D01*
G01X162954D02*
X160592D01*
G01X174765D02*
X172403D01*
G01X178702D02*
X176340D01*
G01X182639D02*
X180277D01*
G01X186576D02*
X184214D01*
G01X122926Y215937D02*
X121870D01*
G01X126868D02*
X125811D01*
G01X130800D02*
X129744D01*
G01X134742D02*
X133685D01*
G01X138674D02*
X137618D01*
G01X142616D02*
X141559D01*
G01X146548D02*
X145492D01*
G01X150490D02*
X149433D01*
G01X154422D02*
X153366D01*
G01X158364D02*
X157307D01*
G01X162296D02*
X161240D01*
G01X174112D02*
X173055D01*
G01X178044D02*
X176988D01*
G01X181986D02*
X180929D01*
G01X185918D02*
X184862D01*
G01X184642Y215615D02*
X186138D01*
G01X180709D02*
X182206D01*
G01X176768D02*
X178264D01*
G01X172835D02*
X174332D01*
G01X161020D02*
X162516D01*
G01X157087D02*
X158584D01*
G01X153146D02*
X154642D01*
G01X149213D02*
X150710D01*
G01X145272D02*
X146768D01*
G01X141339D02*
X142836D01*
G01X137398D02*
X138894D01*
G01X133465D02*
X134962D01*
G01X129524D02*
X131020D01*
G01X125591D02*
X127088D01*
G01X121650D02*
X123146D01*
G01X170178Y215610D02*
X165178D01*
G01X184640Y215605D02*
X186140D01*
G01X180708D02*
X182207D01*
G01X176766D02*
X178266D01*
G01X172834D02*
X174333D01*
G01X161018D02*
X162518D01*
G01X157086D02*
X158585D01*
G01X153144D02*
X154644D01*
G01X149212D02*
X150711D01*
G01X145270D02*
X146770D01*
G01X141338D02*
X142837D01*
G01X137396D02*
X138896D01*
G01X133464D02*
X134963D01*
G01X129522D02*
X131022D01*
G01X125590D02*
X127089D01*
G01X121648D02*
X123148D01*
G01X123229Y215413D02*
X121576D01*
G01X131103D02*
X129450D01*
G01X138977D02*
X137324D01*
G01X146851D02*
X145198D01*
G01X154725D02*
X153072D01*
G01X162599D02*
X160946D01*
G01X178347D02*
X176694D01*
G01X186221D02*
X184568D01*
G01X184380Y215117D02*
X186400D01*
G01X180447D02*
X182468D01*
G01X176506D02*
X178526D01*
G01X172573D02*
X174594D01*
G01X160758D02*
X162778D01*
G01X156825D02*
X158846D01*
G01X152884D02*
X154904D01*
G01X148951D02*
X150972D01*
G01X145009D02*
X147030D01*
G01X141077D02*
X143098D01*
G01X137135D02*
X139156D01*
G01X133203D02*
X135224D01*
G01X129261D02*
X131282D01*
G01X125329D02*
X127350D01*
G01X121387D02*
X123408D01*
G01X186497Y215019D02*
X186812D01*
G01X178623D02*
X178938D01*
G01X162875D02*
X163190D01*
G01X155001D02*
X155316D01*
G01X147127D02*
X147442D01*
G01X139253D02*
X139568D01*
G01X131379D02*
X131694D01*
G01X123505D02*
X123820D01*
G01X121300D02*
X120985D01*
G01X125237D02*
X124922D01*
G01X127757D02*
X127442D01*
G01X129174D02*
X128859D01*
G01X133111D02*
X132796D01*
G01X137048D02*
X136733D01*
G01X135631D02*
X135316D01*
G01X140985D02*
X140670D01*
G01X143505D02*
X143190D01*
G01X144922D02*
X144607D01*
G01X148859D02*
X148544D01*
G01X151379D02*
X151064D01*
G01X152796D02*
X152481D01*
G01X156733D02*
X156418D01*
G01X159253D02*
X158938D01*
G01X160670D02*
X160355D01*
G01X172481D02*
X172166D01*
G01X175001D02*
X174686D01*
G01X176418D02*
X176103D01*
G01X180355D02*
X180040D01*
G01X182875D02*
X182560D01*
G01X184292D02*
X183977D01*
G01X184907Y215009D02*
X185873D01*
G01X180975D02*
X181940D01*
G01X177033D02*
X177999D01*
G01X173101D02*
X174066D01*
G01X161285D02*
X162251D01*
G01X157353D02*
X158318D01*
G01X153411D02*
X154377D01*
G01X149479D02*
X150444D01*
G01X145537D02*
X146503D01*
G01X141605D02*
X142570D01*
G01X137663D02*
X138629D01*
G01X133731D02*
X134696D01*
G01X129789D02*
X130755D01*
G01X125857D02*
X126822D01*
G01X121915D02*
X122881D01*
G01X184568Y214921D02*
X186221D01*
G01X176694D02*
X178347D01*
G01X160946D02*
X162599D01*
G01X153072D02*
X154725D01*
G01X145198D02*
X146851D01*
G01X137324D02*
X138977D01*
G01X129450D02*
X131103D01*
G01X121576D02*
X123229D01*
G01X183977Y214822D02*
X186812D01*
G01X180040D02*
X182875D01*
G01X176103D02*
X178938D01*
G01X172166D02*
X175001D01*
G01X160355D02*
X163190D01*
G01X156418D02*
X159253D01*
G01X152481D02*
X155316D01*
G01X148544D02*
X151379D01*
G01X144607D02*
X147442D01*
G01X140670D02*
X143505D01*
G01X136733D02*
X139568D01*
G01X132796D02*
X135631D01*
G01X128859D02*
X131694D01*
G01X124922D02*
X127757D01*
G01X120985D02*
X123820D01*
G01X186221Y214665D02*
X186812D01*
G01X183977D02*
X184568D01*
G01X182284D02*
X182875D01*
G01X180040D02*
X180631D01*
G01X178347D02*
X178938D01*
G01X176103D02*
X176694D01*
G01X174410D02*
X175001D01*
G01X172166D02*
X172757D01*
G01X162599D02*
X163190D01*
G01X160355D02*
X160946D01*
G01X158662D02*
X159253D01*
G01X156418D02*
X157009D01*
G01X154725D02*
X155316D01*
G01X152481D02*
X153072D01*
G01X150788D02*
X151379D01*
G01X148544D02*
X149135D01*
G01X146851D02*
X147442D01*
G01X144607D02*
X145198D01*
G01X142914D02*
X143505D01*
G01X140670D02*
X141261D01*
G01X138977D02*
X139568D01*
G01X136733D02*
X137324D01*
G01X135040D02*
X135631D01*
G01X132796D02*
X133387D01*
G01X131103D02*
X131694D01*
G01X128859D02*
X129450D01*
G01X127166D02*
X127757D01*
G01X124922D02*
X125513D01*
G01X123229D02*
X123820D01*
G01X120985D02*
X121576D01*
G01X123134Y214640D02*
X121661D01*
G01X127076D02*
X125603D01*
G01X131008D02*
X129535D01*
G01X134950D02*
X133477D01*
G01X138882D02*
X137409D01*
G01X142824D02*
X141351D01*
G01X146756D02*
X145283D01*
G01X150698D02*
X149225D01*
G01X154630D02*
X153157D01*
G01X158572D02*
X157099D01*
G01X162504D02*
X161031D01*
G01X174320D02*
X172847D01*
G01X178252D02*
X176779D01*
G01X182194D02*
X180721D01*
G01X186126D02*
X184653D01*
G01X184640Y214621D02*
X186140D01*
G01X180708D02*
X182207D01*
G01X176766D02*
X178266D01*
G01X172834D02*
X174333D01*
G01X161018D02*
X162518D01*
G01X157086D02*
X158585D01*
G01X153144D02*
X154644D01*
G01X149212D02*
X150711D01*
G01X145270D02*
X146770D01*
G01X141338D02*
X142837D01*
G01X137396D02*
X138896D01*
G01X133464D02*
X134963D01*
G01X129522D02*
X131022D01*
G01X125590D02*
X127089D01*
G01X121648D02*
X123148D01*
G01X123403Y214231D02*
X121392D01*
G01X127345D02*
X125334D01*
G01X131278D02*
X129266D01*
G01X135219D02*
X133208D01*
G01X139152D02*
X137140D01*
G01X143093D02*
X141082D01*
G01X147026D02*
X145014D01*
G01X150967D02*
X148956D01*
G01X154900D02*
X152888D01*
G01X158841D02*
X156830D01*
G01X162774D02*
X160762D01*
G01X174589D02*
X172578D01*
G01X178522D02*
X176510D01*
G01X182463D02*
X180452D01*
G01X186396D02*
X184384D01*
G01X121576Y213996D02*
X120985D01*
G01X123820D02*
X123229D01*
G01X125513D02*
X124922D01*
G01X127757D02*
X127166D01*
G01X129450D02*
X128859D01*
G01X131694D02*
X131103D01*
G01X133387D02*
X132796D01*
G01X135631D02*
X135040D01*
G01X137324D02*
X136733D01*
G01X139568D02*
X138977D01*
G01X141261D02*
X140670D01*
G01X143505D02*
X142914D01*
G01X145198D02*
X144607D01*
G01X147442D02*
X146851D01*
G01X149135D02*
X148544D01*
G01X151379D02*
X150788D01*
G01X153072D02*
X152481D01*
G01X155316D02*
X154725D01*
G01X157009D02*
X156418D01*
G01X159253D02*
X158662D01*
G01X160946D02*
X160355D01*
G01X163190D02*
X162599D01*
G01X172757D02*
X172166D01*
G01X175001D02*
X174410D01*
G01X176694D02*
X176103D01*
G01X178938D02*
X178347D01*
G01X180631D02*
X180040D01*
G01X182875D02*
X182284D01*
G01X184568D02*
X183977D01*
G01X186812D02*
X186221D01*
G01X123820Y213838D02*
X120985D01*
G01X127757D02*
X124922D01*
G01X131694D02*
X128859D01*
G01X135631D02*
X132796D01*
G01X139568D02*
X136733D01*
G01X143505D02*
X140670D01*
G01X147442D02*
X144607D01*
G01X151379D02*
X148544D01*
G01X155316D02*
X152481D01*
G01X159253D02*
X156418D01*
G01X163190D02*
X160355D01*
G01X175001D02*
X172166D01*
G01X178938D02*
X176103D01*
G01X182875D02*
X180040D01*
G01X186812D02*
X183977D01*
G01X127166Y213740D02*
X125513D01*
G01X135040D02*
X133387D01*
G01X142914D02*
X141261D01*
G01X150788D02*
X149135D01*
G01X158662D02*
X157009D01*
G01X174410D02*
X172757D01*
G01X182284D02*
X180631D01*
G01Y213248D02*
X182284D01*
G01X172757D02*
X174410D01*
G01X157009D02*
X158662D01*
G01X149135D02*
X150788D01*
G01X141261D02*
X142914D01*
G01X133387D02*
X135040D01*
G01X125513D02*
X127166D01*
G01X183977Y212342D02*
X186812D01*
G01X180040D02*
X182875D01*
G01X176103D02*
X178938D01*
G01X172166D02*
X175001D01*
G01X160355D02*
X163190D01*
G01X156418D02*
X159253D01*
G01X152481D02*
X155316D01*
G01X148544D02*
X151379D01*
G01X144607D02*
X147442D01*
G01X140670D02*
X143505D01*
G01X136733D02*
X139568D01*
G01X132796D02*
X135631D01*
G01X128859D02*
X131694D01*
G01X124922D02*
X127757D01*
G01X120985D02*
X123820D01*
G01X180631Y211476D02*
X182284D01*
G01X172757D02*
X174410D01*
G01X157009D02*
X158662D01*
G01X149135D02*
X150788D01*
G01X141261D02*
X142914D01*
G01X133387D02*
X135040D01*
G01X125513D02*
X127166D01*
G01X184214Y211082D02*
X186576D01*
G01X180277D02*
X182639D01*
G01X172403D02*
X174765D01*
G01X160592D02*
X162954D01*
G01X156655D02*
X159017D01*
G01X152717D02*
X155080D01*
G01X148780D02*
X151143D01*
G01X144843D02*
X147206D01*
G01X140906D02*
X143269D01*
G01X136969D02*
X139332D01*
G01X133032D02*
X135395D01*
G01X129095D02*
X131458D01*
G01X125158D02*
X127521D01*
G01X121221D02*
X123584D01*
G01X116241D02*
X111517D01*
G01X178702D02*
X176340D01*
G01X127166Y210984D02*
X125513D01*
G01X135040D02*
X133387D01*
G01X142914D02*
X141261D01*
G01X150788D02*
X149135D01*
G01X158662D02*
X157009D01*
G01X174410D02*
X172757D01*
G01X182284D02*
X180631D01*
G01X165178Y210885D02*
X170178D01*
G01X127009D02*
X125670D01*
G01X134883D02*
X133544D01*
G01X142757D02*
X141418D01*
G01X150631D02*
X149292D01*
G01X158505D02*
X157166D01*
G01X174253D02*
X172914D01*
G01X182127D02*
X180788D01*
G01X115001Y203577D02*
X115575Y203661D01*
G01X184214Y209901D02*
X186576D01*
G01X180277D02*
X182639D01*
G01X176340D02*
X178702D01*
G01X172403D02*
X174765D01*
G01X160592D02*
X162954D01*
G01X156655D02*
X159017D01*
G01X152717D02*
X155080D01*
G01X148780D02*
X151143D01*
G01X144843D02*
X147206D01*
G01X140906D02*
X143269D01*
G01X136969D02*
X139332D01*
G01X133032D02*
X135395D01*
G01X129095D02*
X131458D01*
G01X125158D02*
X127521D01*
G01X121221D02*
X123584D01*
G01X460985Y208523D02*
X110592D01*
G01X115575Y203661D02*
X115739D01*
G01X112294D02*
X109506D01*
G01X109916Y203242D02*
X112294D01*
G01X115821D02*
X115493D01*
G01X181458Y203011D02*
X201143D01*
G01X157836D02*
X177521D01*
G01X134214D02*
X153899D01*
G01X130277D02*
X110592D01*
G01X114673Y202740D02*
X114263D01*
G01X123613Y202405D02*
X123941D01*
G01X122301D02*
X122629D01*
G01X121481D02*
X121891D01*
G01X119922D02*
X120250D01*
G01X118610D02*
X118938D01*
G01X117790D02*
X118200D01*
G01X111228Y202237D02*
X110736D01*
G01X118774Y202070D02*
X118610D01*
G01X120086D02*
X119840D01*
G01X122465D02*
X122301D01*
G01X123777D02*
X123531D01*
G01X115493Y201902D02*
X115821D01*
G01X110736Y201818D02*
X111228D01*
G01X115821Y201567D02*
X115493D01*
G01X109506Y201483D02*
X110080D01*
G01X109998Y200729D02*
X109506D01*
G01X114181Y200646D02*
X114591D01*
G01X115411Y200143D02*
X115903D01*
G01X113114D02*
X113525D01*
G01X111228D02*
X110736D01*
G01Y199724D02*
X111228D01*
G01X113525D02*
X113114D01*
G01X115985D02*
X115329D01*
G01X118200D02*
X117790D01*
G01X119512D02*
X119102D01*
G01X121891D02*
X121481D01*
G01X120824D02*
X120414D01*
G01X123203D02*
X122793D01*
G01X124515D02*
X124105D01*
G01X116313Y201483D02*
X115821Y201567D01*
G01X115739Y203661D02*
X116313Y203577D01*
G01X111228Y201818D02*
X111556Y201734D01*
G01X115329Y199724D02*
X115001Y199808D01*
G01X110736Y200143D02*
X110408Y200227D01*
G01X116231Y203158D02*
X115821Y203242D01*
G01X111638Y202153D02*
X111228Y202237D01*
G01X115001Y200227D02*
X115411Y200143D01*
G01X110326Y199808D02*
X110736Y199724D01*
G01X116477Y201734D02*
X116887Y201567D01*
G01X123941Y202405D02*
X124187Y202321D01*
G01X122629Y202405D02*
X122875Y202321D01*
G01X120250Y202405D02*
X120496Y202321D01*
G01X118938Y202405D02*
X119184Y202321D01*
G01X123941Y201986D02*
X123777Y202070D01*
G01X122629Y201986D02*
X122465Y202070D01*
G01X120250Y201986D02*
X120086Y202070D01*
G01X116313Y203577D02*
X116641Y203410D01*
G01X118938Y201986D02*
X118774Y202070D01*
G01X114837Y200310D02*
X115001Y200227D01*
G01Y199808D02*
X114673Y199975D01*
G01X107701Y201734D02*
X108849Y201148D01*
G01X116477Y202991D02*
X116231Y203158D01*
G01X112048Y201902D02*
X111638Y202153D01*
G01X109916Y200059D02*
X110326Y199808D01*
G01X108685Y200897D02*
X107127Y201734D01*
G01X184917Y231368D02*
X184663Y231737D01*
G01X184871Y230441D02*
X184650Y230762D01*
G01X180975Y231368D02*
X180721Y231737D01*
G01X180710Y230760D02*
X180929Y230441D01*
G01X177043Y231368D02*
X176789Y231737D01*
G01X176997Y230441D02*
X176776Y230762D01*
G01X185918Y215937D02*
X186140Y215615D01*
G01X185873Y215009D02*
X186126Y214640D01*
G01X173101Y231368D02*
X172847Y231737D01*
G01X172836Y230760D02*
X173055Y230441D01*
G01X182206Y215617D02*
X181986Y215937D01*
G01X116559Y201316D02*
X116313Y201483D01*
G01X114673Y199975D02*
X114427Y200143D01*
G01X111556Y201734D02*
X111802Y201567D01*
G01X110408Y200227D02*
X110162Y200394D01*
G01X170423Y226732D02*
X168936Y228975D01*
G01X164933Y219645D02*
X166421Y217402D01*
G01X181940Y215009D02*
X182194Y214640D01*
G01X178044Y215937D02*
X178266Y215615D01*
G01X177999Y215009D02*
X178252Y214640D01*
G01X174332Y215617D02*
X174112Y215937D01*
G01X174066Y215009D02*
X174320Y214640D01*
G01X161295Y231368D02*
X161041Y231737D01*
G01X161249Y230441D02*
X161028Y230762D01*
G01X157353Y231368D02*
X157099Y231737D01*
G01X157088Y230760D02*
X157307Y230441D01*
G01X153421Y231368D02*
X153167Y231737D01*
G01X153375Y230441D02*
X153154Y230762D01*
G01X162296Y215937D02*
X162518Y215615D01*
G01X162251Y215009D02*
X162504Y214640D01*
G01X149479Y231368D02*
X149225Y231737D01*
G01X149214Y230760D02*
X149433Y230441D01*
G01X158584Y215617D02*
X158364Y215937D01*
G01X158318Y215009D02*
X158572Y214640D01*
G01X145547Y231368D02*
X145293Y231737D01*
G01X145501Y230441D02*
X145280Y230762D01*
G01X154422Y215937D02*
X154644Y215615D01*
G01X154377Y215009D02*
X154630Y214640D01*
G01X141605Y231368D02*
X141351Y231737D01*
G01X124187Y202321D02*
X124351Y202153D01*
G01X124023Y201902D02*
X123941Y201986D01*
G01X122875Y202321D02*
X123121Y202070D01*
G01X122711Y201902D02*
X122629Y201986D01*
G01X120496Y202321D02*
X120660Y202153D01*
G01X120332Y201902D02*
X120250Y201986D01*
G01X119184Y202321D02*
X119430Y202070D01*
G01X119020Y201902D02*
X118938Y201986D01*
G01X116641Y203410D02*
X116969Y203075D01*
G01X141340Y230760D02*
X141559Y230441D01*
G01X150710Y215617D02*
X150490Y215937D01*
G01X150444Y215009D02*
X150698Y214640D01*
G01X137673Y231368D02*
X137419Y231737D01*
G01X137627Y230441D02*
X137406Y230762D01*
G01X146548Y215937D02*
X146770Y215615D01*
G01X146503Y215009D02*
X146756Y214640D01*
G01X133731Y231368D02*
X133477Y231737D01*
G01X133466Y230760D02*
X133685Y230441D01*
G01X142836Y215617D02*
X142616Y215937D01*
G01X142570Y215009D02*
X142824Y214640D01*
G01X129799Y231368D02*
X129545Y231737D01*
G01X129753Y230441D02*
X129532Y230762D01*
G01X138674Y215937D02*
X138896Y215615D01*
G01X138629Y215009D02*
X138882Y214640D01*
G01X125857Y231368D02*
X125603Y231737D01*
G01X125592Y230760D02*
X125811Y230441D01*
G01X134962Y215617D02*
X134742Y215937D01*
G01X134696Y215009D02*
X134950Y214640D01*
G01X121925Y231368D02*
X121671Y231737D01*
G01X121879Y230441D02*
X121658Y230762D01*
G01X130800Y215937D02*
X131022Y215615D01*
G01X130755Y215009D02*
X131008Y214640D01*
G01X127088Y215617D02*
X126868Y215937D01*
G01X126822Y215009D02*
X127076Y214640D01*
G01X122926Y215937D02*
X123147Y215615D01*
G01X114673Y200478D02*
X114837Y200310D01*
G01X184871Y230441D02*
X184881Y230393D01*
G01X185918Y215937D02*
X185909Y215984D01*
G01X180939Y230393D02*
X180929Y230441D01*
G01X181976Y215984D02*
X181986Y215937D01*
G01X176997Y230441D02*
X177007Y230393D01*
G01X116641Y202740D02*
X116477Y202991D01*
G01X116887Y201567D02*
X117051Y201316D01*
G01X114427Y200143D02*
X114263Y200394D01*
G01X111802Y201567D02*
X111966Y201316D01*
G01X108685Y202572D02*
X108849Y202321D01*
G01X115001Y229685D02*
X116958Y226732D01*
G01X122881Y215009D02*
X123134Y214640D01*
G01X112294Y201567D02*
X112048Y201902D01*
G01X109670Y200394D02*
X109916Y200059D01*
G01X178044Y215937D02*
X178035Y215984D01*
G01X173065Y230393D02*
X173055Y230441D01*
G01X174102Y215984D02*
X174112Y215937D01*
G01X161249Y230441D02*
X161259Y230393D01*
G01X162296Y215937D02*
X162287Y215984D01*
G01X157317Y230393D02*
X157307Y230441D01*
G01X158354Y215984D02*
X158364Y215937D01*
G01X153375Y230441D02*
X153385Y230393D01*
G01X154422Y215937D02*
X154413Y215984D01*
G01X124105Y201734D02*
X124023Y201902D01*
G01X122793Y201734D02*
X122711Y201902D01*
G01X120414Y201734D02*
X120332Y201902D01*
G01X119102Y201734D02*
X119020Y201902D01*
G01X116723Y200981D02*
X116559Y201316D01*
G01X114591Y200646D02*
X114673Y200478D01*
G01X185886Y215984D02*
X185873Y215009D01*
G01X186777Y232539D02*
Y231555D01*
G01X186773Y214822D02*
Y213838D01*
G01X186768Y214822D02*
Y213838D01*
G01X186576Y215984D02*
Y209901D01*
G01Y236476D02*
Y230393D01*
G01X186497Y213838D02*
Y232539D01*
G01X186423Y232538D02*
Y231553D01*
G01X186414Y214824D02*
Y213840D01*
G01X186221Y227698D02*
Y232539D01*
G01Y213838D02*
Y218680D01*
G01X186147Y230760D02*
Y231750D01*
G01X186138Y214627D02*
Y215617D01*
G01X186064Y218760D02*
Y217696D01*
G01Y228681D02*
Y227618D01*
G01X185788D02*
Y228602D01*
G01Y218760D02*
Y217775D01*
G01X185001Y227618D02*
Y228602D01*
G01Y218760D02*
Y217775D01*
G01X184725Y218760D02*
Y217696D01*
G01Y228681D02*
Y227618D01*
G01X184651Y231750D02*
Y230760D01*
G01X184642Y215617D02*
Y214627D01*
G01X184607Y208523D02*
Y203011D01*
G01X184568Y227698D02*
Y232539D01*
G01Y213838D02*
Y218680D01*
G01X184376Y231553D02*
Y232538D01*
G01X184366Y213840D02*
Y214824D01*
G01X184292Y232539D02*
Y213838D01*
G01X184214Y215984D02*
Y209901D01*
G01Y236476D02*
Y230393D01*
G01X184021Y232539D02*
Y231555D01*
G01X184017Y232539D02*
Y231555D01*
G01X184012Y214822D02*
Y213838D01*
G01X183977Y216515D02*
Y212342D01*
G01Y234035D02*
Y229862D01*
G01X185882Y231368D02*
X185895Y230393D01*
G01X184907Y215009D02*
X184894Y215984D01*
G01X181940Y231368D02*
X181953Y230393D01*
G01X186400Y215117D02*
X186264Y221024D01*
G01X186259Y220138D02*
X186396Y214231D01*
G01X184530Y226239D02*
X184394Y232147D01*
G01X184389Y231260D02*
X184525Y225353D01*
G01X182468Y215117D02*
X182332Y221024D01*
G01X182327Y220138D02*
X182463Y214231D01*
G01X180588Y226239D02*
X180452Y232147D01*
G01X180447Y231260D02*
X180583Y225353D01*
G01X186247Y226012D02*
X186197Y226999D01*
G01X186195Y226037D02*
X186245Y225050D01*
G01X184595Y220340D02*
X184544Y221327D01*
G01X184542Y220365D02*
X184592Y219379D01*
G01X182306Y226012D02*
X182255Y226999D01*
G01X182253Y226037D02*
X182303Y225050D01*
G01X180662Y220340D02*
X180612Y221327D01*
G01X180610Y220365D02*
X180660Y219379D01*
G01X178373Y226012D02*
X178323Y226999D01*
G01X178321Y226037D02*
X178371Y225050D01*
G01X176721Y220340D02*
X176670Y221327D01*
G01X176668Y220365D02*
X176718Y219379D01*
G01X149443Y230393D02*
X149433Y230441D01*
G01X150480Y215984D02*
X150490Y215937D01*
G01X145501Y230441D02*
X145511Y230393D01*
G01X146548Y215937D02*
X146539Y215984D01*
G01X141569Y230393D02*
X141559Y230441D01*
G01X142606Y215984D02*
X142616Y215937D01*
G01X137627Y230441D02*
X137637Y230393D01*
G01X138674Y215937D02*
X138665Y215984D01*
G01X133695Y230393D02*
X133685Y230441D01*
G01X134732Y215984D02*
X134742Y215937D01*
G01X129753Y230441D02*
X129763Y230393D01*
G01X130800Y215937D02*
X130791Y215984D01*
G01X112232Y242854D02*
X112970Y240592D01*
G01X113380Y239252D02*
X113052Y240257D01*
G01X114263Y200394D02*
X114181Y200646D01*
G01X112560Y243189D02*
X113872Y239252D01*
G01X124351Y202153D02*
X124515Y201734D01*
G01X120660Y202153D02*
X120824Y201734D01*
G01X112458Y201148D02*
X112294Y201567D01*
G01X110162Y200394D02*
X109998Y200729D01*
G01X109506D02*
X109670Y200394D01*
G01X184871Y215984D02*
X184862Y215937D01*
G01X185918Y230393D02*
X185928Y230441D01*
G01X186188Y219379D02*
X186238Y220365D01*
G01X186236Y221327D02*
X186185Y220340D01*
G01X184554Y225050D02*
X184604Y226037D01*
G01X184602Y226999D02*
X184551Y226012D01*
G01X182255Y219379D02*
X182306Y220365D01*
G01X182303Y221327D02*
X182253Y220340D01*
G01X180612Y225050D02*
X180662Y226037D01*
G01X180660Y226999D02*
X180610Y226012D01*
G01X178314Y219379D02*
X178364Y220365D01*
G01X178362Y221327D02*
X178311Y220340D01*
G01X176680Y225050D02*
X176730Y226037D01*
G01X176728Y226999D02*
X176677Y226012D01*
G01X174381Y219379D02*
X174432Y220365D01*
G01X174429Y221327D02*
X174379Y220340D01*
G01X172738Y225050D02*
X172788Y226037D01*
G01X172786Y226999D02*
X172736Y226012D01*
G01X186274Y225353D02*
X186410Y231260D01*
G01X186405Y232147D02*
X186269Y226239D01*
G01X184384Y214231D02*
X184521Y220138D01*
G01X184516Y221024D02*
X184380Y215117D01*
G01X182332Y225353D02*
X182468Y231260D01*
G01X182463Y232147D02*
X182327Y226239D01*
G01X180452Y214231D02*
X180588Y220138D01*
G01X180583Y221024D02*
X180447Y215117D01*
G01X178399Y225353D02*
X178536Y231260D01*
G01X178531Y232147D02*
X178395Y226239D01*
G01X176510Y214231D02*
X176647Y220138D01*
G01X176642Y221024D02*
X176506Y215117D01*
G01X174458Y225353D02*
X174594Y231260D01*
G01X174589Y232147D02*
X174453Y226239D01*
G01X172578Y214231D02*
X172714Y220138D01*
G01X172709Y221024D02*
X172573Y215117D01*
G01X162651Y225353D02*
X162788Y231260D01*
G01X162783Y232147D02*
X162647Y226239D01*
G01X184904Y230393D02*
X184917Y231368D01*
G01X181953Y215984D02*
X181940Y215009D01*
G01X180962Y230393D02*
X180975Y231368D01*
G01X178012Y215984D02*
X177999Y215009D01*
G01X177030Y230393D02*
X177043Y231368D01*
G01X174079Y215984D02*
X174066Y215009D01*
G01X173088Y230393D02*
X173101Y231368D01*
G01X162264Y215984D02*
X162251Y215009D01*
G01X161281Y230393D02*
X161295Y231368D01*
G01X182875Y229862D02*
Y234035D01*
G01Y212342D02*
Y216515D01*
G01X182840Y214822D02*
Y213838D01*
G01X182836Y214822D02*
Y213838D01*
G01Y232539D02*
Y231555D01*
G01X182639Y215984D02*
Y209901D01*
G01Y236476D02*
Y230393D01*
G01X182560Y213838D02*
Y232539D01*
G01X182481Y214824D02*
Y213840D01*
G01Y232538D02*
Y231553D01*
G01X182284Y231555D02*
Y236396D01*
G01Y209981D02*
Y214822D01*
G01X182206Y230760D02*
Y231750D01*
G01Y214627D02*
Y215617D01*
G01X182127Y210965D02*
Y209901D01*
G01Y236476D02*
Y235412D01*
G01X181851Y209901D02*
Y210885D01*
G01Y236476D02*
Y235492D01*
G01X181458Y208523D02*
Y203011D01*
G01X181064Y210885D02*
Y209901D01*
G01Y236476D02*
Y235492D01*
G01X180788Y210965D02*
Y209901D01*
G01Y236476D02*
Y235412D01*
G01X180710Y215617D02*
Y214627D01*
G01Y231750D02*
Y230760D01*
G01X180631Y231555D02*
Y236396D01*
G01Y209981D02*
Y214822D01*
G01X180434Y213840D02*
Y214824D01*
G01Y231553D02*
Y232538D01*
G01X180355Y232539D02*
Y213838D01*
G01X180277Y215984D02*
Y209901D01*
G01Y236476D02*
Y230393D01*
G01X180080Y214822D02*
Y213838D01*
G01Y232539D02*
Y231555D01*
G01X180075Y232539D02*
Y231555D01*
G01X180040Y216515D02*
Y212342D01*
G01Y234035D02*
Y229862D01*
G01X178938D02*
Y234035D01*
G01Y212342D02*
Y216515D01*
G01X178903Y232539D02*
Y231555D01*
G01X178899Y214822D02*
Y213838D01*
G01X178894Y214822D02*
Y213838D01*
G01X178702Y215984D02*
Y209901D01*
G01Y236476D02*
Y230393D01*
G01X178623Y213838D02*
Y232539D01*
G01X178549Y232538D02*
Y231553D01*
G01X178540Y214824D02*
Y213840D01*
G01X178347Y227698D02*
Y232539D01*
G01Y213838D02*
Y218680D01*
G01X178273Y230760D02*
Y231750D01*
G01X178264Y214627D02*
Y215617D01*
G01X178190Y218760D02*
Y217696D01*
G01Y228681D02*
Y227618D01*
G01X177914D02*
Y228602D01*
G01Y218760D02*
Y217775D01*
G01X177521Y208523D02*
Y203011D01*
G01X177127Y227618D02*
Y228602D01*
G01Y218760D02*
Y217775D01*
G01X176851Y218760D02*
Y217696D01*
G01Y228681D02*
Y227618D01*
G01X176777Y231750D02*
Y230760D01*
G01X176768Y215617D02*
Y214627D01*
G01X176694Y227698D02*
Y232539D01*
G01Y213838D02*
Y218680D01*
G01X176502Y231553D02*
Y232538D01*
G01X176492Y213840D02*
Y214824D01*
G01X176418Y232539D02*
Y213838D01*
G01X176340Y215984D02*
Y209901D01*
G01Y236476D02*
Y230393D01*
G01X176147Y232539D02*
Y231555D01*
G01X176143Y232539D02*
Y231555D01*
G01X176138Y214822D02*
Y213838D01*
G01X176103Y216515D02*
Y212342D01*
G01Y234035D02*
Y229862D01*
G01X175001D02*
Y234035D01*
G01Y212342D02*
Y216515D01*
G01X174966Y214822D02*
Y213838D01*
G01X174962Y214822D02*
Y213838D01*
G01Y232539D02*
Y231555D01*
G01X174765Y215984D02*
Y209901D01*
G01Y236476D02*
Y230393D01*
G01X174686Y213838D02*
Y232539D01*
G01X174607Y214824D02*
Y213840D01*
G01Y232538D02*
Y231553D01*
G01X174410Y231555D02*
Y236396D01*
G01Y209981D02*
Y214822D01*
G01X174371Y208523D02*
Y203011D01*
G01X174332Y230760D02*
Y231750D01*
G01Y214627D02*
Y215617D01*
G01X174253Y210965D02*
Y209901D01*
G01Y236476D02*
Y235412D01*
G01X173977Y209901D02*
Y210885D01*
G01Y236476D02*
Y235492D01*
G01X173190Y210885D02*
Y209901D01*
G01Y236476D02*
Y235492D01*
G01X172914Y210965D02*
Y209901D01*
G01Y236476D02*
Y235412D01*
G01X172836Y215617D02*
Y214627D01*
G01Y231750D02*
Y230760D01*
G01X172757Y231555D02*
Y236396D01*
G01Y209981D02*
Y214822D01*
G01X172560Y231553D02*
Y232538D01*
G01Y213840D02*
Y214824D01*
G01X172481Y232539D02*
Y213838D01*
G01X172403Y215984D02*
Y209901D01*
G01Y236476D02*
Y230393D01*
G01X172206Y214822D02*
Y213838D01*
G01Y232539D02*
Y231555D01*
G01X172201Y232539D02*
Y231555D01*
G01X172166Y216515D02*
Y212342D01*
G01Y234035D02*
Y229862D01*
G01X171123Y220064D02*
Y226314D01*
G01X171084Y226732D02*
Y219645D01*
G01X170728Y226732D02*
Y219645D01*
G01X170178Y230767D02*
Y235492D01*
G01Y210885D02*
Y215610D01*
G01X170021Y220595D02*
Y225782D01*
G01X168936Y217402D02*
Y228975D01*
G01X166421D02*
Y217402D01*
G01X165178Y215610D02*
Y210885D01*
G01Y235492D02*
Y230767D01*
G01X164629Y219645D02*
Y226732D01*
G01X164273D02*
Y219645D01*
G01X163190Y229862D02*
Y234035D01*
G01Y212342D02*
Y216515D01*
G01X163155Y232539D02*
Y231555D01*
G01X163151Y214822D02*
Y213838D01*
G01X163146Y214822D02*
Y213838D01*
G01X162954Y215984D02*
Y209901D01*
G01Y236476D02*
Y230393D01*
G01X162875Y213838D02*
Y232539D01*
G01X162801Y232538D02*
Y231553D01*
G01X162792Y214824D02*
Y213840D01*
G01X162599Y227698D02*
Y232539D01*
G01Y213838D02*
Y218680D01*
G01X162525Y230760D02*
Y231750D01*
G01X162516Y214627D02*
Y215617D01*
G01X162442Y218760D02*
Y217696D01*
G01Y228681D02*
Y227618D01*
G01X162166D02*
Y228602D01*
G01Y218760D02*
Y217775D01*
G01X161379Y218760D02*
Y217775D01*
G01Y228602D02*
Y227618D01*
G01X161103Y218760D02*
Y217696D01*
G01Y228681D02*
Y227618D01*
G01X161029Y231750D02*
Y230760D01*
G01X161020Y215617D02*
Y214627D01*
G01X160985Y208523D02*
Y203011D01*
G01X160946Y227698D02*
Y232539D01*
G01Y213838D02*
Y218680D01*
G01X160754Y231553D02*
Y232538D01*
G01X160744Y213840D02*
Y214824D01*
G01X160670Y232539D02*
Y213838D01*
G01X160592Y215984D02*
Y209901D01*
G01Y236476D02*
Y230393D01*
G01X160399Y232539D02*
Y231555D01*
G01X160395Y232539D02*
Y231555D01*
G01X160390Y214822D02*
Y213838D01*
G01X160355Y216515D02*
Y212342D01*
G01Y234035D02*
Y229862D01*
G01X180975Y215009D02*
X180962Y215984D01*
G01X178008Y231368D02*
X178021Y230393D01*
G01X177033Y215009D02*
X177020Y215984D01*
G01X174066Y231368D02*
X174079Y230393D01*
G01X173101Y215009D02*
X173088Y215984D01*
G01X162260Y231368D02*
X162273Y230393D01*
G01X161285Y215009D02*
X161272Y215984D01*
G01X158318Y231368D02*
X158331Y230393D01*
G01X178526Y215117D02*
X178390Y221024D01*
G01X178385Y220138D02*
X178522Y214231D01*
G01X176656Y226239D02*
X176520Y232147D01*
G01X176515Y231260D02*
X176651Y225353D01*
G01X174594Y215117D02*
X174458Y221024D01*
G01X174453Y220138D02*
X174589Y214231D01*
G01X172714Y226239D02*
X172578Y232147D01*
G01X172573Y231260D02*
X172709Y225353D01*
G01X162778Y215117D02*
X162642Y221024D01*
G01X162637Y220138D02*
X162774Y214231D01*
G01X160908Y226239D02*
X160772Y232147D01*
G01X160767Y231260D02*
X160903Y225353D01*
G01X158846Y215117D02*
X158710Y221024D01*
G01X158705Y220138D02*
X158841Y214231D01*
G01X156966Y226239D02*
X156830Y232147D01*
G01X156825Y231260D02*
X156961Y225353D01*
G01X174432Y226012D02*
X174381Y226999D01*
G01X174379Y226037D02*
X174429Y225050D01*
G01X172788Y220340D02*
X172738Y221327D01*
G01X172736Y220365D02*
X172786Y219379D01*
G01X162625Y226012D02*
X162575Y226999D01*
G01X162573Y226037D02*
X162623Y225050D01*
G01X160973Y220340D02*
X160922Y221327D01*
G01X160920Y220365D02*
X160970Y219379D01*
G01X158684Y226012D02*
X158633Y226999D01*
G01X158631Y226037D02*
X158681Y225050D01*
G01X157040Y220340D02*
X156990Y221327D01*
G01X156988Y220365D02*
X157038Y219379D01*
G01X154751Y226012D02*
X154701Y226999D01*
G01X154699Y226037D02*
X154749Y225050D01*
G01X153099Y220340D02*
X153048Y221327D01*
G01X153046Y220365D02*
X153096Y219379D01*
G01X125821Y230393D02*
X125811Y230441D01*
G01X126858Y215984D02*
X126868Y215937D01*
G01X121879Y230441D02*
X121889Y230393D01*
G01X122926Y215937D02*
X122917Y215984D01*
G01X116969Y203075D02*
X117051Y202740D01*
G01Y201316D02*
X117134Y200981D01*
G01X111966Y201316D02*
X112048Y201064D01*
G01X123367Y202321D02*
X123613Y202405D01*
G01X122301Y202070D02*
X122055Y201986D01*
G01Y202321D02*
X122301Y202405D01*
G01X119676Y202321D02*
X119922Y202405D01*
G01X118610Y202070D02*
X118364Y201986D01*
G01Y202321D02*
X118610Y202405D01*
G01X115821Y201902D02*
X116313Y202070D01*
G01X184653Y214640D02*
X184907Y215009D01*
G01X184640Y215615D02*
X184862Y215937D01*
G01X180929D02*
X180939Y215984D01*
G01X181986Y230441D02*
X181976Y230393D01*
G01X176997Y215984D02*
X176988Y215937D01*
G01X178044Y230393D02*
X178054Y230441D01*
G01X173055Y215937D02*
X173065Y215984D01*
G01X174112Y230441D02*
X174102Y230393D01*
G01X161249Y215984D02*
X161240Y215937D01*
G01X162296Y230393D02*
X162306Y230441D01*
G01X162566Y219379D02*
X162616Y220365D01*
G01X162614Y221327D02*
X162563Y220340D01*
G01X160932Y225050D02*
X160982Y226037D01*
G01X160980Y226999D02*
X160929Y226012D01*
G01X158633Y219379D02*
X158684Y220365D01*
G01X158681Y221327D02*
X158631Y220340D01*
G01X156990Y225050D02*
X157040Y226037D01*
G01X157038Y226999D02*
X156988Y226012D01*
G01X154692Y219379D02*
X154742Y220365D01*
G01X154740Y221327D02*
X154689Y220340D01*
G01X153058Y225050D02*
X153108Y226037D01*
G01X153106Y226999D02*
X153055Y226012D01*
G01X150759Y219379D02*
X150810Y220365D01*
G01X150807Y221327D02*
X150757Y220340D01*
G01X149116Y225050D02*
X149166Y226037D01*
G01X149164Y226999D02*
X149114Y226012D01*
G01X146817Y219379D02*
X146868Y220365D01*
G01X146866Y221327D02*
X146815Y220340D01*
G01X145184Y225050D02*
X145234Y226037D01*
G01X145232Y226999D02*
X145181Y226012D01*
G01X142885Y219379D02*
X142936Y220365D01*
G01X142933Y221327D02*
X142883Y220340D01*
G01X160762Y214231D02*
X160899Y220138D01*
G01X160894Y221024D02*
X160758Y215117D01*
G01X158710Y225353D02*
X158846Y231260D01*
G01X158841Y232147D02*
X158705Y226239D01*
G01X156830Y214231D02*
X156966Y220138D01*
G01X156961Y221024D02*
X156825Y215117D01*
G01X154777Y225353D02*
X154914Y231260D01*
G01X154909Y232147D02*
X154773Y226239D01*
G01X152888Y214231D02*
X153025Y220138D01*
G01X153020Y221024D02*
X152884Y215117D01*
G01X150836Y225353D02*
X150972Y231260D01*
G01X150967Y232147D02*
X150831Y226239D01*
G01X148956Y214231D02*
X149092Y220138D01*
G01X149087Y221024D02*
X148951Y215117D01*
G01X146903Y225353D02*
X147040Y231260D01*
G01X147035Y232147D02*
X146899Y226239D01*
G01X145014Y214231D02*
X145151Y220138D01*
G01X145146Y221024D02*
X145009Y215117D01*
G01X142962Y225353D02*
X143098Y231260D01*
G01X143093Y232147D02*
X142957Y226239D01*
G01X141082Y214231D02*
X141218Y220138D01*
G01X141213Y221024D02*
X141077Y215117D01*
G01X139029Y225353D02*
X139166Y231260D01*
G01X139161Y232147D02*
X139025Y226239D01*
G01X158331Y215984D02*
X158318Y215009D01*
G01X157340Y230393D02*
X157353Y231368D01*
G01X154390Y215984D02*
X154377Y215009D01*
G01X153407Y230393D02*
X153421Y231368D01*
G01X150457Y215984D02*
X150444Y215009D01*
G01X149466Y230393D02*
X149479Y231368D01*
G01X146516Y215984D02*
X146503Y215009D01*
G01X145533Y230393D02*
X145547Y231368D01*
G01X142583Y215984D02*
X142570Y215009D01*
G01X141592Y230393D02*
X141605Y231368D01*
G01X138642Y215984D02*
X138629Y215009D01*
G01X137659Y230393D02*
X137673Y231368D01*
G01X159253Y229862D02*
Y234035D01*
G01Y212342D02*
Y216515D01*
G01X159218Y214822D02*
Y213838D01*
G01X159214Y214822D02*
Y213838D01*
G01Y232539D02*
Y231555D01*
G01X159017Y215984D02*
Y209901D01*
G01Y236476D02*
Y230393D01*
G01X158938Y213838D02*
Y232539D01*
G01X158859Y214824D02*
Y213840D01*
G01Y232538D02*
Y231553D01*
G01X158662Y231555D02*
Y236396D01*
G01Y209981D02*
Y214822D01*
G01X158584Y230760D02*
Y231750D01*
G01Y214627D02*
Y215617D01*
G01X158505Y210965D02*
Y209901D01*
G01Y236476D02*
Y235412D01*
G01X158229Y209901D02*
Y210885D01*
G01Y236476D02*
Y235492D01*
G01X157836Y208523D02*
Y203011D01*
G01X157442Y210885D02*
Y209901D01*
G01Y236476D02*
Y235492D01*
G01X157166Y210965D02*
Y209901D01*
G01Y236476D02*
Y235412D01*
G01X157088Y215617D02*
Y214627D01*
G01Y231750D02*
Y230760D01*
G01X157009Y231555D02*
Y236396D01*
G01Y209981D02*
Y214822D01*
G01X156812Y231553D02*
Y232538D01*
G01Y213840D02*
Y214824D01*
G01X156733Y232539D02*
Y213838D01*
G01X156655Y215984D02*
Y209901D01*
G01Y236476D02*
Y230393D01*
G01X156458Y214822D02*
Y213838D01*
G01Y232539D02*
Y231555D01*
G01X156453Y232539D02*
Y231555D01*
G01X156418Y216515D02*
Y212342D01*
G01Y234035D02*
Y229862D01*
G01X155316D02*
Y234035D01*
G01Y212342D02*
Y216515D01*
G01X155281Y232539D02*
Y231555D01*
G01X155277Y214822D02*
Y213838D01*
G01X155272Y214822D02*
Y213838D01*
G01X155080Y215984D02*
Y209901D01*
G01Y236476D02*
Y230393D01*
G01X155001Y213838D02*
Y232539D01*
G01X154927Y232538D02*
Y231553D01*
G01X154918Y214824D02*
Y213840D01*
G01X154725Y227698D02*
Y232539D01*
G01Y213838D02*
Y218680D01*
G01X154651Y230760D02*
Y231750D01*
G01X154642Y214627D02*
Y215617D01*
G01X154568Y218760D02*
Y217696D01*
G01Y228681D02*
Y227618D01*
G01X154292D02*
Y228602D01*
G01Y218760D02*
Y217775D01*
G01X153899Y208523D02*
Y203011D01*
G01X153505Y218760D02*
Y217775D01*
G01Y228602D02*
Y227618D01*
G01X153229Y218760D02*
Y217696D01*
G01Y228681D02*
Y227618D01*
G01X153155Y231750D02*
Y230760D01*
G01X153146Y215617D02*
Y214627D01*
G01X153072Y227698D02*
Y232539D01*
G01Y213838D02*
Y218680D01*
G01X152880Y231553D02*
Y232538D01*
G01X152870Y213840D02*
Y214824D01*
G01X152796Y232539D02*
Y213838D01*
G01X152717Y215984D02*
Y209901D01*
G01Y236476D02*
Y230393D01*
G01X152525Y232539D02*
Y231555D01*
G01X152521Y232539D02*
Y231555D01*
G01X152516Y214822D02*
Y213838D01*
G01X152481Y216515D02*
Y212342D01*
G01Y234035D02*
Y229862D01*
G01X151379D02*
Y234035D01*
G01Y212342D02*
Y216515D01*
G01X151344Y214822D02*
Y213838D01*
G01X151340Y214822D02*
Y213838D01*
G01Y232539D02*
Y231555D01*
G01X151143Y215984D02*
Y209901D01*
G01Y236476D02*
Y230393D01*
G01X151064Y213838D02*
Y232539D01*
G01X150985Y214824D02*
Y213840D01*
G01Y232538D02*
Y231553D01*
G01X150788Y231555D02*
Y236396D01*
G01Y209981D02*
Y214822D01*
G01X150749Y208523D02*
Y203011D01*
G01X150710Y230760D02*
Y231750D01*
G01Y214627D02*
Y215617D01*
G01X150631Y210965D02*
Y209901D01*
G01Y236476D02*
Y235412D01*
G01X150355Y209901D02*
Y210885D01*
G01Y236476D02*
Y235492D01*
G01X149568Y210885D02*
Y209901D01*
G01Y236476D02*
Y235492D01*
G01X149292Y210965D02*
Y209901D01*
G01Y236476D02*
Y235412D01*
G01X149214Y215617D02*
Y214627D01*
G01Y231750D02*
Y230760D01*
G01X149135Y231555D02*
Y236396D01*
G01Y209981D02*
Y214822D01*
G01X148938Y231553D02*
Y232538D01*
G01Y213840D02*
Y214824D01*
G01X148859Y232539D02*
Y213838D01*
G01X148780Y215984D02*
Y209901D01*
G01Y236476D02*
Y230393D01*
G01X148584Y214822D02*
Y213838D01*
G01Y232539D02*
Y231555D01*
G01X148579Y232539D02*
Y231555D01*
G01X148544Y216515D02*
Y212342D01*
G01Y234035D02*
Y229862D01*
G01X147442D02*
Y234035D01*
G01Y212342D02*
Y216515D01*
G01X147407Y232539D02*
Y231555D01*
G01X147403Y214822D02*
Y213838D01*
G01X147398Y214822D02*
Y213838D01*
G01X147206Y215984D02*
Y209901D01*
G01Y236476D02*
Y230393D01*
G01X147127Y213838D02*
Y232539D01*
G01X147053Y232538D02*
Y231553D01*
G01X147044Y214824D02*
Y213840D01*
G01X146851Y227698D02*
Y232539D01*
G01Y213838D02*
Y218680D01*
G01X146777Y230760D02*
Y231750D01*
G01X146768Y214627D02*
Y215617D01*
G01X146694Y218760D02*
Y217696D01*
G01Y228681D02*
Y227618D01*
G01X146418D02*
Y228602D01*
G01Y218760D02*
Y217775D01*
G01X145631Y218760D02*
Y217775D01*
G01Y228602D02*
Y227618D01*
G01X145355Y218760D02*
Y217696D01*
G01Y228681D02*
Y227618D01*
G01X145281Y231750D02*
Y230760D01*
G01X145272Y215617D02*
Y214627D01*
G01X145198Y227698D02*
Y232539D01*
G01Y213838D02*
Y218680D01*
G01X145006Y231553D02*
Y232538D01*
G01X144996Y213840D02*
Y214824D01*
G01X144922Y232539D02*
Y213838D01*
G01X144843Y215984D02*
Y209901D01*
G01Y236476D02*
Y230393D01*
G01X144651Y232539D02*
Y231555D01*
G01X144647Y232539D02*
Y231555D01*
G01X144642Y214822D02*
Y213838D01*
G01X144607Y216515D02*
Y212342D01*
G01Y234035D02*
Y229862D01*
G01X143505D02*
Y234035D01*
G01Y212342D02*
Y216515D01*
G01X143470Y214822D02*
Y213838D01*
G01X143466Y214822D02*
Y213838D01*
G01Y232539D02*
Y231555D01*
G01X143269Y215984D02*
Y209901D01*
G01Y236476D02*
Y230393D01*
G01X143190Y213838D02*
Y232539D01*
G01X143111Y214824D02*
Y213840D01*
G01Y232538D02*
Y231553D01*
G01X142914Y231555D02*
Y236396D01*
G01Y209981D02*
Y214822D01*
G01X142836Y230760D02*
Y231750D01*
G01Y214627D02*
Y215617D01*
G01X142757Y210965D02*
Y209901D01*
G01Y236476D02*
Y235412D01*
G01X142481Y209901D02*
Y210885D01*
G01Y236476D02*
Y235492D01*
G01X141694Y210885D02*
Y209901D01*
G01Y236476D02*
Y235492D01*
G01X141418Y210965D02*
Y209901D01*
G01Y236476D02*
Y235412D01*
G01X141340Y215617D02*
Y214627D01*
G01Y231750D02*
Y230760D01*
G01X141261Y231555D02*
Y236396D01*
G01Y209981D02*
Y214822D01*
G01X141064Y213840D02*
Y214824D01*
G01Y231553D02*
Y232538D01*
G01X140985Y232539D02*
Y213838D01*
G01X140906Y215984D02*
Y209901D01*
G01Y236476D02*
Y230393D01*
G01X140710Y214822D02*
Y213838D01*
G01Y232539D02*
Y231555D01*
G01X140705Y232539D02*
Y231555D01*
G01X140670Y216515D02*
Y212342D01*
G01Y234035D02*
Y229862D01*
G01X139568D02*
Y234035D01*
G01Y212342D02*
Y216515D01*
G01X139533Y232539D02*
Y231555D01*
G01X139529Y214822D02*
Y213838D01*
G01X139524Y214822D02*
Y213838D01*
G01X139332Y215984D02*
Y209901D01*
G01Y236476D02*
Y230393D01*
G01X139253Y213838D02*
Y232539D01*
G01X139179Y232538D02*
Y231553D01*
G01X139170Y214824D02*
Y213840D01*
G01X138977Y227698D02*
Y232539D01*
G01Y213838D02*
Y218680D01*
G01X138903Y230760D02*
Y231750D01*
G01X138894Y214627D02*
Y215617D01*
G01X138820Y218760D02*
Y217696D01*
G01Y228681D02*
Y227618D01*
G01X138544D02*
Y228602D01*
G01Y218760D02*
Y217775D01*
G01X137757Y227618D02*
Y228602D01*
G01Y218760D02*
Y217775D01*
G01X137481Y218760D02*
Y217696D01*
G01Y228681D02*
Y227618D01*
G01X137407Y231750D02*
Y230760D01*
G01X137398Y215617D02*
Y214627D01*
G01X137363Y208523D02*
Y203011D01*
G01X137324Y227698D02*
Y232539D01*
G01Y213838D02*
Y218680D01*
G01X137132Y231553D02*
Y232538D01*
G01X137122Y213840D02*
Y214824D01*
G01X137048Y232539D02*
Y213838D01*
G01X136969Y215984D02*
Y209901D01*
G01Y236476D02*
Y230393D01*
G01X136777Y232539D02*
Y231555D01*
G01X136773Y232539D02*
Y231555D01*
G01X136768Y214822D02*
Y213838D01*
G01X136733Y216515D02*
Y212342D01*
G01Y234035D02*
Y229862D01*
G01X135631D02*
Y234035D01*
G01Y212342D02*
Y216515D01*
G01X135596Y214822D02*
Y213838D01*
G01X135592Y214822D02*
Y213838D01*
G01Y232539D02*
Y231555D01*
G01X135395Y215984D02*
Y209901D01*
G01Y236476D02*
Y230393D01*
G01X135316Y213838D02*
Y232539D01*
G01X135237Y214824D02*
Y213840D01*
G01Y232538D02*
Y231553D01*
G01X135040Y231555D02*
Y236396D01*
G01Y209981D02*
Y214822D01*
G01X134962Y230760D02*
Y231750D01*
G01Y214627D02*
Y215617D01*
G01X134883Y210965D02*
Y209901D01*
G01Y236476D02*
Y235412D01*
G01X157353Y215009D02*
X157340Y215984D01*
G01X154386Y231368D02*
X154399Y230393D01*
G01X153411Y215009D02*
X153398Y215984D01*
G01X150444Y231368D02*
X150457Y230393D01*
G01X149479Y215009D02*
X149466Y215984D01*
G01X146512Y231368D02*
X146525Y230393D01*
G01X145537Y215009D02*
X145524Y215984D01*
G01X142570Y231368D02*
X142583Y230393D01*
G01X141605Y215009D02*
X141592Y215984D01*
G01X138638Y231368D02*
X138651Y230393D01*
G01X137663Y215009D02*
X137650Y215984D01*
G01X134696Y231368D02*
X134709Y230393D01*
G01X133731Y215009D02*
X133718Y215984D01*
G01X154904Y215117D02*
X154768Y221024D01*
G01X154763Y220138D02*
X154900Y214231D01*
G01X153034Y226239D02*
X152898Y232147D01*
G01X152893Y231260D02*
X153029Y225353D01*
G01X150972Y215117D02*
X150836Y221024D01*
G01X150831Y220138D02*
X150967Y214231D01*
G01X149092Y226239D02*
X148956Y232147D01*
G01X148951Y231260D02*
X149087Y225353D01*
G01X147030Y215117D02*
X146894Y221024D01*
G01X146889Y220138D02*
X147026Y214231D01*
G01X145160Y226239D02*
X145024Y232147D01*
G01X145019Y231260D02*
X145155Y225353D01*
G01X143098Y215117D02*
X142962Y221024D01*
G01X142957Y220138D02*
X143093Y214231D01*
G01X141218Y226239D02*
X141082Y232147D01*
G01X141077Y231260D02*
X141213Y225353D01*
G01X139156Y215117D02*
X139020Y221024D01*
G01X139015Y220138D02*
X139152Y214231D01*
G01X137286Y226239D02*
X137150Y232147D01*
G01X137145Y231260D02*
X137281Y225353D01*
G01X135224Y215117D02*
X135088Y221024D01*
G01X135083Y220138D02*
X135219Y214231D01*
G01X133344Y226239D02*
X133208Y232147D01*
G01X133203Y231260D02*
X133339Y225353D01*
G01X150810Y226012D02*
X150759Y226999D01*
G01X150757Y226037D02*
X150807Y225050D01*
G01X149166Y220340D02*
X149116Y221327D01*
G01X149114Y220365D02*
X149164Y219379D01*
G01X146877Y226012D02*
X146827Y226999D01*
G01X146825Y226037D02*
X146875Y225050D01*
G01X145225Y220340D02*
X145174Y221327D01*
G01X145172Y220365D02*
X145222Y219379D01*
G01X142936Y226012D02*
X142885Y226999D01*
G01X142883Y226037D02*
X142933Y225050D01*
G01X141292Y220340D02*
X141242Y221327D01*
G01X141239Y220365D02*
X141290Y219379D01*
G01X139003Y226012D02*
X138953Y226999D01*
G01X138950Y226037D02*
X139001Y225050D01*
G01X137351Y220340D02*
X137300Y221327D01*
G01X137298Y220365D02*
X137348Y219379D01*
G01X135062Y226012D02*
X135011Y226999D01*
G01X135009Y226037D02*
X135059Y225050D01*
G01X133418Y220340D02*
X133368Y221327D01*
G01X133365Y220365D02*
X133416Y219379D01*
G01X131129Y226012D02*
X131079Y226999D01*
G01X131076Y226037D02*
X131127Y225050D01*
G01X129477Y220340D02*
X129426Y221327D01*
G01X129424Y220365D02*
X129474Y219379D01*
G01X123531Y202070D02*
X123367Y201986D01*
G01X116641Y199975D02*
X116313Y199808D01*
G01Y200227D02*
X116477Y200310D01*
G01X119840Y202070D02*
X119676Y201986D01*
G01X114673Y203410D02*
X115001Y203577D01*
G01X108849Y202321D02*
X107701Y201734D01*
G01X107127D02*
X108685Y202572D01*
G01X111638Y199808D02*
X112048Y200059D01*
G01X110326Y202153D02*
X109916Y201902D01*
G01X116887Y200143D02*
X116641Y199975D01*
G01X111802Y200394D02*
X111556Y200227D01*
G01X180721Y214640D02*
X180975Y215009D01*
G01X180929Y215937D02*
X180710Y215617D01*
G01X176779Y214640D02*
X177033Y215009D01*
G01X176766Y215615D02*
X176988Y215937D01*
G01X186149Y230762D02*
X185928Y230441D01*
G01X186136Y231737D02*
X185882Y231368D01*
G01X172847Y214640D02*
X173101Y215009D01*
G01X173055Y215937D02*
X172836Y215617D01*
G01X181986Y230441D02*
X182206Y230760D01*
G01X182194Y231737D02*
X181940Y231368D01*
G01X178275Y230762D02*
X178054Y230441D01*
G01X178262Y231737D02*
X178008Y231368D01*
G01X174112Y230441D02*
X174332Y230760D01*
G01X174320Y231737D02*
X174066Y231368D01*
G01X161031Y214640D02*
X161285Y215009D01*
G01X161018Y215615D02*
X161240Y215937D01*
G01X157099Y214640D02*
X157353Y215009D01*
G01X157307Y215937D02*
X157088Y215617D01*
G01X168936Y217402D02*
X170423Y219645D01*
G01X166421Y228975D02*
X164933Y226732D01*
G01X157307Y215937D02*
X157317Y215984D01*
G01X158364Y230441D02*
X158354Y230393D01*
G01X153375Y215984D02*
X153366Y215937D01*
G01X154422Y230393D02*
X154432Y230441D01*
G01X149433Y215937D02*
X149443Y215984D01*
G01X150490Y230441D02*
X150480Y230393D01*
G01X145501Y215984D02*
X145492Y215937D01*
G01X146548Y230393D02*
X146558Y230441D01*
G01X141559Y215937D02*
X141569Y215984D01*
G01X142616Y230441D02*
X142606Y230393D01*
G01X137627Y215984D02*
X137618Y215937D01*
G01X138674Y230393D02*
X138684Y230441D01*
G01X133685Y215937D02*
X133695Y215984D01*
G01X141242Y225050D02*
X141292Y226037D01*
G01X141290Y226999D02*
X141239Y226012D01*
G01X138943Y219379D02*
X138994Y220365D01*
G01X138992Y221327D02*
X138941Y220340D01*
G01X137309Y225050D02*
X137360Y226037D01*
G01X137358Y226999D02*
X137307Y226012D01*
G01X135011Y219379D02*
X135062Y220365D01*
G01X135059Y221327D02*
X135009Y220340D01*
G01X133368Y225050D02*
X133418Y226037D01*
G01X133416Y226999D02*
X133365Y226012D01*
G01X131069Y219379D02*
X131120Y220365D01*
G01X131118Y221327D02*
X131067Y220340D01*
G01X129435Y225050D02*
X129486Y226037D01*
G01X129484Y226999D02*
X129433Y226012D01*
G01X127137Y219379D02*
X127188Y220365D01*
G01X127185Y221327D02*
X127135Y220340D01*
G01X125494Y225050D02*
X125544Y226037D01*
G01X125542Y226999D02*
X125491Y226012D01*
G01X123195Y219379D02*
X123246Y220365D01*
G01X123244Y221327D02*
X123193Y220340D01*
G01X121561Y225050D02*
X121612Y226037D01*
G01X121610Y226999D02*
X121559Y226012D01*
G01X137140Y214231D02*
X137276Y220138D01*
G01X137272Y221024D02*
X137135Y215117D01*
G01X135088Y225353D02*
X135224Y231260D01*
G01X135219Y232147D02*
X135083Y226239D01*
G01X133208Y214231D02*
X133344Y220138D01*
G01X133339Y221024D02*
X133203Y215117D01*
G01X131155Y225353D02*
X131292Y231260D01*
G01X131287Y232147D02*
X131151Y226239D01*
G01X129266Y214231D02*
X129402Y220138D01*
G01X129398Y221024D02*
X129261Y215117D01*
G01X127214Y225353D02*
X127350Y231260D01*
G01X127345Y232147D02*
X127209Y226239D01*
G01X125334Y214231D02*
X125470Y220138D01*
G01X125465Y221024D02*
X125329Y215117D01*
G01X123281Y225353D02*
X123418Y231260D01*
G01X123413Y232147D02*
X123277Y226239D01*
G01X121392Y214231D02*
X121528Y220138D01*
G01X121524Y221024D02*
X121387Y215117D01*
G01X134709Y215984D02*
X134696Y215009D01*
G01X133718Y230393D02*
X133731Y231368D01*
G01X130768Y215984D02*
X130755Y215009D01*
G01X129785Y230393D02*
X129799Y231368D01*
G01X126835Y215984D02*
X126822Y215009D01*
G01X125844Y230393D02*
X125857Y231368D01*
G01X122894Y215984D02*
X122881Y215009D01*
G01X121911Y230393D02*
X121925Y231368D01*
G01X134607Y209901D02*
Y210885D01*
G01Y236476D02*
Y235492D01*
G01X134214Y208523D02*
Y203011D01*
G01X133820Y210885D02*
Y209901D01*
G01Y236476D02*
Y235492D01*
G01X133544Y210965D02*
Y209901D01*
G01Y236476D02*
Y235412D01*
G01X133466Y215617D02*
Y214627D01*
G01Y231750D02*
Y230760D01*
G01X133387Y231555D02*
Y236396D01*
G01Y209981D02*
Y214822D01*
G01X133190Y231553D02*
Y232538D01*
G01Y213840D02*
Y214824D01*
G01X133111Y232539D02*
Y213838D01*
G01X133032Y215984D02*
Y209901D01*
G01Y236476D02*
Y230393D01*
G01X132836Y214822D02*
Y213838D01*
G01Y232539D02*
Y231555D01*
G01X132831Y232539D02*
Y231555D01*
G01X132796Y216515D02*
Y212342D01*
G01Y234035D02*
Y229862D01*
G01X131694D02*
Y234035D01*
G01Y212342D02*
Y216515D01*
G01X131659Y232539D02*
Y231555D01*
G01X131655Y214822D02*
Y213838D01*
G01X131650Y214822D02*
Y213838D01*
G01X131458Y215984D02*
Y209901D01*
G01Y236476D02*
Y230393D01*
G01X131379Y213838D02*
Y232539D01*
G01X131305Y232538D02*
Y231553D01*
G01X131296Y214824D02*
Y213840D01*
G01X131103Y227698D02*
Y232539D01*
G01Y213838D02*
Y218680D01*
G01X131029Y230760D02*
Y231750D01*
G01X131020Y214627D02*
Y215617D01*
G01X130946Y218760D02*
Y217696D01*
G01Y228681D02*
Y227618D01*
G01X130670D02*
Y228602D01*
G01Y218760D02*
Y217775D01*
G01X130277Y208523D02*
Y203011D01*
G01X129883Y227618D02*
Y228602D01*
G01Y218760D02*
Y217775D01*
G01X129607Y218760D02*
Y217696D01*
G01Y228681D02*
Y227618D01*
G01X129533Y231750D02*
Y230760D01*
G01X129524Y215617D02*
Y214627D01*
G01X129450Y227698D02*
Y232539D01*
G01Y213838D02*
Y218680D01*
G01X129258Y231553D02*
Y232538D01*
G01X129248Y213840D02*
Y214824D01*
G01X129174Y232539D02*
Y213838D01*
G01X129095Y215984D02*
Y209901D01*
G01Y236476D02*
Y230393D01*
G01X128903Y232539D02*
Y231555D01*
G01X128899Y232539D02*
Y231555D01*
G01X128894Y214822D02*
Y213838D01*
G01X128859Y216515D02*
Y212342D01*
G01Y234035D02*
Y229862D01*
G01X127757D02*
Y234035D01*
G01Y212342D02*
Y216515D01*
G01X127722Y214822D02*
Y213838D01*
G01X127717Y214822D02*
Y213838D01*
G01Y232539D02*
Y231555D01*
G01X127521Y215984D02*
Y209901D01*
G01Y236476D02*
Y230393D01*
G01X127442Y213838D02*
Y232539D01*
G01X127363Y214824D02*
Y213840D01*
G01Y232538D02*
Y231553D01*
G01X127166Y231555D02*
Y236396D01*
G01Y209981D02*
Y214822D01*
G01X127127Y208523D02*
Y203011D01*
G01X127088Y230760D02*
Y231750D01*
G01Y214627D02*
Y215617D01*
G01X127009Y210965D02*
Y209901D01*
G01Y236476D02*
Y235412D01*
G01X126733Y209901D02*
Y210885D01*
G01Y236476D02*
Y235492D01*
G01X125946Y210885D02*
Y209901D01*
G01Y236476D02*
Y235492D01*
G01X125670Y210965D02*
Y209901D01*
G01Y236476D02*
Y235412D01*
G01X125592Y215617D02*
Y214627D01*
G01Y231750D02*
Y230760D01*
G01X125513Y231555D02*
Y236396D01*
G01Y209981D02*
Y214822D01*
G01X125316Y231553D02*
Y232538D01*
G01Y213840D02*
Y214824D01*
G01X125237Y232539D02*
Y213838D01*
G01X125158Y215984D02*
Y209901D01*
G01Y236476D02*
Y230393D01*
G01X124962Y214822D02*
Y213838D01*
G01Y232539D02*
Y231555D01*
G01X124957Y232539D02*
Y231555D01*
G01X124922Y216515D02*
Y212342D01*
G01Y234035D02*
Y229862D01*
G01X124515Y201734D02*
Y199724D01*
G01X124105D02*
Y201734D01*
G01X123820Y229862D02*
Y234035D01*
G01Y212342D02*
Y216515D01*
G01X123785Y232539D02*
Y231555D01*
G01X123780Y214822D02*
Y213838D01*
G01X123776Y214822D02*
Y213838D01*
G01X123584Y215984D02*
Y209901D01*
G01Y236476D02*
Y230393D01*
G01X123505Y213838D02*
Y232539D01*
G01X123431Y232538D02*
Y231553D01*
G01X123421Y214824D02*
Y213840D01*
G01X123229Y227698D02*
Y232539D01*
G01Y213838D02*
Y218680D01*
G01X123203Y201734D02*
Y199724D01*
G01X123155Y230760D02*
Y231750D01*
G01X123146Y214627D02*
Y215617D01*
G01X123072Y218760D02*
Y217696D01*
G01Y228681D02*
Y227618D01*
G01X122796D02*
Y228602D01*
G01Y218760D02*
Y217775D01*
G01X122793Y199724D02*
Y201734D01*
G01X122009Y218760D02*
Y217775D01*
G01Y228602D02*
Y227618D01*
G01X121891Y201818D02*
Y199724D01*
G01Y202405D02*
Y202153D01*
G01X121733Y218760D02*
Y217696D01*
G01Y228681D02*
Y227618D01*
G01X121659Y231750D02*
Y230760D01*
G01X121650Y215617D02*
Y214627D01*
G01X121576Y227698D02*
Y232539D01*
G01Y213838D02*
Y218680D01*
G01X121481Y199724D02*
Y202405D01*
G01X121384Y231553D02*
Y232538D01*
G01X121374Y213840D02*
Y214824D01*
G01X121300Y232539D02*
Y213838D01*
G01X121221Y215984D02*
Y209901D01*
G01Y236476D02*
Y230393D01*
G01X121029Y232539D02*
Y231555D01*
G01X121025Y232539D02*
Y231555D01*
G01X121020Y214822D02*
Y213838D01*
G01X120985Y216515D02*
Y212342D01*
G01Y234035D02*
Y229862D01*
G01X120824Y201734D02*
Y199724D01*
G01X120414D02*
Y201734D01*
G01X119512D02*
Y199724D01*
G01X119102D02*
Y201734D01*
G01X118406Y226732D02*
Y219645D01*
G01X118200Y201818D02*
Y199724D01*
G01Y202405D02*
Y202153D01*
G01X117856Y237854D02*
Y234735D01*
G01X117790Y199724D02*
Y202405D01*
G01X117134Y200981D02*
Y200646D01*
G01X117051Y202740D02*
Y202572D01*
G01X116723Y200646D02*
Y200981D01*
G01X116641Y202572D02*
Y202740D01*
G01X116497Y219252D02*
Y227126D01*
G01X116241Y216988D02*
Y211082D01*
G01Y235295D02*
Y229389D01*
G01X115513Y243189D02*
Y239252D01*
G01X115493Y201567D02*
Y201902D01*
G01X115021Y239252D02*
Y242519D01*
G01X115001Y229685D02*
Y216693D01*
G01X114529Y241932D02*
Y242602D01*
G01X114270Y237854D02*
Y234735D01*
G01X113741Y208523D02*
Y203011D01*
G01X113525Y200143D02*
Y199724D01*
G01X113114D02*
Y200143D01*
G01X112560Y227126D02*
Y219252D01*
G01X112458Y200813D02*
Y201148D01*
G01X112294Y203242D02*
Y203661D01*
G01X112048Y201064D02*
Y200897D01*
G01X111517Y216988D02*
Y211082D01*
G01Y235295D02*
Y229389D01*
G01X110592Y203011D02*
Y237854D01*
G01X130764Y231368D02*
X130777Y230393D01*
G01X129789Y215009D02*
X129776Y215984D01*
G01X126822Y231368D02*
X126835Y230393D01*
G01X125857Y215009D02*
X125844Y215984D01*
G01X122890Y231368D02*
X122903Y230393D01*
G01X121915Y215009D02*
X121902Y215984D01*
G01X131282Y215117D02*
X131146Y221024D01*
G01X131141Y220138D02*
X131278Y214231D01*
G01X129412Y226239D02*
X129276Y232147D01*
G01X129271Y231260D02*
X129407Y225353D01*
G01X127350Y215117D02*
X127214Y221024D01*
G01X127209Y220138D02*
X127345Y214231D01*
G01X125470Y226239D02*
X125334Y232147D01*
G01X125329Y231260D02*
X125465Y225353D01*
G01X123408Y215117D02*
X123272Y221024D01*
G01X123267Y220138D02*
X123403Y214231D01*
G01X121538Y226239D02*
X121402Y232147D01*
G01X121397Y231260D02*
X121533Y225353D01*
G01X127188Y226012D02*
X127137Y226999D01*
G01X127135Y226037D02*
X127185Y225050D01*
G01X125544Y220340D02*
X125494Y221327D01*
G01X125491Y220365D02*
X125542Y219379D01*
G01X123255Y226012D02*
X123205Y226999D01*
G01X123202Y226037D02*
X123253Y225050D01*
G01X121603Y220340D02*
X121552Y221327D01*
G01X121550Y220365D02*
X121600Y219379D01*
G01X115083Y203158D02*
X114837Y202991D01*
G01X116805Y201986D02*
X116477Y201734D01*
G01X110080Y201483D02*
X110408Y201734D01*
G01X123367Y201986D02*
X123285Y201902D01*
G01X123121Y202070D02*
X123367Y202321D01*
G01X122055Y201986D02*
X121891Y201818D01*
G01Y202153D02*
X122055Y202321D01*
G01X119676Y201986D02*
X119594Y201902D01*
G01X119430Y202070D02*
X119676Y202321D01*
G01X118364Y201986D02*
X118200Y201818D01*
G01X116477Y200310D02*
X116641Y200478D01*
G01X118200Y202153D02*
X118364Y202321D01*
G01X116313Y202070D02*
X116477Y202237D01*
G01X114345Y203075D02*
X114673Y203410D01*
G01X153157Y214640D02*
X153411Y215009D01*
G01X153144Y215615D02*
X153366Y215937D01*
G01X162527Y230762D02*
X162306Y230441D01*
G01X162514Y231737D02*
X162260Y231368D01*
G01X149225Y214640D02*
X149479Y215009D01*
G01X149433Y215937D02*
X149214Y215617D01*
G01X158364Y230441D02*
X158584Y230760D01*
G01X158572Y231737D02*
X158318Y231368D01*
G01X145283Y214640D02*
X145537Y215009D01*
G01X145270Y215615D02*
X145492Y215937D01*
G01X154653Y230762D02*
X154432Y230441D01*
G01X154640Y231737D02*
X154386Y231368D01*
G01X141351Y214640D02*
X141605Y215009D01*
G01X141559Y215937D02*
X141340Y215617D01*
G01X150490Y230441D02*
X150710Y230760D01*
G01X150698Y231737D02*
X150444Y231368D01*
G01X137409Y214640D02*
X137663Y215009D01*
G01X137396Y215615D02*
X137618Y215937D01*
G01X146779Y230762D02*
X146558Y230441D01*
G01X146766Y231737D02*
X146512Y231368D01*
G01X133477Y214640D02*
X133731Y215009D01*
G01X133685Y215937D02*
X133466Y215617D01*
G01X142616Y230441D02*
X142836Y230760D01*
G01X142824Y231737D02*
X142570Y231368D01*
G01X129535Y214640D02*
X129789Y215009D01*
G01X129522Y215615D02*
X129744Y215937D01*
G01X138905Y230762D02*
X138684Y230441D01*
G01X138892Y231737D02*
X138638Y231368D01*
G01X125603Y214640D02*
X125857Y215009D01*
G01X125811Y215937D02*
X125592Y215617D01*
G01X134742Y230441D02*
X134962Y230760D01*
G01X117051Y200394D02*
X116887Y200143D01*
G01X116969Y202237D02*
X116805Y201986D01*
G01X123285Y201902D02*
X123203Y201734D01*
G01X119594Y201902D02*
X119512Y201734D01*
G01X116641Y200478D02*
X116723Y200646D01*
G01X116477Y202237D02*
X116641Y202572D01*
G01X117134Y200646D02*
X117051Y200394D01*
G01X112048Y200897D02*
X111966Y200646D01*
G01X117051Y202572D02*
X116969Y202237D01*
G01X114263Y202740D02*
X114345Y203075D01*
G01X134742Y230441D02*
X134732Y230393D01*
G01X129753Y215984D02*
X129744Y215937D01*
G01X130800Y230393D02*
X130810Y230441D01*
G01X125811Y215937D02*
X125821Y215984D01*
G01X126868Y230441D02*
X126858Y230393D01*
G01X121879Y215984D02*
X121870Y215937D01*
G01X122926Y230393D02*
X122935Y230441D01*
G01X109916Y201902D02*
Y203242D01*
G01X109506Y203661D02*
Y201483D01*
G01X115021Y242519D02*
X114529Y241932D01*
G01Y242602D02*
X115021Y243189D01*
G01X112048Y200059D02*
X112294Y200394D01*
G01X134950Y231737D02*
X134696Y231368D01*
G01X121661Y214640D02*
X121915Y215009D01*
G01X121648Y215615D02*
X121870Y215937D01*
G01X131031Y230762D02*
X130810Y230441D01*
G01X131018Y231737D02*
X130764Y231368D01*
G01X126868Y230441D02*
X127088Y230760D01*
G01X127076Y231737D02*
X126822Y231368D01*
G01X123157Y230762D02*
X122935Y230441D01*
G01X123144Y231737D02*
X122890Y231368D01*
G01X116958Y219645D02*
X115001Y216693D01*
G01X114837Y202991D02*
X114673Y202740D01*
G01X111966Y200646D02*
X111802Y200394D01*
G01X108849Y201148D02*
X108685Y200897D01*
G01X112294Y200394D02*
X112458Y200813D01*
G01X110592Y239252D02*
X111904Y243189D01*
G01X111412Y240257D02*
X111084Y239252D01*
G01X111494Y240592D02*
X112232Y242854D01*
G01X175080Y563228D02*
X173111Y565196D01*
G01X175080Y534488D02*
Y563228D01*
G01Y534488D02*
G03X175867Y533700I787J-1D01*
G01X209529D02*
X175867D01*
G01X114845Y782204D02*
Y764881D01*
G01X207086Y-588235D02*
X207556Y-588970D01*
X208182Y-589390D01*
X208887Y-589495D01*
X209514Y-589390D01*
X210141Y-588865D01*
X210532Y-588235D01*
X210611Y-587605D01*
X210454Y-586870D01*
X209906Y-586345D01*
X209357Y-586135D01*
X208652D01*
G01X209357D02*
X209827Y-585820D01*
X210219Y-585295D01*
X210376Y-584665D01*
X210219Y-584035D01*
X209827Y-583510D01*
X209122Y-583195D01*
X208417Y-583300D01*
X207712Y-583720D01*
G01X264903Y-58386D02*
Y-69410D01*
G01X263918D02*
Y-58386D01*
G01X261753D02*
Y-69410D01*
G01X260769D02*
Y-58386D01*
G01X258603D02*
Y-69410D01*
G01X257619D02*
Y-58386D01*
G01X255454D02*
Y-69410D01*
G01X254469D02*
Y-58386D01*
G01X252304D02*
Y-69410D01*
G01X251320D02*
Y-58386D01*
G01X249155D02*
Y-69410D01*
G01X248170D02*
Y-58386D01*
G01X246005D02*
Y-69410D01*
G01X245021D02*
Y-58386D01*
G01X242855D02*
Y-69410D01*
G01X241871D02*
Y-58386D01*
G01X239706D02*
Y-69410D01*
G01X238721D02*
Y-58386D01*
G01X236556D02*
Y-69410D01*
G01X235572D02*
Y-58386D01*
G01X233406D02*
Y-69410D01*
G01X232422D02*
Y-58386D01*
G01X230257D02*
Y-69410D01*
G01X229273D02*
Y-58386D01*
G01X227107D02*
Y-69410D01*
G01X226123D02*
Y-58386D01*
G01X223958D02*
Y-69410D01*
G01X222973D02*
Y-58386D01*
G01X220808D02*
Y-69410D01*
G01X219824D02*
Y-58386D01*
G01X217658D02*
Y-69410D01*
G01X216674D02*
Y-58386D01*
G01X214509D02*
Y-69410D01*
G01X213525D02*
Y-58386D01*
G01X211359D02*
Y-69410D01*
G01X210375D02*
Y-58386D01*
G01X208210D02*
Y-69410D01*
G01X207225D02*
Y-58386D01*
G01X205060D02*
Y-69410D01*
G01X204076D02*
Y-58386D01*
G01X201910D02*
Y-69410D01*
G01X200926D02*
Y-58386D01*
G01X198761D02*
Y-69410D01*
G01X197777D02*
Y-58386D01*
G01X195611D02*
Y-69410D01*
G01X194627D02*
Y-58386D01*
G01X192462D02*
Y-69410D01*
G01X191477Y-58386D02*
Y-69410D01*
G01X189312D02*
Y-58386D01*
G01X187245Y-71378D02*
Y-52874D01*
G01Y-71378D02*
Y-52874D01*
G01X264903Y-69410D02*
X267068D01*
G01X261753D02*
X263918D01*
G01X258603D02*
X260769D01*
G01X255454D02*
X257619D01*
G01X252304D02*
X254469D01*
G01X249155D02*
X251320D01*
G01X246005D02*
X248170D01*
G01X242855D02*
X245021D01*
G01X239706D02*
X241871D01*
G01X236556D02*
X238721D01*
G01X233406D02*
X235572D01*
G01X230257D02*
X232422D01*
G01X227107D02*
X229273D01*
G01X223958D02*
X226123D01*
G01X220808D02*
X222973D01*
G01X217658D02*
X219824D01*
G01X214509D02*
X216674D01*
G01X211359D02*
X213525D01*
G01X208210D02*
X210375D01*
G01X205060D02*
X207225D01*
G01X201910D02*
X204076D01*
G01X198761D02*
X200926D01*
G01X195611D02*
X197777D01*
G01X192462D02*
X194627D01*
G01X191477D02*
X189312D01*
G01X405434Y-70278D02*
X187245D01*
G01X189214Y-73347D02*
X403466D01*
G01X189214D02*
X403466D01*
G01X189214D02*
X187245Y-71378D01*
G01X189214Y-73347D02*
X187245Y-71378D01*
G01X189214Y-73346D02*
X403466D01*
G01X187245Y-71378D02*
X189214Y-73346D01*
G01X187245Y-52874D02*
Y-71378D01*
G01X189312Y-58386D02*
X191477D01*
G01X194627D02*
X192462D01*
G01X197777D02*
X195611D01*
G01X200926D02*
X198761D01*
G01X204076D02*
X201910D01*
G01X207225D02*
X205060D01*
G01X210375D02*
X208210D01*
G01X213525D02*
X211359D01*
G01X216674D02*
X214509D01*
G01X219824D02*
X217658D01*
G01X222973D02*
X220808D01*
G01X226123D02*
X223958D01*
G01X229273D02*
X227107D01*
G01X232422D02*
X230257D01*
G01X235572D02*
X233406D01*
G01X238721D02*
X236556D01*
G01X241871D02*
X239706D01*
G01X245021D02*
X242855D01*
G01X248170D02*
X246005D01*
G01X251320D02*
X249155D01*
G01X254469D02*
X252304D01*
G01X257619D02*
X255454D01*
G01X260769D02*
X258603D01*
G01X263918D02*
X261753D01*
G01X267068D02*
X264903D01*
G01X264998Y145965D02*
X265009Y146239D01*
G01X264993Y145948D02*
X264998Y145965D01*
G01X264988Y146012D02*
X264993Y145948D01*
G01X265000Y144988D02*
X265014Y145353D01*
G01X264992Y144965D02*
X265000Y144988D01*
G01X264985Y145050D02*
X264992Y144965D01*
G01X264921Y146524D02*
X264935Y146037D01*
G01X264915Y146913D02*
X264921Y146524D01*
G01X264910Y147384D02*
X264915Y146913D01*
G01X264906Y147925D02*
X264910Y147384D01*
G01X264903Y148520D02*
X264906Y147925D01*
G01X264901Y149153D02*
X264903Y148520D01*
G01X264900Y149807D02*
X264901Y149153D01*
G01X264895Y151677D02*
X264888Y151750D01*
G01X264899Y151547D02*
X264895Y151677D01*
G01X264902Y151359D02*
X264899Y151547D01*
G01X264905Y151120D02*
X264902Y151359D01*
G01X264908Y150838D02*
X264905Y151120D01*
G01X264910Y150521D02*
X264908Y150838D01*
G01X264911Y150180D02*
X264910Y150521D01*
G01X264911Y149826D02*
Y150180D01*
G01X264927Y147364D02*
X264937Y146999D01*
G01X264922Y147656D02*
X264927Y147364D01*
G01X264919Y148009D02*
X264922Y147656D01*
G01X264916Y148414D02*
X264919Y148009D01*
G01X264913Y148861D02*
X264916Y148414D01*
G01X264912Y149336D02*
X264913Y148861D01*
G01X264911Y149826D02*
X264912Y149336D01*
G01X263281Y145965D02*
X263291Y146012D01*
G01X263275Y146063D02*
X263281Y145965D01*
G01X263270Y146239D02*
X263275Y146063D01*
G01X263366Y148861D02*
X263368Y149826D01*
G01X263363Y148414D02*
X263366Y148861D01*
G01X263360Y148009D02*
X263363Y148414D01*
G01X263357Y147656D02*
X263360Y148009D01*
G01X263352Y147364D02*
X263357Y147656D01*
G01X263347Y147143D02*
X263352Y147364D01*
G01X263342Y146999D02*
X263347Y147143D01*
G01X263369Y150521D02*
X263368Y149826D01*
G01X263371Y150838D02*
X263369Y150521D01*
G01X263374Y151120D02*
X263371Y150838D01*
G01X263377Y151359D02*
X263374Y151120D01*
G01X263380Y151547D02*
X263377Y151359D01*
G01X263384Y151677D02*
X263380Y151547D01*
G01X263387Y151746D02*
X263384Y151677D01*
G01X263391Y151750D02*
X263387Y151746D01*
G01X263376Y148520D02*
X263379Y149807D01*
G01X263373Y147925D02*
X263376Y148520D01*
G01X263369Y147384D02*
X263373Y147925D01*
G01X263364Y146913D02*
X263369Y147384D01*
G01X263358Y146524D02*
X263364Y146913D01*
G01X263351Y146230D02*
X263358Y146524D01*
G01X263344Y146037D02*
X263351Y146230D01*
G01X263279Y144988D02*
X263294Y145050D01*
G01X263272Y145118D02*
X263279Y144988D01*
G01X263265Y145353D02*
X263272Y145118D01*
G01X263271Y140412D02*
X263261Y140138D01*
G01X263277Y140429D02*
X263271Y140412D01*
G01X263282Y140365D02*
X263277Y140429D01*
G01X263270Y141390D02*
X263256Y141024D01*
G01X263277Y141412D02*
X263270Y141390D01*
G01X263284Y141327D02*
X263277Y141412D01*
G01X263348Y139853D02*
X263335Y140340D01*
G01X263354Y139464D02*
X263348Y139853D01*
G01X263359Y138993D02*
X263354Y139464D01*
G01X263364Y138453D02*
X263359Y138993D01*
G01X263367Y137857D02*
X263364Y138453D01*
G01X263369Y137224D02*
X263367Y137857D01*
G01X263369Y136570D02*
Y137224D01*
G01X263374Y134700D02*
X263382Y134627D01*
G01X263371Y134830D02*
X263374Y134700D01*
G01X263367Y135018D02*
X263371Y134830D01*
G01X263364Y135257D02*
X263367Y135018D01*
G01X263362Y135540D02*
X263364Y135257D01*
G01X263360Y135857D02*
X263362Y135540D01*
G01X263359Y136198D02*
X263360Y135857D01*
G01X263358Y136551D02*
X263359Y136198D01*
G01X263343Y139013D02*
X263333Y139379D01*
G01X263347Y138722D02*
X263343Y139013D01*
G01X263351Y138368D02*
X263347Y138722D01*
G01X263354Y137963D02*
X263351Y138368D01*
G01X263356Y137516D02*
X263354Y137963D01*
G01X263358Y137041D02*
X263356Y137516D01*
G01X263358Y136551D02*
Y137041D01*
G01X264989Y140412D02*
X264978Y140365D01*
G01X264994Y140314D02*
X264989Y140412D01*
G01X265000Y140138D02*
X264994Y140314D01*
G01X264904Y137516D02*
X264902Y136551D01*
G01X264906Y137963D02*
X264904Y137516D01*
G01X264909Y138368D02*
X264906Y137963D01*
G01X264913Y138722D02*
X264909Y138368D01*
G01X264918Y139013D02*
X264913Y138722D01*
G01X264922Y139234D02*
X264918Y139013D01*
G01X264928Y139379D02*
X264922Y139234D01*
G01X264900Y135857D02*
X264902Y136551D01*
G01X264898Y135540D02*
X264900Y135857D01*
G01X264896Y135257D02*
X264898Y135540D01*
G01X264893Y135018D02*
X264896Y135257D01*
G01X264890Y134830D02*
X264893Y135018D01*
G01X264886Y134700D02*
X264890Y134830D01*
G01X264882Y134632D02*
X264886Y134700D01*
G01X264878Y134627D02*
X264882Y134632D01*
G01X264894Y137857D02*
X264891Y136570D01*
G01X264897Y138453D02*
X264894Y137857D01*
G01X264901Y138993D02*
X264897Y138453D01*
G01X264906Y139464D02*
X264901Y138993D01*
G01X264912Y139853D02*
X264906Y139464D01*
G01X264918Y140148D02*
X264912Y139853D01*
G01X264925Y140340D02*
X264918Y140148D01*
G01X264990Y141390D02*
X264976Y141327D01*
G01X264998Y141259D02*
X264990Y141390D01*
G01X265004Y141024D02*
X264998Y141259D01*
G01X259339Y145965D02*
X259350Y146012D01*
G01X259334Y146063D02*
X259339Y145965D01*
G01X259328Y146239D02*
X259334Y146063D01*
G01X259424Y148861D02*
X259426Y149826D01*
G01X259422Y148414D02*
X259424Y148861D01*
G01X259419Y148009D02*
X259422Y148414D01*
G01X259415Y147656D02*
X259419Y148009D01*
G01X259410Y147364D02*
X259415Y147656D01*
G01X259405Y147143D02*
X259410Y147364D01*
G01X259400Y146999D02*
X259405Y147143D01*
G01X259434Y148520D02*
X259437Y149807D01*
G01X259431Y147925D02*
X259434Y148520D01*
G01X259427Y147384D02*
X259431Y147925D01*
G01X259422Y146913D02*
X259427Y147384D01*
G01X259416Y146524D02*
X259422Y146913D01*
G01X259410Y146230D02*
X259416Y146524D01*
G01X259403Y146037D02*
X259410Y146230D01*
G01X259338Y144988D02*
X259352Y145050D01*
G01X259330Y145118D02*
X259338Y144988D01*
G01X259324Y145353D02*
X259330Y145118D01*
G01X261058Y144988D02*
X261072Y145353D01*
G01X261051Y144965D02*
X261058Y144988D01*
G01X261044Y145050D02*
X261051Y144965D01*
G01X260980Y146524D02*
X260993Y146037D01*
G01X260974Y146913D02*
X260980Y146524D01*
G01X260969Y147384D02*
X260974Y146913D01*
G01X260964Y147925D02*
X260969Y147384D01*
G01X260961Y148520D02*
X260964Y147925D01*
G01X260959Y149153D02*
X260961Y148520D01*
G01X260959Y149807D02*
Y149153D01*
G01X260985Y147364D02*
X260995Y146999D01*
G01X260981Y147656D02*
X260985Y147364D01*
G01X260977Y148009D02*
X260981Y147656D01*
G01X260974Y148414D02*
X260977Y148009D01*
G01X260972Y148861D02*
X260974Y148414D01*
G01X260970Y149336D02*
X260972Y148861D01*
G01X260969Y149826D02*
X260970Y149336D01*
G01X261057Y145965D02*
X261067Y146239D01*
G01X261051Y145948D02*
X261057Y145965D01*
G01X261046Y146012D02*
X261051Y145948D01*
G01X261057Y140412D02*
X261046Y140365D01*
G01X261062Y140314D02*
X261057Y140412D01*
G01X261067Y140138D02*
X261062Y140314D01*
G01X260972Y137516D02*
X260969Y136551D01*
G01X260974Y137963D02*
X260972Y137516D01*
G01X260977Y138368D02*
X260974Y137963D01*
G01X260981Y138722D02*
X260977Y138368D01*
G01X260985Y139013D02*
X260981Y138722D01*
G01X260990Y139234D02*
X260985Y139013D01*
G01X260995Y139379D02*
X260990Y139234D01*
G01X260961Y137857D02*
X260959Y136570D01*
G01X260964Y138453D02*
X260961Y137857D01*
G01X260969Y138993D02*
X260964Y138453D01*
G01X260974Y139464D02*
X260969Y138993D01*
G01X260980Y139853D02*
X260974Y139464D01*
G01X260986Y140148D02*
X260980Y139853D01*
G01X260993Y140340D02*
X260986Y140148D01*
G01X261058Y141390D02*
X261044Y141327D01*
G01X261065Y141259D02*
X261058Y141390D01*
G01X261072Y141024D02*
X261065Y141259D01*
G01X259338Y141390D02*
X259324Y141024D01*
G01X259345Y141412D02*
X259338Y141390D01*
G01X259352Y141327D02*
X259345Y141412D01*
G01X259416Y139853D02*
X259403Y140340D01*
G01X259422Y139464D02*
X259416Y139853D01*
G01X259427Y138993D02*
X259422Y139464D01*
G01X259431Y138453D02*
X259427Y138993D01*
G01X259434Y137857D02*
X259431Y138453D01*
G01X259436Y137224D02*
X259434Y137857D01*
G01X259437Y136570D02*
X259436Y137224D01*
G01X259410Y139013D02*
X259400Y139379D01*
G01X259415Y138722D02*
X259410Y139013D01*
G01X259419Y138368D02*
X259415Y138722D01*
G01X259422Y137963D02*
X259419Y138368D01*
G01X259424Y137516D02*
X259422Y137963D01*
G01X259426Y137041D02*
X259424Y137516D01*
G01X259426Y136551D02*
Y137041D01*
G01X259339Y140412D02*
X259328Y140138D01*
G01X259344Y140429D02*
X259339Y140412D01*
G01X259350Y140365D02*
X259344Y140429D01*
G01X255407Y145965D02*
X255417Y146012D01*
G01X255401Y146063D02*
X255407Y145965D01*
G01X255396Y146239D02*
X255401Y146063D01*
G01X255492Y148861D02*
X255494Y149826D01*
G01X255489Y148414D02*
X255492Y148861D01*
G01X255486Y148009D02*
X255489Y148414D01*
G01X255482Y147656D02*
X255486Y148009D01*
G01X255478Y147364D02*
X255482Y147656D01*
G01X255473Y147143D02*
X255478Y147364D01*
G01X255468Y146999D02*
X255473Y147143D01*
G01X255495Y150521D02*
X255494Y149826D01*
G01X255497Y150838D02*
X255495Y150521D01*
G01X255500Y151120D02*
X255497Y150838D01*
G01X255503Y151359D02*
X255500Y151120D01*
G01X255506Y151547D02*
X255503Y151359D01*
G01X255510Y151677D02*
X255506Y151547D01*
G01X255513Y151746D02*
X255510Y151677D01*
G01X255517Y151750D02*
X255513Y151746D01*
G01X255502Y148520D02*
X255505Y149807D01*
G01X255499Y147925D02*
X255502Y148520D01*
G01X255495Y147384D02*
X255499Y147925D01*
G01X255490Y146913D02*
X255495Y147384D01*
G01X255484Y146524D02*
X255490Y146913D01*
G01X255477Y146230D02*
X255484Y146524D01*
G01X255470Y146037D02*
X255477Y146230D01*
G01X255405Y144988D02*
X255420Y145050D01*
G01X255398Y145118D02*
X255405Y144988D01*
G01X255391Y145353D02*
X255398Y145118D01*
G01X257126Y144988D02*
X257140Y145353D01*
G01X257118Y144965D02*
X257126Y144988D01*
G01X257111Y145050D02*
X257118Y144965D01*
G01X257047Y146524D02*
X257061Y146037D01*
G01X257041Y146913D02*
X257047Y146524D01*
G01X257036Y147384D02*
X257041Y146913D01*
G01X257032Y147925D02*
X257036Y147384D01*
G01X257029Y148520D02*
X257032Y147925D01*
G01X257027Y149153D02*
X257029Y148520D01*
G01X257026Y149807D02*
X257027Y149153D01*
G01X257021Y151677D02*
X257014Y151750D01*
G01X257025Y151547D02*
X257021Y151677D01*
G01X257028Y151359D02*
X257025Y151547D01*
G01X257031Y151120D02*
X257028Y151359D01*
G01X257034Y150838D02*
X257031Y151120D01*
G01X257036Y150521D02*
X257034Y150838D01*
G01X257037Y150180D02*
X257036Y150521D01*
G01X257037Y149826D02*
Y150180D01*
G01X257053Y147364D02*
X257063Y146999D01*
G01X257048Y147656D02*
X257053Y147364D01*
G01X257045Y148009D02*
X257048Y147656D01*
G01X257042Y148414D02*
X257045Y148009D01*
G01X257039Y148861D02*
X257042Y148414D01*
G01X257038Y149336D02*
X257039Y148861D01*
G01X257037Y149826D02*
X257038Y149336D01*
G01X257124Y145965D02*
X257135Y146239D01*
G01X257119Y145948D02*
X257124Y145965D01*
G01X257114Y146012D02*
X257119Y145948D01*
G01X257115Y140412D02*
X257104Y140365D01*
G01X257120Y140314D02*
X257115Y140412D01*
G01X257126Y140138D02*
X257120Y140314D01*
G01X257030Y137516D02*
X257028Y136551D01*
G01X257032Y137963D02*
X257030Y137516D01*
G01X257035Y138368D02*
X257032Y137963D01*
G01X257039Y138722D02*
X257035Y138368D01*
G01X257044Y139013D02*
X257039Y138722D01*
G01X257048Y139234D02*
X257044Y139013D01*
G01X257054Y139379D02*
X257048Y139234D01*
G01X257026Y135857D02*
X257028Y136551D01*
G01X257024Y135540D02*
X257026Y135857D01*
G01X257022Y135257D02*
X257024Y135540D01*
G01X257019Y135018D02*
X257022Y135257D01*
G01X257016Y134830D02*
X257019Y135018D01*
G01X257012Y134700D02*
X257016Y134830D01*
G01X257008Y134632D02*
X257012Y134700D01*
G01X257004Y134627D02*
X257008Y134632D01*
G01X257020Y137857D02*
X257017Y136570D01*
G01X257023Y138453D02*
X257020Y137857D01*
G01X257027Y138993D02*
X257023Y138453D01*
G01X257032Y139464D02*
X257027Y138993D01*
G01X257038Y139853D02*
X257032Y139464D01*
G01X257044Y140148D02*
X257038Y139853D01*
G01X257051Y140340D02*
X257044Y140148D01*
G01X257116Y141390D02*
X257102Y141327D01*
G01X257124Y141259D02*
X257116Y141390D01*
G01X257130Y141024D02*
X257124Y141259D01*
G01X255396Y141390D02*
X255382Y141024D01*
G01X255403Y141412D02*
X255396Y141390D01*
G01X255410Y141327D02*
X255403Y141412D01*
G01X255474Y139853D02*
X255461Y140340D01*
G01X255480Y139464D02*
X255474Y139853D01*
G01X255485Y138993D02*
X255480Y139464D01*
G01X255490Y138453D02*
X255485Y138993D01*
G01X255493Y137857D02*
X255490Y138453D01*
G01X255495Y137224D02*
X255493Y137857D01*
G01X255495Y136570D02*
Y137224D01*
G01X255500Y134700D02*
X255508Y134627D01*
G01X255497Y134830D02*
X255500Y134700D01*
G01X255493Y135018D02*
X255497Y134830D01*
G01X255490Y135257D02*
X255493Y135018D01*
G01X255488Y135540D02*
X255490Y135257D01*
G01X255486Y135857D02*
X255488Y135540D01*
G01X255485Y136198D02*
X255486Y135857D01*
G01X255484Y136551D02*
X255485Y136198D01*
G01X255469Y139013D02*
X255459Y139379D01*
G01X255473Y138722D02*
X255469Y139013D01*
G01X255477Y138368D02*
X255473Y138722D01*
G01X255480Y137963D02*
X255477Y138368D01*
G01X255482Y137516D02*
X255480Y137963D01*
G01X255484Y137041D02*
X255482Y137516D01*
G01X255484Y136551D02*
Y137041D01*
G01X255397Y140412D02*
X255387Y140138D01*
G01X255403Y140429D02*
X255397Y140412D01*
G01X255408Y140365D02*
X255403Y140429D01*
G01X251465Y145965D02*
X251476Y146012D01*
G01X251459Y146063D02*
X251465Y145965D01*
G01X251454Y146239D02*
X251459Y146063D01*
G01X251550Y148861D02*
X251552Y149826D01*
G01X251548Y148414D02*
X251550Y148861D01*
G01X251545Y148009D02*
X251548Y148414D01*
G01X251541Y147656D02*
X251545Y148009D01*
G01X251536Y147364D02*
X251541Y147656D01*
G01X251531Y147143D02*
X251536Y147364D01*
G01X251526Y146999D02*
X251531Y147143D01*
G01X251560Y148520D02*
X251563Y149807D01*
G01X251557Y147925D02*
X251560Y148520D01*
G01X251553Y147384D02*
X251557Y147925D01*
G01X251548Y146913D02*
X251553Y147384D01*
G01X251542Y146524D02*
X251548Y146913D01*
G01X251536Y146230D02*
X251542Y146524D01*
G01X251529Y146037D02*
X251536Y146230D01*
G01X251464Y144988D02*
X251478Y145050D01*
G01X251456Y145118D02*
X251464Y144988D01*
G01X251450Y145353D02*
X251456Y145118D01*
G01X253184Y144988D02*
X253198Y145353D01*
G01X253177Y144965D02*
X253184Y144988D01*
G01X253170Y145050D02*
X253177Y144965D01*
G01X253105Y146524D02*
X253119Y146037D01*
G01X253100Y146913D02*
X253105Y146524D01*
G01X253094Y147384D02*
X253100Y146913D01*
G01X253090Y147925D02*
X253094Y147384D01*
G01X253087Y148520D02*
X253090Y147925D01*
G01X253085Y149153D02*
X253087Y148520D01*
G01X253085Y149807D02*
Y149153D01*
G01X253111Y147364D02*
X253121Y146999D01*
G01X253107Y147656D02*
X253111Y147364D01*
G01X253103Y148009D02*
X253107Y147656D01*
G01X253100Y148414D02*
X253103Y148009D01*
G01X253098Y148861D02*
X253100Y148414D01*
G01X253096Y149336D02*
X253098Y148861D01*
G01X253095Y149826D02*
X253096Y149336D01*
G01X253183Y145965D02*
X253193Y146239D01*
G01X253177Y145948D02*
X253183Y145965D01*
G01X253172Y146012D02*
X253177Y145948D01*
G01X253183Y140412D02*
X253172Y140365D01*
G01X253188Y140314D02*
X253183Y140412D01*
G01X253193Y140138D02*
X253188Y140314D01*
G01X253098Y137516D02*
X253095Y136551D01*
G01X253100Y137963D02*
X253098Y137516D01*
G01X253103Y138368D02*
X253100Y137963D01*
G01X253107Y138722D02*
X253103Y138368D01*
G01X253111Y139013D02*
X253107Y138722D01*
G01X253116Y139234D02*
X253111Y139013D01*
G01X253121Y139379D02*
X253116Y139234D01*
G01X253087Y137857D02*
X253085Y136570D01*
G01X253090Y138453D02*
X253087Y137857D01*
G01X253094Y138993D02*
X253090Y138453D01*
G01X253100Y139464D02*
X253094Y138993D01*
G01X253105Y139853D02*
X253100Y139464D01*
G01X253112Y140148D02*
X253105Y139853D01*
G01X253119Y140340D02*
X253112Y140148D01*
G01X253184Y141390D02*
X253170Y141327D01*
G01X253191Y141259D02*
X253184Y141390D01*
G01X253198Y141024D02*
X253191Y141259D01*
G01X251464Y141390D02*
X251450Y141024D01*
G01X251471Y141412D02*
X251464Y141390D01*
G01X251478Y141327D02*
X251471Y141412D01*
G01X251542Y139853D02*
X251529Y140340D01*
G01X251548Y139464D02*
X251542Y139853D01*
G01X251553Y138993D02*
X251548Y139464D01*
G01X251557Y138453D02*
X251553Y138993D01*
G01X251560Y137857D02*
X251557Y138453D01*
G01X251562Y137224D02*
X251560Y137857D01*
G01X251563Y136570D02*
X251562Y137224D01*
G01X251536Y139013D02*
X251526Y139379D01*
G01X251541Y138722D02*
X251536Y139013D01*
G01X251545Y138368D02*
X251541Y138722D01*
G01X251548Y137963D02*
X251545Y138368D01*
G01X251550Y137516D02*
X251548Y137963D01*
G01X251552Y137041D02*
X251550Y137516D01*
G01X251552Y136551D02*
Y137041D01*
G01X251465Y140412D02*
X251454Y140138D01*
G01X251470Y140429D02*
X251465Y140412D01*
G01X251476Y140365D02*
X251470Y140429D01*
G01X247533Y145965D02*
X247543Y146012D01*
G01X247527Y146063D02*
X247533Y145965D01*
G01X247522Y146239D02*
X247527Y146063D01*
G01X247618Y148861D02*
X247620Y149826D01*
G01X247615Y148414D02*
X247618Y148861D01*
G01X247612Y148009D02*
X247615Y148414D01*
G01X247608Y147656D02*
X247612Y148009D01*
G01X247604Y147364D02*
X247608Y147656D01*
G01X247599Y147143D02*
X247604Y147364D01*
G01X247594Y146999D02*
X247599Y147143D01*
G01X247621Y150521D02*
X247620Y149826D01*
G01X247623Y150838D02*
X247621Y150521D01*
G01X247626Y151120D02*
X247623Y150838D01*
G01X247629Y151359D02*
X247626Y151120D01*
G01X247632Y151547D02*
X247629Y151359D01*
G01X247636Y151677D02*
X247632Y151547D01*
G01X247639Y151746D02*
X247636Y151677D01*
G01X247643Y151750D02*
X247639Y151746D01*
G01X247628Y148520D02*
X247631Y149807D01*
G01X247625Y147925D02*
X247628Y148520D01*
G01X247621Y147384D02*
X247625Y147925D01*
G01X247616Y146913D02*
X247621Y147384D01*
G01X247610Y146524D02*
X247616Y146913D01*
G01X247603Y146230D02*
X247610Y146524D01*
G01X247596Y146037D02*
X247603Y146230D01*
G01X247531Y144988D02*
X247546Y145050D01*
G01X247524Y145118D02*
X247531Y144988D01*
G01X247517Y145353D02*
X247524Y145118D01*
G01X249252Y144988D02*
X249266Y145353D01*
G01X249244Y144965D02*
X249252Y144988D01*
G01X249237Y145050D02*
X249244Y144965D01*
G01X249173Y146524D02*
X249187Y146037D01*
G01X249167Y146913D02*
X249173Y146524D01*
G01X249162Y147384D02*
X249167Y146913D01*
G01X249158Y147925D02*
X249162Y147384D01*
G01X249155Y148520D02*
X249158Y147925D01*
G01X249153Y149153D02*
X249155Y148520D01*
G01X249152Y149807D02*
X249153Y149153D01*
G01X249147Y151677D02*
X249139Y151750D01*
G01X249151Y151547D02*
X249147Y151677D01*
G01X249154Y151359D02*
X249151Y151547D01*
G01X249157Y151120D02*
X249154Y151359D01*
G01X249160Y150838D02*
X249157Y151120D01*
G01X249162Y150521D02*
X249160Y150838D01*
G01X249163Y150180D02*
X249162Y150521D01*
G01X249163Y149826D02*
Y150180D01*
G01X249179Y147364D02*
X249189Y146999D01*
G01X249174Y147656D02*
X249179Y147364D01*
G01X249171Y148009D02*
X249174Y147656D01*
G01X249167Y148414D02*
X249171Y148009D01*
G01X249165Y148861D02*
X249167Y148414D01*
G01X249164Y149336D02*
X249165Y148861D01*
G01X249163Y149826D02*
X249164Y149336D01*
G01X249250Y145965D02*
X249261Y146239D01*
G01X249245Y145948D02*
X249250Y145965D01*
G01X249240Y146012D02*
X249245Y145948D01*
G01X249241Y140412D02*
X249230Y140365D01*
G01X249246Y140314D02*
X249241Y140412D01*
G01X249252Y140138D02*
X249246Y140314D01*
G01X249156Y137516D02*
X249154Y136551D01*
G01X249158Y137963D02*
X249156Y137516D01*
G01X249161Y138368D02*
X249158Y137963D01*
G01X249165Y138722D02*
X249161Y138368D01*
G01X249170Y139013D02*
X249165Y138722D01*
G01X249174Y139234D02*
X249170Y139013D01*
G01X249180Y139379D02*
X249174Y139234D01*
G01X249152Y135857D02*
X249154Y136551D01*
G01X249150Y135540D02*
X249152Y135857D01*
G01X249148Y135257D02*
X249150Y135540D01*
G01X249145Y135018D02*
X249148Y135257D01*
G01X249142Y134830D02*
X249145Y135018D01*
G01X249138Y134700D02*
X249142Y134830D01*
G01X249134Y134632D02*
X249138Y134700D01*
G01X249130Y134627D02*
X249134Y134632D01*
G01X249146Y137857D02*
X249143Y136570D01*
G01X249149Y138453D02*
X249146Y137857D01*
G01X249153Y138993D02*
X249149Y138453D01*
G01X249158Y139464D02*
X249153Y138993D01*
G01X249164Y139853D02*
X249158Y139464D01*
G01X249170Y140148D02*
X249164Y139853D01*
G01X249177Y140340D02*
X249170Y140148D01*
G01X249242Y141390D02*
X249228Y141327D01*
G01X249249Y141259D02*
X249242Y141390D01*
G01X249256Y141024D02*
X249249Y141259D01*
G01X247522Y141390D02*
X247508Y141024D01*
G01X247529Y141412D02*
X247522Y141390D01*
G01X247536Y141327D02*
X247529Y141412D01*
G01X247600Y139853D02*
X247587Y140340D01*
G01X247606Y139464D02*
X247600Y139853D01*
G01X247611Y138993D02*
X247606Y139464D01*
G01X247616Y138453D02*
X247611Y138993D01*
G01X247619Y137857D02*
X247616Y138453D01*
G01X247621Y137224D02*
X247619Y137857D01*
G01X247621Y136570D02*
Y137224D01*
G01X247626Y134700D02*
X247634Y134627D01*
G01X247623Y134830D02*
X247626Y134700D01*
G01X247619Y135018D02*
X247623Y134830D01*
G01X247616Y135257D02*
X247619Y135018D01*
G01X247614Y135540D02*
X247616Y135257D01*
G01X247612Y135857D02*
X247614Y135540D01*
G01X247611Y136198D02*
X247612Y135857D01*
G01X247610Y136551D02*
X247611Y136198D01*
G01X247595Y139013D02*
X247585Y139379D01*
G01X247599Y138722D02*
X247595Y139013D01*
G01X247603Y138368D02*
X247599Y138722D01*
G01X247606Y137963D02*
X247603Y138368D01*
G01X247608Y137516D02*
X247606Y137963D01*
G01X247610Y137041D02*
X247608Y137516D01*
G01X247610Y136551D02*
Y137041D01*
G01X247523Y140412D02*
X247513Y140138D01*
G01X247529Y140429D02*
X247523Y140412D01*
G01X247534Y140365D02*
X247529Y140429D01*
G01X243591Y145965D02*
X243602Y146012D01*
G01X243585Y146063D02*
X243591Y145965D01*
G01X243580Y146239D02*
X243585Y146063D01*
G01X243676Y148861D02*
X243678Y149826D01*
G01X243674Y148414D02*
X243676Y148861D01*
G01X243671Y148009D02*
X243674Y148414D01*
G01X243667Y147656D02*
X243671Y148009D01*
G01X243662Y147364D02*
X243667Y147656D01*
G01X243657Y147143D02*
X243662Y147364D01*
G01X243652Y146999D02*
X243657Y147143D01*
G01X243686Y148520D02*
X243689Y149807D01*
G01X243683Y147925D02*
X243686Y148520D01*
G01X243679Y147384D02*
X243683Y147925D01*
G01X243674Y146913D02*
X243679Y147384D01*
G01X243668Y146524D02*
X243674Y146913D01*
G01X243662Y146230D02*
X243668Y146524D01*
G01X243655Y146037D02*
X243662Y146230D01*
G01X243590Y144988D02*
X243604Y145050D01*
G01X243582Y145118D02*
X243590Y144988D01*
G01X243576Y145353D02*
X243582Y145118D01*
G01X245309Y145965D02*
X245319Y146239D01*
G01X245303Y145948D02*
X245309Y145965D01*
G01X245298Y146012D02*
X245303Y145948D01*
G01X245310Y144988D02*
X245324Y145353D01*
G01X245303Y144965D02*
X245310Y144988D01*
G01X245296Y145050D02*
X245303Y144965D01*
G01X245231Y146524D02*
X245245Y146037D01*
G01X245226Y146913D02*
X245231Y146524D01*
G01X245220Y147384D02*
X245226Y146913D01*
G01X245216Y147925D02*
X245220Y147384D01*
G01X245213Y148520D02*
X245216Y147925D01*
G01X245211Y149153D02*
X245213Y148520D01*
G01X245210Y149807D02*
X245211Y149153D01*
G01X245237Y147364D02*
X245247Y146999D01*
G01X245233Y147656D02*
X245237Y147364D01*
G01X245229Y148009D02*
X245233Y147656D01*
G01X245226Y148414D02*
X245229Y148009D01*
G01X245223Y148861D02*
X245226Y148414D01*
G01X245222Y149336D02*
X245223Y148861D01*
G01X245221Y149826D02*
X245222Y149336D01*
G01X245309Y140412D02*
X245298Y140365D01*
G01X245314Y140314D02*
X245309Y140412D01*
G01X245319Y140138D02*
X245314Y140314D01*
G01X245223Y137516D02*
X245221Y136551D01*
G01X245226Y137963D02*
X245223Y137516D01*
G01X245229Y138368D02*
X245226Y137963D01*
G01X245233Y138722D02*
X245229Y138368D01*
G01X245237Y139013D02*
X245233Y138722D01*
G01X245242Y139234D02*
X245237Y139013D01*
G01X245247Y139379D02*
X245242Y139234D01*
G01X245213Y137857D02*
X245210Y136570D01*
G01X245216Y138453D02*
X245213Y137857D01*
G01X245220Y138993D02*
X245216Y138453D01*
G01X245226Y139464D02*
X245220Y138993D01*
G01X245231Y139853D02*
X245226Y139464D01*
G01X245238Y140148D02*
X245231Y139853D01*
G01X245245Y140340D02*
X245238Y140148D01*
G01X245310Y141390D02*
X245296Y141327D01*
G01X245317Y141259D02*
X245310Y141390D01*
G01X245324Y141024D02*
X245317Y141259D01*
G01X243591Y140412D02*
X243580Y140138D01*
G01X243596Y140429D02*
X243591Y140412D01*
G01X243602Y140365D02*
X243596Y140429D01*
G01X243590Y141390D02*
X243576Y141024D01*
G01X243597Y141412D02*
X243590Y141390D01*
G01X243604Y141327D02*
X243597Y141412D01*
G01X243668Y139853D02*
X243655Y140340D01*
G01X243674Y139464D02*
X243668Y139853D01*
G01X243679Y138993D02*
X243674Y139464D01*
G01X243683Y138453D02*
X243679Y138993D01*
G01X243686Y137857D02*
X243683Y138453D01*
G01X243688Y137224D02*
X243686Y137857D01*
G01X243689Y136570D02*
X243688Y137224D01*
G01X243662Y139013D02*
X243652Y139379D01*
G01X243667Y138722D02*
X243662Y139013D01*
G01X243671Y138368D02*
X243667Y138722D01*
G01X243674Y137963D02*
X243671Y138368D01*
G01X243676Y137516D02*
X243674Y137963D01*
G01X243678Y137041D02*
X243676Y137516D01*
G01X243678Y136551D02*
Y137041D01*
G01X241376Y145965D02*
X241387Y146239D01*
G01X241371Y145948D02*
X241376Y145965D01*
G01X241366Y146012D02*
X241371Y145948D01*
G01X241378Y144988D02*
X241392Y145353D01*
G01X241370Y144965D02*
X241378Y144988D01*
G01X241363Y145050D02*
X241370Y144965D01*
G01X241299Y146524D02*
X241313Y146037D01*
G01X241293Y146913D02*
X241299Y146524D01*
G01X241288Y147384D02*
X241293Y146913D01*
G01X241284Y147925D02*
X241288Y147384D01*
G01X241281Y148520D02*
X241284Y147925D01*
G01X241279Y149153D02*
X241281Y148520D01*
G01X241278Y149807D02*
X241279Y149153D01*
G01X241273Y151677D02*
X241265Y151750D01*
G01X241277Y151547D02*
X241273Y151677D01*
G01X241280Y151359D02*
X241277Y151547D01*
G01X241283Y151120D02*
X241280Y151359D01*
G01X241286Y150838D02*
X241283Y151120D01*
G01X241288Y150521D02*
X241286Y150838D01*
G01X241289Y150180D02*
X241288Y150521D01*
G01X241289Y149826D02*
Y150180D01*
G01X241305Y147364D02*
X241315Y146999D01*
G01X241300Y147656D02*
X241305Y147364D01*
G01X241297Y148009D02*
X241300Y147656D01*
G01X241293Y148414D02*
X241297Y148009D01*
G01X241291Y148861D02*
X241293Y148414D01*
G01X241290Y149336D02*
X241291Y148861D01*
G01X241289Y149826D02*
X241290Y149336D01*
G01X239658Y145965D02*
X239669Y146012D01*
G01X239653Y146063D02*
X239658Y145965D01*
G01X239648Y146239D02*
X239653Y146063D01*
G01X239744Y148861D02*
X239746Y149826D01*
G01X239741Y148414D02*
X239744Y148861D01*
G01X239738Y148009D02*
X239741Y148414D01*
G01X239734Y147656D02*
X239738Y148009D01*
G01X239730Y147364D02*
X239734Y147656D01*
G01X239725Y147143D02*
X239730Y147364D01*
G01X239720Y146999D02*
X239725Y147143D01*
G01X239747Y150521D02*
X239746Y149826D01*
G01X239749Y150838D02*
X239747Y150521D01*
G01X239752Y151120D02*
X239749Y150838D01*
G01X239754Y151359D02*
X239752Y151120D01*
G01X239758Y151547D02*
X239754Y151359D01*
G01X239762Y151677D02*
X239758Y151547D01*
G01X239765Y151746D02*
X239762Y151677D01*
G01X239769Y151750D02*
X239765Y151746D01*
G01X239754Y148520D02*
X239757Y149807D01*
G01X239751Y147925D02*
X239754Y148520D01*
G01X239747Y147384D02*
X239751Y147925D01*
G01X239742Y146913D02*
X239747Y147384D01*
G01X239736Y146524D02*
X239742Y146913D01*
G01X239729Y146230D02*
X239736Y146524D01*
G01X239722Y146037D02*
X239729Y146230D01*
G01X239657Y144988D02*
X239672Y145050D01*
G01X239650Y145118D02*
X239657Y144988D01*
G01X239643Y145353D02*
X239650Y145118D01*
G01X239649Y140412D02*
X239639Y140138D01*
G01X239655Y140429D02*
X239649Y140412D01*
G01X239660Y140365D02*
X239655Y140429D01*
G01X239648Y141390D02*
X239634Y141024D01*
G01X239655Y141412D02*
X239648Y141390D01*
G01X239662Y141327D02*
X239655Y141412D01*
G01X239726Y139853D02*
X239713Y140340D01*
G01X239732Y139464D02*
X239726Y139853D01*
G01X239737Y138993D02*
X239732Y139464D01*
G01X239742Y138453D02*
X239737Y138993D01*
G01X239745Y137857D02*
X239742Y138453D01*
G01X239747Y137224D02*
X239745Y137857D01*
G01X239747Y136570D02*
Y137224D01*
G01X239752Y134700D02*
X239760Y134627D01*
G01X239749Y134830D02*
X239752Y134700D01*
G01X239745Y135018D02*
X239749Y134830D01*
G01X239742Y135257D02*
X239745Y135018D01*
G01X239740Y135540D02*
X239742Y135257D01*
G01X239738Y135857D02*
X239740Y135540D01*
G01X239737Y136198D02*
X239738Y135857D01*
G01X239736Y136551D02*
X239737Y136198D01*
G01X239721Y139013D02*
X239711Y139379D01*
G01X239725Y138722D02*
X239721Y139013D01*
G01X239729Y138368D02*
X239725Y138722D01*
G01X239732Y137963D02*
X239729Y138368D01*
G01X239734Y137516D02*
X239732Y137963D01*
G01X239736Y137041D02*
X239734Y137516D01*
G01X239736Y136551D02*
Y137041D01*
G01X241367Y140412D02*
X241356Y140365D01*
G01X241372Y140314D02*
X241367Y140412D01*
G01X241378Y140138D02*
X241372Y140314D01*
G01X241282Y137516D02*
X241280Y136551D01*
G01X241284Y137963D02*
X241282Y137516D01*
G01X241287Y138368D02*
X241284Y137963D01*
G01X241291Y138722D02*
X241287Y138368D01*
G01X241296Y139013D02*
X241291Y138722D01*
G01X241300Y139234D02*
X241296Y139013D01*
G01X241306Y139379D02*
X241300Y139234D01*
G01X241278Y135857D02*
X241280Y136551D01*
G01X241276Y135540D02*
X241278Y135857D01*
G01X241274Y135257D02*
X241276Y135540D01*
G01X241271Y135018D02*
X241274Y135257D01*
G01X241268Y134830D02*
X241271Y135018D01*
G01X241264Y134700D02*
X241268Y134830D01*
G01X241260Y134632D02*
X241264Y134700D01*
G01X241256Y134627D02*
X241260Y134632D01*
G01X241272Y137857D02*
X241269Y136570D01*
G01X241275Y138453D02*
X241272Y137857D01*
G01X241279Y138993D02*
X241275Y138453D01*
G01X241284Y139464D02*
X241279Y138993D01*
G01X241290Y139853D02*
X241284Y139464D01*
G01X241296Y140148D02*
X241290Y139853D01*
G01X241303Y140340D02*
X241296Y140148D01*
G01X241368Y141390D02*
X241354Y141327D01*
G01X241375Y141259D02*
X241368Y141390D01*
G01X241382Y141024D02*
X241375Y141259D01*
G01X235717Y145965D02*
X235728Y146012D01*
G01X235711Y146063D02*
X235717Y145965D01*
G01X235706Y146239D02*
X235711Y146063D01*
G01X235802Y148861D02*
X235804Y149826D01*
G01X235800Y148414D02*
X235802Y148861D01*
G01X235797Y148009D02*
X235800Y148414D01*
G01X235793Y147656D02*
X235797Y148009D01*
G01X235788Y147364D02*
X235793Y147656D01*
G01X235783Y147143D02*
X235788Y147364D01*
G01X235778Y146999D02*
X235783Y147143D01*
G01X235812Y148520D02*
X235815Y149807D01*
G01X235809Y147925D02*
X235812Y148520D01*
G01X235805Y147384D02*
X235809Y147925D01*
G01X235800Y146913D02*
X235805Y147384D01*
G01X235794Y146524D02*
X235800Y146913D01*
G01X235788Y146230D02*
X235794Y146524D01*
G01X235781Y146037D02*
X235788Y146230D01*
G01X235716Y144988D02*
X235730Y145050D01*
G01X235708Y145118D02*
X235716Y144988D01*
G01X235702Y145353D02*
X235708Y145118D01*
G01X237435Y145965D02*
X237445Y146239D01*
G01X237429Y145948D02*
X237435Y145965D01*
G01X237424Y146012D02*
X237429Y145948D01*
G01X237436Y144988D02*
X237450Y145353D01*
G01X237429Y144965D02*
X237436Y144988D01*
G01X237421Y145050D02*
X237429Y144965D01*
G01X237357Y146524D02*
X237371Y146037D01*
G01X237352Y146913D02*
X237357Y146524D01*
G01X237346Y147384D02*
X237352Y146913D01*
G01X237342Y147925D02*
X237346Y147384D01*
G01X237339Y148520D02*
X237342Y147925D01*
G01X237337Y149153D02*
X237339Y148520D01*
G01X237336Y149807D02*
X237337Y149153D01*
G01X237363Y147364D02*
X237373Y146999D01*
G01X237359Y147656D02*
X237363Y147364D01*
G01X237355Y148009D02*
X237359Y147656D01*
G01X237352Y148414D02*
X237355Y148009D01*
G01X237349Y148861D02*
X237352Y148414D01*
G01X237348Y149336D02*
X237349Y148861D01*
G01X237347Y149826D02*
X237348Y149336D01*
G01X237435Y140412D02*
X237424Y140365D01*
G01X237440Y140314D02*
X237435Y140412D01*
G01X237445Y140138D02*
X237440Y140314D01*
G01X237349Y137516D02*
X237347Y136551D01*
G01X237352Y137963D02*
X237349Y137516D01*
G01X237355Y138368D02*
X237352Y137963D01*
G01X237359Y138722D02*
X237355Y138368D01*
G01X237363Y139013D02*
X237359Y138722D01*
G01X237368Y139234D02*
X237363Y139013D01*
G01X237373Y139379D02*
X237368Y139234D01*
G01X237339Y137857D02*
X237336Y136570D01*
G01X237342Y138453D02*
X237339Y137857D01*
G01X237346Y138993D02*
X237342Y138453D01*
G01X237352Y139464D02*
X237346Y138993D01*
G01X237357Y139853D02*
X237352Y139464D01*
G01X237364Y140148D02*
X237357Y139853D01*
G01X237371Y140340D02*
X237364Y140148D01*
G01X237436Y141390D02*
X237421Y141327D01*
G01X237443Y141259D02*
X237436Y141390D01*
G01X237450Y141024D02*
X237443Y141259D01*
G01X235717Y140412D02*
X235706Y140138D01*
G01X235722Y140429D02*
X235717Y140412D01*
G01X235728Y140365D02*
X235722Y140429D01*
G01X235716Y141390D02*
X235702Y141024D01*
G01X235723Y141412D02*
X235716Y141390D01*
G01X235730Y141327D02*
X235723Y141412D01*
G01X235794Y139853D02*
X235781Y140340D01*
G01X235800Y139464D02*
X235794Y139853D01*
G01X235805Y138993D02*
X235800Y139464D01*
G01X235809Y138453D02*
X235805Y138993D01*
G01X235812Y137857D02*
X235809Y138453D01*
G01X235814Y137224D02*
X235812Y137857D01*
G01X235815Y136570D02*
X235814Y137224D01*
G01X235788Y139013D02*
X235778Y139379D01*
G01X235793Y138722D02*
X235788Y139013D01*
G01X235797Y138368D02*
X235793Y138722D01*
G01X235800Y137963D02*
X235797Y138368D01*
G01X235802Y137516D02*
X235800Y137963D01*
G01X235804Y137041D02*
X235802Y137516D01*
G01X235804Y136551D02*
Y137041D01*
G01X233502Y145965D02*
X233513Y146239D01*
G01X233497Y145948D02*
X233502Y145965D01*
G01X233491Y146012D02*
X233497Y145948D01*
G01X233504Y144988D02*
X233518Y145353D01*
G01X233496Y144965D02*
X233504Y144988D01*
G01X233489Y145050D02*
X233496Y144965D01*
G01X233425Y146524D02*
X233439Y146037D01*
G01X233419Y146913D02*
X233425Y146524D01*
G01X233414Y147384D02*
X233419Y146913D01*
G01X233410Y147925D02*
X233414Y147384D01*
G01X233407Y148520D02*
X233410Y147925D01*
G01X233405Y149153D02*
X233407Y148520D01*
G01X233404Y149807D02*
X233405Y149153D01*
G01X233399Y151677D02*
X233391Y151750D01*
G01X233403Y151547D02*
X233399Y151677D01*
G01X233406Y151359D02*
X233403Y151547D01*
G01X233409Y151120D02*
X233406Y151359D01*
G01X233412Y150838D02*
X233409Y151120D01*
G01X233414Y150521D02*
X233412Y150838D01*
G01X233415Y150180D02*
X233414Y150521D01*
G01X233415Y149826D02*
Y150180D01*
G01X233431Y147364D02*
X233441Y146999D01*
G01X233426Y147656D02*
X233431Y147364D01*
G01X233423Y148009D02*
X233426Y147656D01*
G01X233419Y148414D02*
X233423Y148009D01*
G01X233417Y148861D02*
X233419Y148414D01*
G01X233416Y149336D02*
X233417Y148861D01*
G01X233415Y149826D02*
X233416Y149336D01*
G01X231784Y145965D02*
X231795Y146012D01*
G01X231779Y146063D02*
X231784Y145965D01*
G01X231774Y146239D02*
X231779Y146063D01*
G01X231870Y148861D02*
X231872Y149826D01*
G01X231867Y148414D02*
X231870Y148861D01*
G01X231864Y148009D02*
X231867Y148414D01*
G01X231860Y147656D02*
X231864Y148009D01*
G01X231856Y147364D02*
X231860Y147656D01*
G01X231851Y147143D02*
X231856Y147364D01*
G01X231846Y146999D02*
X231851Y147143D01*
G01X231873Y150521D02*
X231872Y149826D01*
G01X231875Y150838D02*
X231873Y150521D01*
G01X231878Y151120D02*
X231875Y150838D01*
G01X231880Y151359D02*
X231878Y151120D01*
G01X231884Y151547D02*
X231880Y151359D01*
G01X231888Y151677D02*
X231884Y151547D01*
G01X231891Y151746D02*
X231888Y151677D01*
G01X231895Y151750D02*
X231891Y151746D01*
G01X231880Y148520D02*
X231883Y149807D01*
G01X231877Y147925D02*
X231880Y148520D01*
G01X231873Y147384D02*
X231877Y147925D01*
G01X231868Y146913D02*
X231873Y147384D01*
G01X231862Y146524D02*
X231868Y146913D01*
G01X231855Y146230D02*
X231862Y146524D01*
G01X231848Y146037D02*
X231855Y146230D01*
G01X231783Y144988D02*
X231798Y145050D01*
G01X231776Y145118D02*
X231783Y144988D01*
G01X231769Y145353D02*
X231776Y145118D01*
G01X231775Y140412D02*
X231765Y140138D01*
G01X231781Y140429D02*
X231775Y140412D01*
G01X231786Y140365D02*
X231781Y140429D01*
G01X231774Y141390D02*
X231760Y141024D01*
G01X231781Y141412D02*
X231774Y141390D01*
G01X231788Y141327D02*
X231781Y141412D01*
G01X231852Y139853D02*
X231839Y140340D01*
G01X231858Y139464D02*
X231852Y139853D01*
G01X231863Y138993D02*
X231858Y139464D01*
G01X231868Y138453D02*
X231863Y138993D01*
G01X231871Y137857D02*
X231868Y138453D01*
G01X231873Y137224D02*
X231871Y137857D01*
G01X231873Y136570D02*
Y137224D01*
G01X231878Y134700D02*
X231886Y134627D01*
G01X231875Y134830D02*
X231878Y134700D01*
G01X231871Y135018D02*
X231875Y134830D01*
G01X231868Y135257D02*
X231871Y135018D01*
G01X231866Y135540D02*
X231868Y135257D01*
G01X231864Y135857D02*
X231866Y135540D01*
G01X231863Y136198D02*
X231864Y135857D01*
G01X231862Y136551D02*
X231863Y136198D01*
G01X231847Y139013D02*
X231837Y139379D01*
G01X231851Y138722D02*
X231847Y139013D01*
G01X231855Y138368D02*
X231851Y138722D01*
G01X231858Y137963D02*
X231855Y138368D01*
G01X231860Y137516D02*
X231858Y137963D01*
G01X231862Y137041D02*
X231860Y137516D01*
G01X231862Y136551D02*
Y137041D01*
G01X233493Y140412D02*
X233482Y140365D01*
G01X233498Y140314D02*
X233493Y140412D01*
G01X233503Y140138D02*
X233498Y140314D01*
G01X233408Y137516D02*
X233406Y136551D01*
G01X233410Y137963D02*
X233408Y137516D01*
G01X233413Y138368D02*
X233410Y137963D01*
G01X233417Y138722D02*
X233413Y138368D01*
G01X233422Y139013D02*
X233417Y138722D01*
G01X233426Y139234D02*
X233422Y139013D01*
G01X233432Y139379D02*
X233426Y139234D01*
G01X233404Y135857D02*
X233406Y136551D01*
G01X233402Y135540D02*
X233404Y135857D01*
G01X233400Y135257D02*
X233402Y135540D01*
G01X233397Y135018D02*
X233400Y135257D01*
G01X233394Y134830D02*
X233397Y135018D01*
G01X233390Y134700D02*
X233394Y134830D01*
G01X233386Y134632D02*
X233390Y134700D01*
G01X233382Y134627D02*
X233386Y134632D01*
G01X233398Y137857D02*
X233395Y136570D01*
G01X233401Y138453D02*
X233398Y137857D01*
G01X233405Y138993D02*
X233401Y138453D01*
G01X233410Y139464D02*
X233405Y138993D01*
G01X233416Y139853D02*
X233410Y139464D01*
G01X233422Y140148D02*
X233416Y139853D01*
G01X233429Y140340D02*
X233422Y140148D01*
G01X233494Y141390D02*
X233480Y141327D01*
G01X233501Y141259D02*
X233494Y141390D01*
G01X233508Y141024D02*
X233501Y141259D01*
G01X227843Y145965D02*
X227854Y146012D01*
G01X227837Y146063D02*
X227843Y145965D01*
G01X227832Y146239D02*
X227837Y146063D01*
G01X227928Y148861D02*
X227930Y149826D01*
G01X227926Y148414D02*
X227928Y148861D01*
G01X227923Y148009D02*
X227926Y148414D01*
G01X227919Y147656D02*
X227923Y148009D01*
G01X227914Y147364D02*
X227919Y147656D01*
G01X227909Y147143D02*
X227914Y147364D01*
G01X227904Y146999D02*
X227909Y147143D01*
G01X227938Y148520D02*
X227941Y149807D01*
G01X227935Y147925D02*
X227938Y148520D01*
G01X227931Y147384D02*
X227935Y147925D01*
G01X227926Y146913D02*
X227931Y147384D01*
G01X227920Y146524D02*
X227926Y146913D01*
G01X227913Y146230D02*
X227920Y146524D01*
G01X227907Y146037D02*
X227913Y146230D01*
G01X227842Y144988D02*
X227856Y145050D01*
G01X227834Y145118D02*
X227842Y144988D01*
G01X227828Y145353D02*
X227834Y145118D01*
G01X229561Y145965D02*
X229571Y146239D01*
G01X229555Y145948D02*
X229561Y145965D01*
G01X229550Y146012D02*
X229555Y145948D01*
G01X229562Y144988D02*
X229576Y145353D01*
G01X229555Y144965D02*
X229562Y144988D01*
G01X229547Y145050D02*
X229555Y144965D01*
G01X229483Y146524D02*
X229497Y146037D01*
G01X229478Y146913D02*
X229483Y146524D01*
G01X229472Y147384D02*
X229478Y146913D01*
G01X229468Y147925D02*
X229472Y147384D01*
G01X229465Y148520D02*
X229468Y147925D01*
G01X229463Y149153D02*
X229465Y148520D01*
G01X229462Y149807D02*
X229463Y149153D01*
G01X229489Y147364D02*
X229499Y146999D01*
G01X229485Y147656D02*
X229489Y147364D01*
G01X229481Y148009D02*
X229485Y147656D01*
G01X229478Y148414D02*
X229481Y148009D01*
G01X229475Y148861D02*
X229478Y148414D01*
G01X229474Y149336D02*
X229475Y148861D01*
G01X229473Y149826D02*
X229474Y149336D01*
G01X229561Y140412D02*
X229550Y140365D01*
G01X229566Y140314D02*
X229561Y140412D01*
G01X229571Y140138D02*
X229566Y140314D01*
G01X229475Y137516D02*
X229473Y136551D01*
G01X229478Y137963D02*
X229475Y137516D01*
G01X229481Y138368D02*
X229478Y137963D01*
G01X229485Y138722D02*
X229481Y138368D01*
G01X229489Y139013D02*
X229485Y138722D01*
G01X229494Y139234D02*
X229489Y139013D01*
G01X229499Y139379D02*
X229494Y139234D01*
G01X229465Y137857D02*
X229462Y136570D01*
G01X229468Y138453D02*
X229465Y137857D01*
G01X229472Y138993D02*
X229468Y138453D01*
G01X229478Y139464D02*
X229472Y138993D01*
G01X229483Y139853D02*
X229478Y139464D01*
G01X229490Y140148D02*
X229483Y139853D01*
G01X229497Y140340D02*
X229490Y140148D01*
G01X229562Y141390D02*
X229547Y141327D01*
G01X229569Y141259D02*
X229562Y141390D01*
G01X229576Y141024D02*
X229569Y141259D01*
G01X227843Y140412D02*
X227832Y140138D01*
G01X227848Y140429D02*
X227843Y140412D01*
G01X227854Y140365D02*
X227848Y140429D01*
G01X227842Y141390D02*
X227828Y141024D01*
G01X227849Y141412D02*
X227842Y141390D01*
G01X227856Y141327D02*
X227849Y141412D01*
G01X227920Y139853D02*
X227907Y140340D01*
G01X227926Y139464D02*
X227920Y139853D01*
G01X227931Y138993D02*
X227926Y139464D01*
G01X227935Y138453D02*
X227931Y138993D01*
G01X227938Y137857D02*
X227935Y138453D01*
G01X227940Y137224D02*
X227938Y137857D01*
G01X227941Y136570D02*
X227940Y137224D01*
G01X227914Y139013D02*
X227904Y139379D01*
G01X227919Y138722D02*
X227914Y139013D01*
G01X227923Y138368D02*
X227919Y138722D01*
G01X227926Y137963D02*
X227923Y138368D01*
G01X227928Y137516D02*
X227926Y137963D01*
G01X227929Y137041D02*
X227928Y137516D01*
G01X227930Y136551D02*
X227929Y137041D01*
G01X225628Y145965D02*
X225639Y146239D01*
G01X225623Y145948D02*
X225628Y145965D01*
G01X225617Y146012D02*
X225623Y145948D01*
G01X225630Y144988D02*
X225644Y145353D01*
G01X225622Y144965D02*
X225630Y144988D01*
G01X225615Y145050D02*
X225622Y144965D01*
G01X225551Y146524D02*
X225565Y146037D01*
G01X225545Y146913D02*
X225551Y146524D01*
G01X225540Y147384D02*
X225545Y146913D01*
G01X225536Y147925D02*
X225540Y147384D01*
G01X225533Y148520D02*
X225536Y147925D01*
G01X225531Y149153D02*
X225533Y148520D01*
G01X225530Y149807D02*
X225531Y149153D01*
G01X225525Y151677D02*
X225517Y151750D01*
G01X225529Y151547D02*
X225525Y151677D01*
G01X225532Y151359D02*
X225529Y151547D01*
G01X225535Y151120D02*
X225532Y151359D01*
G01X225538Y150838D02*
X225535Y151120D01*
G01X225540Y150521D02*
X225538Y150838D01*
G01X225541Y150180D02*
X225540Y150521D01*
G01X225541Y149826D02*
Y150180D01*
G01X225557Y147364D02*
X225567Y146999D01*
G01X225552Y147656D02*
X225557Y147364D01*
G01X225549Y148009D02*
X225552Y147656D01*
G01X225545Y148414D02*
X225549Y148009D01*
G01X225543Y148861D02*
X225545Y148414D01*
G01X225542Y149336D02*
X225543Y148861D01*
G01X225541Y149826D02*
X225542Y149336D01*
G01X223910Y145965D02*
X223921Y146012D01*
G01X223905Y146063D02*
X223910Y145965D01*
G01X223900Y146239D02*
X223905Y146063D01*
G01X223996Y148861D02*
X223998Y149826D01*
G01X223993Y148414D02*
X223996Y148861D01*
G01X223990Y148009D02*
X223993Y148414D01*
G01X223986Y147656D02*
X223990Y148009D01*
G01X223982Y147364D02*
X223986Y147656D01*
G01X223977Y147143D02*
X223982Y147364D01*
G01X223972Y146999D02*
X223977Y147143D01*
G01X223999Y150521D02*
X223998Y149826D01*
G01X224001Y150838D02*
X223999Y150521D01*
G01X224004Y151120D02*
X224001Y150838D01*
G01X224006Y151359D02*
X224004Y151120D01*
G01X224010Y151547D02*
X224006Y151359D01*
G01X224014Y151677D02*
X224010Y151547D01*
G01X224017Y151746D02*
X224014Y151677D01*
G01X224021Y151750D02*
X224017Y151746D01*
G01X224006Y148520D02*
X224009Y149807D01*
G01X224003Y147925D02*
X224006Y148520D01*
G01X223999Y147384D02*
X224003Y147925D01*
G01X223994Y146913D02*
X223999Y147384D01*
G01X223988Y146524D02*
X223994Y146913D01*
G01X223981Y146230D02*
X223988Y146524D01*
G01X223974Y146037D02*
X223981Y146230D01*
G01X223909Y144988D02*
X223924Y145050D01*
G01X223902Y145118D02*
X223909Y144988D01*
G01X223895Y145353D02*
X223902Y145118D01*
G01X223901Y140412D02*
X223891Y140138D01*
G01X223907Y140429D02*
X223901Y140412D01*
G01X223912Y140365D02*
X223907Y140429D01*
G01X223900Y141390D02*
X223886Y141024D01*
G01X223907Y141412D02*
X223900Y141390D01*
G01X223914Y141327D02*
X223907Y141412D01*
G01X223978Y139853D02*
X223965Y140340D01*
G01X223984Y139464D02*
X223978Y139853D01*
G01X223989Y138993D02*
X223984Y139464D01*
G01X223994Y138453D02*
X223989Y138993D01*
G01X223997Y137857D02*
X223994Y138453D01*
G01X223999Y137224D02*
X223997Y137857D01*
G01X223999Y136570D02*
Y137224D01*
G01X224004Y134700D02*
X224012Y134627D01*
G01X224000Y134830D02*
X224004Y134700D01*
G01X223997Y135018D02*
X224000Y134830D01*
G01X223994Y135257D02*
X223997Y135018D01*
G01X223992Y135540D02*
X223994Y135257D01*
G01X223990Y135857D02*
X223992Y135540D01*
G01X223989Y136198D02*
X223990Y135857D01*
G01X223988Y136551D02*
X223989Y136198D01*
G01X223973Y139013D02*
X223962Y139379D01*
G01X223977Y138722D02*
X223973Y139013D01*
G01X223981Y138368D02*
X223977Y138722D01*
G01X223984Y137963D02*
X223981Y138368D01*
G01X223986Y137516D02*
X223984Y137963D01*
G01X223988Y137041D02*
X223986Y137516D01*
G01X223988Y136551D02*
Y137041D01*
G01X225619Y140412D02*
X225608Y140365D01*
G01X225624Y140314D02*
X225619Y140412D01*
G01X225629Y140138D02*
X225624Y140314D01*
G01X225534Y137516D02*
X225532Y136551D01*
G01X225536Y137963D02*
X225534Y137516D01*
G01X225539Y138368D02*
X225536Y137963D01*
G01X225543Y138722D02*
X225539Y138368D01*
G01X225547Y139013D02*
X225543Y138722D01*
G01X225552Y139234D02*
X225547Y139013D01*
G01X225558Y139379D02*
X225552Y139234D01*
G01X225530Y135857D02*
X225532Y136551D01*
G01X225528Y135540D02*
X225530Y135857D01*
G01X225526Y135257D02*
X225528Y135540D01*
G01X225523Y135018D02*
X225526Y135257D01*
G01X225520Y134830D02*
X225523Y135018D01*
G01X225516Y134700D02*
X225520Y134830D01*
G01X225512Y134632D02*
X225516Y134700D01*
G01X225508Y134627D02*
X225512Y134632D01*
G01X225523Y137857D02*
X225521Y136570D01*
G01X225527Y138453D02*
X225523Y137857D01*
G01X225531Y138993D02*
X225527Y138453D01*
G01X225536Y139464D02*
X225531Y138993D01*
G01X225542Y139853D02*
X225536Y139464D01*
G01X225548Y140148D02*
X225542Y139853D01*
G01X225555Y140340D02*
X225548Y140148D01*
G01X225620Y141390D02*
X225606Y141327D01*
G01X225627Y141259D02*
X225620Y141390D01*
G01X225634Y141024D02*
X225627Y141259D01*
G01X219969Y145965D02*
X219980Y146012D01*
G01X219963Y146063D02*
X219969Y145965D01*
G01X219958Y146239D02*
X219963Y146063D01*
G01X220054Y148861D02*
X220056Y149826D01*
G01X220052Y148414D02*
X220054Y148861D01*
G01X220049Y148009D02*
X220052Y148414D01*
G01X220045Y147656D02*
X220049Y148009D01*
G01X220040Y147364D02*
X220045Y147656D01*
G01X220035Y147143D02*
X220040Y147364D01*
G01X220030Y146999D02*
X220035Y147143D01*
G01X220064Y148520D02*
X220067Y149807D01*
G01X220061Y147925D02*
X220064Y148520D01*
G01X220057Y147384D02*
X220061Y147925D01*
G01X220052Y146913D02*
X220057Y147384D01*
G01X220046Y146524D02*
X220052Y146913D01*
G01X220039Y146230D02*
X220046Y146524D01*
G01X220032Y146037D02*
X220039Y146230D01*
G01X219967Y144988D02*
X219982Y145050D01*
G01X219960Y145118D02*
X219967Y144988D01*
G01X219954Y145353D02*
X219960Y145118D01*
G01X221687Y145965D02*
X221697Y146239D01*
G01X221681Y145948D02*
X221687Y145965D01*
G01X221676Y146012D02*
X221681Y145948D01*
G01X221688Y144988D02*
X221702Y145353D01*
G01X221681Y144965D02*
X221688Y144988D01*
G01X221673Y145050D02*
X221681Y144965D01*
G01X221609Y146524D02*
X221623Y146037D01*
G01X221604Y146913D02*
X221609Y146524D01*
G01X221598Y147384D02*
X221604Y146913D01*
G01X221594Y147925D02*
X221598Y147384D01*
G01X221591Y148520D02*
X221594Y147925D01*
G01X221589Y149153D02*
X221591Y148520D01*
G01X221588Y149807D02*
X221589Y149153D01*
G01X221615Y147364D02*
X221625Y146999D01*
G01X221611Y147656D02*
X221615Y147364D01*
G01X221607Y148009D02*
X221611Y147656D01*
G01X221604Y148414D02*
X221607Y148009D01*
G01X221601Y148861D02*
X221604Y148414D01*
G01X221600Y149336D02*
X221601Y148861D01*
G01X221599Y149826D02*
X221600Y149336D01*
G01X221687Y140412D02*
X221676Y140365D01*
G01X221692Y140314D02*
X221687Y140412D01*
G01X221697Y140138D02*
X221692Y140314D01*
G01X221601Y137516D02*
X221599Y136551D01*
G01X221604Y137963D02*
X221601Y137516D01*
G01X221607Y138368D02*
X221604Y137963D01*
G01X221611Y138722D02*
X221607Y138368D01*
G01X221615Y139013D02*
X221611Y138722D01*
G01X221620Y139234D02*
X221615Y139013D01*
G01X221625Y139379D02*
X221620Y139234D01*
G01X221591Y137857D02*
X221588Y136570D01*
G01X221594Y138453D02*
X221591Y137857D01*
G01X221598Y138993D02*
X221594Y138453D01*
G01X221604Y139464D02*
X221598Y138993D01*
G01X221609Y139853D02*
X221604Y139464D01*
G01X221616Y140148D02*
X221609Y139853D01*
G01X221623Y140340D02*
X221616Y140148D01*
G01X221688Y141390D02*
X221673Y141327D01*
G01X221695Y141259D02*
X221688Y141390D01*
G01X221702Y141024D02*
X221695Y141259D01*
G01X219969Y140412D02*
X219958Y140138D01*
G01X219974Y140429D02*
X219969Y140412D01*
G01X219980Y140365D02*
X219974Y140429D01*
G01X219967Y141390D02*
X219954Y141024D01*
G01X219975Y141412D02*
X219967Y141390D01*
G01X219982Y141327D02*
X219975Y141412D01*
G01X220046Y139853D02*
X220032Y140340D01*
G01X220052Y139464D02*
X220046Y139853D01*
G01X220057Y138993D02*
X220052Y139464D01*
G01X220061Y138453D02*
X220057Y138993D01*
G01X220064Y137857D02*
X220061Y138453D01*
G01X220066Y137224D02*
X220064Y137857D01*
G01X220067Y136570D02*
X220066Y137224D01*
G01X220040Y139013D02*
X220030Y139379D01*
G01X220045Y138722D02*
X220040Y139013D01*
G01X220049Y138368D02*
X220045Y138722D01*
G01X220052Y137963D02*
X220049Y138368D01*
G01X220054Y137516D02*
X220052Y137963D01*
G01X220055Y137041D02*
X220054Y137516D01*
G01X220056Y136551D02*
X220055Y137041D01*
G01X217754Y145965D02*
X217765Y146239D01*
G01X217749Y145948D02*
X217754Y145965D01*
G01X217743Y146012D02*
X217749Y145948D01*
G01X217756Y144988D02*
X217770Y145353D01*
G01X217748Y144965D02*
X217756Y144988D01*
G01X217741Y145050D02*
X217748Y144965D01*
G01X217677Y146524D02*
X217691Y146037D01*
G01X217671Y146913D02*
X217677Y146524D01*
G01X217666Y147384D02*
X217671Y146913D01*
G01X217662Y147925D02*
X217666Y147384D01*
G01X217659Y148520D02*
X217662Y147925D01*
G01X217657Y149153D02*
X217659Y148520D01*
G01X217656Y149807D02*
X217657Y149153D01*
G01X217651Y151677D02*
X217643Y151750D01*
G01X217655Y151547D02*
X217651Y151677D01*
G01X217658Y151359D02*
X217655Y151547D01*
G01X217661Y151120D02*
X217658Y151359D01*
G01X217664Y150838D02*
X217661Y151120D01*
G01X217665Y150521D02*
X217664Y150838D01*
G01X217667Y150180D02*
X217665Y150521D01*
G01X217667Y149826D02*
Y150180D01*
G01X217683Y147364D02*
X217693Y146999D01*
G01X217678Y147656D02*
X217683Y147364D01*
G01X217675Y148009D02*
X217678Y147656D01*
G01X217671Y148414D02*
X217675Y148009D01*
G01X217669Y148861D02*
X217671Y148414D01*
G01X217668Y149336D02*
X217669Y148861D01*
G01X217667Y149826D02*
X217668Y149336D01*
G01X216036Y145965D02*
X216047Y146012D01*
G01X216031Y146063D02*
X216036Y145965D01*
G01X216026Y146239D02*
X216031Y146063D01*
G01X216122Y148861D02*
X216124Y149826D01*
G01X216119Y148414D02*
X216122Y148861D01*
G01X216116Y148009D02*
X216119Y148414D01*
G01X216112Y147656D02*
X216116Y148009D01*
G01X216108Y147364D02*
X216112Y147656D01*
G01X216103Y147143D02*
X216108Y147364D01*
G01X216098Y146999D02*
X216103Y147143D01*
G01X216125Y150521D02*
X216124Y149826D01*
G01X216127Y150838D02*
X216125Y150521D01*
G01X216130Y151120D02*
X216127Y150838D01*
G01X216132Y151359D02*
X216130Y151120D01*
G01X216136Y151547D02*
X216132Y151359D01*
G01X216140Y151677D02*
X216136Y151547D01*
G01X216143Y151746D02*
X216140Y151677D01*
G01X216147Y151750D02*
X216143Y151746D01*
G01X216132Y148520D02*
X216135Y149807D01*
G01X216129Y147925D02*
X216132Y148520D01*
G01X216125Y147384D02*
X216129Y147925D01*
G01X216120Y146913D02*
X216125Y147384D01*
G01X216114Y146524D02*
X216120Y146913D01*
G01X216107Y146230D02*
X216114Y146524D01*
G01X216100Y146037D02*
X216107Y146230D01*
G01X216035Y144988D02*
X216050Y145050D01*
G01X216028Y145118D02*
X216035Y144988D01*
G01X216021Y145353D02*
X216028Y145118D01*
G01X216027Y140412D02*
X216017Y140138D01*
G01X216033Y140429D02*
X216027Y140412D01*
G01X216038Y140365D02*
X216033Y140429D01*
G01X216026Y141390D02*
X216012Y141024D01*
G01X216033Y141412D02*
X216026Y141390D01*
G01X216040Y141327D02*
X216033Y141412D01*
G01X216104Y139853D02*
X216091Y140340D01*
G01X216110Y139464D02*
X216104Y139853D01*
G01X216115Y138993D02*
X216110Y139464D01*
G01X216120Y138453D02*
X216115Y138993D01*
G01X216123Y137857D02*
X216120Y138453D01*
G01X216125Y137224D02*
X216123Y137857D01*
G01X216125Y136570D02*
Y137224D01*
G01X216130Y134700D02*
X216138Y134627D01*
G01X216126Y134830D02*
X216130Y134700D01*
G01X216123Y135018D02*
X216126Y134830D01*
G01X216120Y135257D02*
X216123Y135018D01*
G01X216118Y135540D02*
X216120Y135257D01*
G01X216116Y135857D02*
X216118Y135540D01*
G01X216115Y136198D02*
X216116Y135857D01*
G01X216114Y136551D02*
X216115Y136198D01*
G01X216099Y139013D02*
X216088Y139379D01*
G01X216103Y138722D02*
X216099Y139013D01*
G01X216107Y138368D02*
X216103Y138722D01*
G01X216110Y137963D02*
X216107Y138368D01*
G01X216112Y137516D02*
X216110Y137963D01*
G01X216114Y137041D02*
X216112Y137516D01*
G01X216114Y136551D02*
Y137041D01*
G01X217745Y140412D02*
X217734Y140365D01*
G01X217750Y140314D02*
X217745Y140412D01*
G01X217755Y140138D02*
X217750Y140314D01*
G01X217660Y137516D02*
X217658Y136551D01*
G01X217662Y137963D02*
X217660Y137516D01*
G01X217665Y138368D02*
X217662Y137963D01*
G01X217669Y138722D02*
X217665Y138368D01*
G01X217673Y139013D02*
X217669Y138722D01*
G01X217678Y139234D02*
X217673Y139013D01*
G01X217684Y139379D02*
X217678Y139234D01*
G01X217656Y135857D02*
X217658Y136551D01*
G01X217654Y135540D02*
X217656Y135857D01*
G01X217652Y135257D02*
X217654Y135540D01*
G01X217649Y135018D02*
X217652Y135257D01*
G01X217646Y134830D02*
X217649Y135018D01*
G01X217642Y134700D02*
X217646Y134830D01*
G01X217638Y134632D02*
X217642Y134700D01*
G01X217634Y134627D02*
X217638Y134632D01*
G01X217649Y137857D02*
X217647Y136570D01*
G01X217653Y138453D02*
X217649Y137857D01*
G01X217657Y138993D02*
X217653Y138453D01*
G01X217662Y139464D02*
X217657Y138993D01*
G01X217668Y139853D02*
X217662Y139464D01*
G01X217674Y140148D02*
X217668Y139853D01*
G01X217681Y140340D02*
X217674Y140148D01*
G01X217746Y141390D02*
X217732Y141327D01*
G01X217753Y141259D02*
X217746Y141390D01*
G01X217760Y141024D02*
X217753Y141259D01*
G01X212095Y145965D02*
X212106Y146012D01*
G01X212089Y146063D02*
X212095Y145965D01*
G01X212084Y146239D02*
X212089Y146063D01*
G01X212180Y148861D02*
X212182Y149826D01*
G01X212178Y148414D02*
X212180Y148861D01*
G01X212175Y148009D02*
X212178Y148414D01*
G01X212171Y147656D02*
X212175Y148009D01*
G01X212166Y147364D02*
X212171Y147656D01*
G01X212161Y147143D02*
X212166Y147364D01*
G01X212156Y146999D02*
X212161Y147143D01*
G01X212190Y148520D02*
X212193Y149807D01*
G01X212187Y147925D02*
X212190Y148520D01*
G01X212183Y147384D02*
X212187Y147925D01*
G01X212178Y146913D02*
X212183Y147384D01*
G01X212172Y146524D02*
X212178Y146913D01*
G01X212165Y146230D02*
X212172Y146524D01*
G01X212158Y146037D02*
X212165Y146230D01*
G01X212093Y144988D02*
X212108Y145050D01*
G01X212086Y145118D02*
X212093Y144988D01*
G01X212080Y145353D02*
X212086Y145118D01*
G01X213813Y145965D02*
X213823Y146239D01*
G01X213807Y145948D02*
X213813Y145965D01*
G01X213802Y146012D02*
X213807Y145948D01*
G01X213814Y144988D02*
X213828Y145353D01*
G01X213807Y144965D02*
X213814Y144988D01*
G01X213799Y145050D02*
X213807Y144965D01*
G01X213735Y146524D02*
X213749Y146037D01*
G01X213730Y146913D02*
X213735Y146524D01*
G01X213724Y147384D02*
X213730Y146913D01*
G01X213720Y147925D02*
X213724Y147384D01*
G01X213717Y148520D02*
X213720Y147925D01*
G01X213715Y149153D02*
X213717Y148520D01*
G01X213714Y149807D02*
X213715Y149153D01*
G01X213741Y147364D02*
X213751Y146999D01*
G01X213737Y147656D02*
X213741Y147364D01*
G01X213733Y148009D02*
X213737Y147656D01*
G01X213730Y148414D02*
X213733Y148009D01*
G01X213727Y148861D02*
X213730Y148414D01*
G01X213726Y149336D02*
X213727Y148861D01*
G01X213725Y149826D02*
X213726Y149336D01*
G01X213813Y140412D02*
X213802Y140365D01*
G01X213818Y140314D02*
X213813Y140412D01*
G01X213823Y140138D02*
X213818Y140314D01*
G01X213727Y137516D02*
X213725Y136551D01*
G01X213730Y137963D02*
X213727Y137516D01*
G01X213733Y138368D02*
X213730Y137963D01*
G01X213737Y138722D02*
X213733Y138368D01*
G01X213741Y139013D02*
X213737Y138722D01*
G01X213746Y139234D02*
X213741Y139013D01*
G01X213751Y139379D02*
X213746Y139234D01*
G01X213717Y137857D02*
X213714Y136570D01*
G01X213720Y138453D02*
X213717Y137857D01*
G01X213724Y138993D02*
X213720Y138453D01*
G01X213730Y139464D02*
X213724Y138993D01*
G01X213735Y139853D02*
X213730Y139464D01*
G01X213742Y140148D02*
X213735Y139853D01*
G01X213749Y140340D02*
X213742Y140148D01*
G01X213814Y141390D02*
X213799Y141327D01*
G01X213821Y141259D02*
X213814Y141390D01*
G01X213828Y141024D02*
X213821Y141259D01*
G01X212095Y140412D02*
X212084Y140138D01*
G01X212100Y140429D02*
X212095Y140412D01*
G01X212106Y140365D02*
X212100Y140429D01*
G01X212093Y141390D02*
X212080Y141024D01*
G01X212101Y141412D02*
X212093Y141390D01*
G01X212108Y141327D02*
X212101Y141412D01*
G01X212172Y139853D02*
X212158Y140340D01*
G01X212178Y139464D02*
X212172Y139853D01*
G01X212183Y138993D02*
X212178Y139464D01*
G01X212187Y138453D02*
X212183Y138993D01*
G01X212190Y137857D02*
X212187Y138453D01*
G01X212192Y137224D02*
X212190Y137857D01*
G01X212193Y136570D02*
X212192Y137224D01*
G01X212166Y139013D02*
X212156Y139379D01*
G01X212171Y138722D02*
X212166Y139013D01*
G01X212175Y138368D02*
X212171Y138722D01*
G01X212178Y137963D02*
X212175Y138368D01*
G01X212180Y137516D02*
X212178Y137963D01*
G01X212181Y137041D02*
X212180Y137516D01*
G01X212182Y136551D02*
X212181Y137041D01*
G01X209880Y145965D02*
X209891Y146239D01*
G01X209875Y145948D02*
X209880Y145965D01*
G01X209869Y146012D02*
X209875Y145948D01*
G01X209882Y144988D02*
X209896Y145353D01*
G01X209874Y144965D02*
X209882Y144988D01*
G01X209867Y145050D02*
X209874Y144965D01*
G01X209803Y146524D02*
X209817Y146037D01*
G01X209797Y146913D02*
X209803Y146524D01*
G01X209792Y147384D02*
X209797Y146913D01*
G01X209788Y147925D02*
X209792Y147384D01*
G01X209785Y148520D02*
X209788Y147925D01*
G01X209783Y149153D02*
X209785Y148520D01*
G01X209782Y149807D02*
X209783Y149153D01*
G01X209777Y151677D02*
X209769Y151750D01*
G01X209781Y151547D02*
X209777Y151677D01*
G01X209784Y151359D02*
X209781Y151547D01*
G01X209787Y151120D02*
X209784Y151359D01*
G01X209790Y150838D02*
X209787Y151120D01*
G01X209791Y150521D02*
X209790Y150838D01*
G01X209793Y150180D02*
X209791Y150521D01*
G01X209793Y149826D02*
Y150180D01*
G01X209809Y147364D02*
X209819Y146999D01*
G01X209804Y147656D02*
X209809Y147364D01*
G01X209801Y148009D02*
X209804Y147656D01*
G01X209797Y148414D02*
X209801Y148009D01*
G01X209795Y148861D02*
X209797Y148414D01*
G01X209794Y149336D02*
X209795Y148861D01*
G01X209793Y149826D02*
X209794Y149336D01*
G01X208162Y145965D02*
X208173Y146012D01*
G01X208157Y146063D02*
X208162Y145965D01*
G01X208152Y146239D02*
X208157Y146063D01*
G01X208248Y148861D02*
X208250Y149826D01*
G01X208245Y148414D02*
X208248Y148861D01*
G01X208242Y148009D02*
X208245Y148414D01*
G01X208238Y147656D02*
X208242Y148009D01*
G01X208234Y147364D02*
X208238Y147656D01*
G01X208229Y147143D02*
X208234Y147364D01*
G01X208224Y146999D02*
X208229Y147143D01*
G01X208251Y150521D02*
X208250Y149826D01*
G01X208253Y150838D02*
X208251Y150521D01*
G01X208255Y151120D02*
X208253Y150838D01*
G01X208258Y151359D02*
X208255Y151120D01*
G01X208262Y151547D02*
X208258Y151359D01*
G01X208265Y151677D02*
X208262Y151547D01*
G01X208269Y151746D02*
X208265Y151677D01*
G01X208273Y151750D02*
X208269Y151746D01*
G01X208258Y148520D02*
X208261Y149807D01*
G01X208255Y147925D02*
X208258Y148520D01*
G01X208251Y147384D02*
X208255Y147925D01*
G01X208246Y146913D02*
X208251Y147384D01*
G01X208240Y146524D02*
X208246Y146913D01*
G01X208233Y146230D02*
X208240Y146524D01*
G01X208226Y146037D02*
X208233Y146230D01*
G01X208161Y144988D02*
X208176Y145050D01*
G01X208154Y145118D02*
X208161Y144988D01*
G01X208147Y145353D02*
X208154Y145118D01*
G01X208153Y140412D02*
X208143Y140138D01*
G01X208159Y140429D02*
X208153Y140412D01*
G01X208164Y140365D02*
X208159Y140429D01*
G01X208152Y141390D02*
X208138Y141024D01*
G01X208159Y141412D02*
X208152Y141390D01*
G01X208166Y141327D02*
X208159Y141412D01*
G01X208230Y139853D02*
X208217Y140340D01*
G01X208236Y139464D02*
X208230Y139853D01*
G01X208241Y138993D02*
X208236Y139464D01*
G01X208246Y138453D02*
X208241Y138993D01*
G01X208249Y137857D02*
X208246Y138453D01*
G01X208251Y137224D02*
X208249Y137857D01*
G01X208251Y136570D02*
Y137224D01*
G01X208256Y134700D02*
X208264Y134627D01*
G01X208252Y134830D02*
X208256Y134700D01*
G01X208249Y135018D02*
X208252Y134830D01*
G01X208246Y135257D02*
X208249Y135018D01*
G01X208244Y135540D02*
X208246Y135257D01*
G01X208242Y135857D02*
X208244Y135540D01*
G01X208241Y136198D02*
X208242Y135857D01*
G01X208240Y136551D02*
X208241Y136198D01*
G01X208225Y139013D02*
X208214Y139379D01*
G01X208229Y138722D02*
X208225Y139013D01*
G01X208233Y138368D02*
X208229Y138722D01*
G01X208236Y137963D02*
X208233Y138368D01*
G01X208238Y137516D02*
X208236Y137963D01*
G01X208240Y137041D02*
X208238Y137516D01*
G01X208240Y136551D02*
Y137041D01*
G01X209871Y140412D02*
X209860Y140365D01*
G01X209876Y140314D02*
X209871Y140412D01*
G01X209881Y140138D02*
X209876Y140314D01*
G01X209786Y137516D02*
X209784Y136551D01*
G01X209788Y137963D02*
X209786Y137516D01*
G01X209791Y138368D02*
X209788Y137963D01*
G01X209795Y138722D02*
X209791Y138368D01*
G01X209799Y139013D02*
X209795Y138722D01*
G01X209804Y139234D02*
X209799Y139013D01*
G01X209810Y139379D02*
X209804Y139234D01*
G01X209782Y135857D02*
X209784Y136551D01*
G01X209780Y135540D02*
X209782Y135857D01*
G01X209778Y135257D02*
X209780Y135540D01*
G01X209775Y135018D02*
X209778Y135257D01*
G01X209772Y134830D02*
X209775Y135018D01*
G01X209768Y134700D02*
X209772Y134830D01*
G01X209764Y134632D02*
X209768Y134700D01*
G01X209760Y134627D02*
X209764Y134632D01*
G01X209775Y137857D02*
X209773Y136570D01*
G01X209779Y138453D02*
X209775Y137857D01*
G01X209783Y138993D02*
X209779Y138453D01*
G01X209788Y139464D02*
X209783Y138993D01*
G01X209794Y139853D02*
X209788Y139464D01*
G01X209800Y140148D02*
X209794Y139853D01*
G01X209807Y140340D02*
X209800Y140148D01*
G01X209872Y141390D02*
X209858Y141327D01*
G01X209879Y141259D02*
X209872Y141390D01*
G01X209886Y141024D02*
X209879Y141259D01*
G01X204221Y145965D02*
X204232Y146012D01*
G01X204215Y146063D02*
X204221Y145965D01*
G01X204210Y146239D02*
X204215Y146063D01*
G01X204306Y148861D02*
X204308Y149826D01*
G01X204304Y148414D02*
X204306Y148861D01*
G01X204301Y148009D02*
X204304Y148414D01*
G01X204297Y147656D02*
X204301Y148009D01*
G01X204292Y147364D02*
X204297Y147656D01*
G01X204287Y147143D02*
X204292Y147364D01*
G01X204282Y146999D02*
X204287Y147143D01*
G01X204316Y148520D02*
X204319Y149807D01*
G01X204313Y147925D02*
X204316Y148520D01*
G01X204309Y147384D02*
X204313Y147925D01*
G01X204304Y146913D02*
X204309Y147384D01*
G01X204298Y146524D02*
X204304Y146913D01*
G01X204291Y146230D02*
X204298Y146524D01*
G01X204284Y146037D02*
X204291Y146230D01*
G01X204219Y144988D02*
X204234Y145050D01*
G01X204212Y145118D02*
X204219Y144988D01*
G01X204206Y145353D02*
X204212Y145118D01*
G01X205939Y145965D02*
X205949Y146239D01*
G01X205933Y145948D02*
X205939Y145965D01*
G01X205928Y146012D02*
X205933Y145948D01*
G01X205940Y144988D02*
X205954Y145353D01*
G01X205933Y144965D02*
X205940Y144988D01*
G01X205925Y145050D02*
X205933Y144965D01*
G01X205861Y146524D02*
X205875Y146037D01*
G01X205855Y146913D02*
X205861Y146524D01*
G01X205850Y147384D02*
X205855Y146913D01*
G01X205846Y147925D02*
X205850Y147384D01*
G01X205843Y148520D02*
X205846Y147925D01*
G01X205841Y149153D02*
X205843Y148520D01*
G01X205840Y149807D02*
X205841Y149153D01*
G01X205867Y147364D02*
X205877Y146999D01*
G01X205863Y147656D02*
X205867Y147364D01*
G01X205859Y148009D02*
X205863Y147656D01*
G01X205856Y148414D02*
X205859Y148009D01*
G01X205853Y148861D02*
X205856Y148414D01*
G01X205852Y149336D02*
X205853Y148861D01*
G01X205851Y149826D02*
X205852Y149336D01*
G01X205939Y140412D02*
X205928Y140365D01*
G01X205944Y140314D02*
X205939Y140412D01*
G01X205949Y140138D02*
X205944Y140314D01*
G01X205853Y137516D02*
X205851Y136551D01*
G01X205856Y137963D02*
X205853Y137516D01*
G01X205859Y138368D02*
X205856Y137963D01*
G01X205863Y138722D02*
X205859Y138368D01*
G01X205867Y139013D02*
X205863Y138722D01*
G01X205872Y139234D02*
X205867Y139013D01*
G01X205877Y139379D02*
X205872Y139234D01*
G01X205843Y137857D02*
X205840Y136570D01*
G01X205846Y138453D02*
X205843Y137857D01*
G01X205850Y138993D02*
X205846Y138453D01*
G01X205855Y139464D02*
X205850Y138993D01*
G01X205861Y139853D02*
X205855Y139464D01*
G01X205868Y140148D02*
X205861Y139853D01*
G01X205875Y140340D02*
X205868Y140148D01*
G01X205940Y141390D02*
X205925Y141327D01*
G01X205947Y141259D02*
X205940Y141390D01*
G01X205954Y141024D02*
X205947Y141259D01*
G01X204221Y140412D02*
X204210Y140138D01*
G01X204226Y140429D02*
X204221Y140412D01*
G01X204232Y140365D02*
X204226Y140429D01*
G01X204219Y141390D02*
X204206Y141024D01*
G01X204227Y141412D02*
X204219Y141390D01*
G01X204234Y141327D02*
X204227Y141412D01*
G01X204298Y139853D02*
X204284Y140340D01*
G01X204304Y139464D02*
X204298Y139853D01*
G01X204309Y138993D02*
X204304Y139464D01*
G01X204313Y138453D02*
X204309Y138993D01*
G01X204316Y137857D02*
X204313Y138453D01*
G01X204318Y137224D02*
X204316Y137857D01*
G01X204319Y136570D02*
X204318Y137224D01*
G01X204292Y139013D02*
X204282Y139379D01*
G01X204297Y138722D02*
X204292Y139013D01*
G01X204301Y138368D02*
X204297Y138722D01*
G01X204304Y137963D02*
X204301Y138368D01*
G01X204306Y137516D02*
X204304Y137963D01*
G01X204307Y137041D02*
X204306Y137516D01*
G01X204308Y136551D02*
X204307Y137041D01*
G01X202006Y145965D02*
X202017Y146239D01*
G01X202001Y145948D02*
X202006Y145965D01*
G01X201995Y146012D02*
X202001Y145948D01*
G01X202008Y144988D02*
X202022Y145353D01*
G01X202000Y144965D02*
X202008Y144988D01*
G01X201993Y145050D02*
X202000Y144965D01*
G01X201929Y146524D02*
X201943Y146037D01*
G01X201923Y146913D02*
X201929Y146524D01*
G01X201918Y147384D02*
X201923Y146913D01*
G01X201914Y147925D02*
X201918Y147384D01*
G01X201911Y148520D02*
X201914Y147925D01*
G01X201909Y149153D02*
X201911Y148520D01*
G01X201908Y149807D02*
X201909Y149153D01*
G01X201903Y151677D02*
X201895Y151750D01*
G01X201907Y151547D02*
X201903Y151677D01*
G01X201910Y151359D02*
X201907Y151547D01*
G01X201913Y151120D02*
X201910Y151359D01*
G01X201916Y150838D02*
X201913Y151120D01*
G01X201917Y150521D02*
X201916Y150838D01*
G01X201919Y150180D02*
X201917Y150521D01*
G01X201919Y149826D02*
Y150180D01*
G01X201935Y147364D02*
X201945Y146999D01*
G01X201930Y147656D02*
X201935Y147364D01*
G01X201927Y148009D02*
X201930Y147656D01*
G01X201923Y148414D02*
X201927Y148009D01*
G01X201921Y148861D02*
X201923Y148414D01*
G01X201920Y149336D02*
X201921Y148861D01*
G01X201919Y149826D02*
X201920Y149336D01*
G01X200288Y145965D02*
X200299Y146012D01*
G01X200283Y146063D02*
X200288Y145965D01*
G01X200278Y146239D02*
X200283Y146063D01*
G01X200374Y148861D02*
X200376Y149826D01*
G01X200371Y148414D02*
X200374Y148861D01*
G01X200368Y148009D02*
X200371Y148414D01*
G01X200364Y147656D02*
X200368Y148009D01*
G01X200360Y147364D02*
X200364Y147656D01*
G01X200355Y147143D02*
X200360Y147364D01*
G01X200350Y146999D02*
X200355Y147143D01*
G01X200377Y150521D02*
X200376Y149826D01*
G01X200379Y150838D02*
X200377Y150521D01*
G01X200381Y151120D02*
X200379Y150838D01*
G01X200384Y151359D02*
X200381Y151120D01*
G01X200388Y151547D02*
X200384Y151359D01*
G01X200391Y151677D02*
X200388Y151547D01*
G01X200395Y151746D02*
X200391Y151677D01*
G01X200399Y151750D02*
X200395Y151746D01*
G01X200384Y148520D02*
X200387Y149807D01*
G01X200381Y147925D02*
X200384Y148520D01*
G01X200377Y147384D02*
X200381Y147925D01*
G01X200372Y146913D02*
X200377Y147384D01*
G01X200366Y146524D02*
X200372Y146913D01*
G01X200359Y146230D02*
X200366Y146524D01*
G01X200352Y146037D02*
X200359Y146230D01*
G01X200287Y144988D02*
X200302Y145050D01*
G01X200280Y145118D02*
X200287Y144988D01*
G01X200273Y145353D02*
X200280Y145118D01*
G01X200279Y140412D02*
X200269Y140138D01*
G01X200285Y140429D02*
X200279Y140412D01*
G01X200290Y140365D02*
X200285Y140429D01*
G01X200278Y141390D02*
X200264Y141024D01*
G01X200285Y141412D02*
X200278Y141390D01*
G01X200292Y141327D02*
X200285Y141412D01*
G01X200356Y139853D02*
X200343Y140340D01*
G01X200362Y139464D02*
X200356Y139853D01*
G01X200367Y138993D02*
X200362Y139464D01*
G01X200371Y138453D02*
X200367Y138993D01*
G01X200375Y137857D02*
X200371Y138453D01*
G01X200377Y137224D02*
X200375Y137857D01*
G01X200377Y136570D02*
Y137224D01*
G01X200382Y134700D02*
X200390Y134627D01*
G01X200378Y134830D02*
X200382Y134700D01*
G01X200375Y135018D02*
X200378Y134830D01*
G01X200372Y135257D02*
X200375Y135018D01*
G01X200370Y135540D02*
X200372Y135257D01*
G01X200368Y135857D02*
X200370Y135540D01*
G01X200367Y136198D02*
X200368Y135857D01*
G01X200366Y136551D02*
X200367Y136198D01*
G01X200351Y139013D02*
X200340Y139379D01*
G01X200355Y138722D02*
X200351Y139013D01*
G01X200359Y138368D02*
X200355Y138722D01*
G01X200362Y137963D02*
X200359Y138368D01*
G01X200364Y137516D02*
X200362Y137963D01*
G01X200366Y137041D02*
X200364Y137516D01*
G01X200366Y136551D02*
Y137041D01*
G01X201997Y140412D02*
X201986Y140365D01*
G01X202002Y140314D02*
X201997Y140412D01*
G01X202007Y140138D02*
X202002Y140314D01*
G01X201912Y137516D02*
X201910Y136551D01*
G01X201914Y137963D02*
X201912Y137516D01*
G01X201917Y138368D02*
X201914Y137963D01*
G01X201921Y138722D02*
X201917Y138368D01*
G01X201925Y139013D02*
X201921Y138722D01*
G01X201930Y139234D02*
X201925Y139013D01*
G01X201936Y139379D02*
X201930Y139234D01*
G01X201908Y135857D02*
X201910Y136551D01*
G01X201906Y135540D02*
X201908Y135857D01*
G01X201904Y135257D02*
X201906Y135540D01*
G01X201901Y135018D02*
X201904Y135257D01*
G01X201898Y134830D02*
X201901Y135018D01*
G01X201894Y134700D02*
X201898Y134830D01*
G01X201890Y134632D02*
X201894Y134700D01*
G01X201886Y134627D02*
X201890Y134632D01*
G01X201901Y137857D02*
X201899Y136570D01*
G01X201905Y138453D02*
X201901Y137857D01*
G01X201909Y138993D02*
X201905Y138453D01*
G01X201914Y139464D02*
X201909Y138993D01*
G01X201920Y139853D02*
X201914Y139464D01*
G01X201926Y140148D02*
X201920Y139853D01*
G01X201933Y140340D02*
X201926Y140148D01*
G01X201998Y141390D02*
X201984Y141327D01*
G01X202005Y141259D02*
X201998Y141390D01*
G01X202012Y141024D02*
X202005Y141259D01*
G01X196347Y145965D02*
X196358Y146012D01*
G01X196341Y146063D02*
X196347Y145965D01*
G01X196336Y146239D02*
X196341Y146063D01*
G01X196432Y148861D02*
X196434Y149826D01*
G01X196430Y148414D02*
X196432Y148861D01*
G01X196427Y148009D02*
X196430Y148414D01*
G01X196423Y147656D02*
X196427Y148009D01*
G01X196418Y147364D02*
X196423Y147656D01*
G01X196413Y147143D02*
X196418Y147364D01*
G01X196408Y146999D02*
X196413Y147143D01*
G01X196442Y148520D02*
X196445Y149807D01*
G01X196439Y147925D02*
X196442Y148520D01*
G01X196435Y147384D02*
X196439Y147925D01*
G01X196430Y146913D02*
X196435Y147384D01*
G01X196424Y146524D02*
X196430Y146913D01*
G01X196417Y146230D02*
X196424Y146524D01*
G01X196410Y146037D02*
X196417Y146230D01*
G01X196345Y144988D02*
X196360Y145050D01*
G01X196338Y145118D02*
X196345Y144988D01*
G01X196331Y145353D02*
X196338Y145118D01*
G01X198065Y145965D02*
X198075Y146239D01*
G01X198059Y145948D02*
X198065Y145965D01*
G01X198054Y146012D02*
X198059Y145948D01*
G01X198066Y144988D02*
X198080Y145353D01*
G01X198059Y144965D02*
X198066Y144988D01*
G01X198051Y145050D02*
X198059Y144965D01*
G01X197987Y146524D02*
X198001Y146037D01*
G01X197981Y146913D02*
X197987Y146524D01*
G01X197976Y147384D02*
X197981Y146913D01*
G01X197972Y147925D02*
X197976Y147384D01*
G01X197969Y148520D02*
X197972Y147925D01*
G01X197967Y149153D02*
X197969Y148520D01*
G01X197966Y149807D02*
X197967Y149153D01*
G01X197993Y147364D02*
X198003Y146999D01*
G01X197989Y147656D02*
X197993Y147364D01*
G01X197985Y148009D02*
X197989Y147656D01*
G01X197982Y148414D02*
X197985Y148009D01*
G01X197979Y148861D02*
X197982Y148414D01*
G01X197978Y149336D02*
X197979Y148861D01*
G01X197977Y149826D02*
X197978Y149336D01*
G01X198065Y140412D02*
X198054Y140365D01*
G01X198070Y140314D02*
X198065Y140412D01*
G01X198075Y140138D02*
X198070Y140314D01*
G01X197979Y137516D02*
X197977Y136551D01*
G01X197982Y137963D02*
X197979Y137516D01*
G01X197985Y138368D02*
X197982Y137963D01*
G01X197989Y138722D02*
X197985Y138368D01*
G01X197993Y139013D02*
X197989Y138722D01*
G01X197998Y139234D02*
X197993Y139013D01*
G01X198003Y139379D02*
X197998Y139234D01*
G01X197969Y137857D02*
X197966Y136570D01*
G01X197972Y138453D02*
X197969Y137857D01*
G01X197976Y138993D02*
X197972Y138453D01*
G01X197981Y139464D02*
X197976Y138993D01*
G01X197987Y139853D02*
X197981Y139464D01*
G01X197994Y140148D02*
X197987Y139853D01*
G01X198001Y140340D02*
X197994Y140148D01*
G01X198066Y141390D02*
X198051Y141327D01*
G01X198073Y141259D02*
X198066Y141390D01*
G01X198080Y141024D02*
X198073Y141259D01*
G01X196347Y140412D02*
X196336Y140138D01*
G01X196352Y140429D02*
X196347Y140412D01*
G01X196358Y140365D02*
X196352Y140429D01*
G01X196345Y141390D02*
X196331Y141024D01*
G01X196353Y141412D02*
X196345Y141390D01*
G01X196360Y141327D02*
X196353Y141412D01*
G01X196424Y139853D02*
X196410Y140340D01*
G01X196430Y139464D02*
X196424Y139853D01*
G01X196435Y138993D02*
X196430Y139464D01*
G01X196439Y138453D02*
X196435Y138993D01*
G01X196442Y137857D02*
X196439Y138453D01*
G01X196444Y137224D02*
X196442Y137857D01*
G01X196445Y136570D02*
X196444Y137224D01*
G01X196418Y139013D02*
X196408Y139379D01*
G01X196423Y138722D02*
X196418Y139013D01*
G01X196427Y138368D02*
X196423Y138722D01*
G01X196430Y137963D02*
X196427Y138368D01*
G01X196432Y137516D02*
X196430Y137963D01*
G01X196433Y137041D02*
X196432Y137516D01*
G01X196434Y136551D02*
X196433Y137041D01*
G01X194132Y145965D02*
X194143Y146239D01*
G01X194127Y145948D02*
X194132Y145965D01*
G01X194121Y146012D02*
X194127Y145948D01*
G01X194134Y144988D02*
X194148Y145353D01*
G01X194126Y144965D02*
X194134Y144988D01*
G01X194119Y145050D02*
X194126Y144965D01*
G01X194055Y146524D02*
X194069Y146037D01*
G01X194049Y146913D02*
X194055Y146524D01*
G01X194044Y147384D02*
X194049Y146913D01*
G01X194040Y147925D02*
X194044Y147384D01*
G01X194037Y148520D02*
X194040Y147925D01*
G01X194035Y149153D02*
X194037Y148520D01*
G01X194034Y149807D02*
X194035Y149153D01*
G01X194029Y151677D02*
X194021Y151750D01*
G01X194033Y151547D02*
X194029Y151677D01*
G01X194036Y151359D02*
X194033Y151547D01*
G01X194039Y151120D02*
X194036Y151359D01*
G01X194042Y150838D02*
X194039Y151120D01*
G01X194043Y150521D02*
X194042Y150838D01*
G01X194045Y150180D02*
X194043Y150521D01*
G01X194045Y149826D02*
Y150180D01*
G01X194061Y147364D02*
X194071Y146999D01*
G01X194056Y147656D02*
X194061Y147364D01*
G01X194053Y148009D02*
X194056Y147656D01*
G01X194049Y148414D02*
X194053Y148009D01*
G01X194047Y148861D02*
X194049Y148414D01*
G01X194046Y149336D02*
X194047Y148861D01*
G01X194045Y149826D02*
X194046Y149336D01*
G01X192414Y145965D02*
X192425Y146012D01*
G01X192409Y146063D02*
X192414Y145965D01*
G01X192404Y146239D02*
X192409Y146063D01*
G01X192500Y148861D02*
X192502Y149826D01*
G01X192497Y148414D02*
X192500Y148861D01*
G01X192494Y148009D02*
X192497Y148414D01*
G01X192490Y147656D02*
X192494Y148009D01*
G01X192486Y147364D02*
X192490Y147656D01*
G01X192481Y147143D02*
X192486Y147364D01*
G01X192476Y146999D02*
X192481Y147143D01*
G01X192503Y150521D02*
X192502Y149826D01*
G01X192505Y150838D02*
X192503Y150521D01*
G01X192507Y151120D02*
X192505Y150838D01*
G01X192510Y151359D02*
X192507Y151120D01*
G01X192514Y151547D02*
X192510Y151359D01*
G01X192517Y151677D02*
X192514Y151547D01*
G01X192521Y151746D02*
X192517Y151677D01*
G01X192525Y151750D02*
X192521Y151746D01*
G01X192510Y148520D02*
X192513Y149807D01*
G01X192507Y147925D02*
X192510Y148520D01*
G01X192503Y147384D02*
X192507Y147925D01*
G01X192498Y146913D02*
X192503Y147384D01*
G01X192492Y146524D02*
X192498Y146913D01*
G01X192485Y146230D02*
X192492Y146524D01*
G01X192478Y146037D02*
X192485Y146230D01*
G01X192413Y144988D02*
X192428Y145050D01*
G01X192406Y145118D02*
X192413Y144988D01*
G01X192399Y145353D02*
X192406Y145118D01*
G01X192405Y140412D02*
X192395Y140138D01*
G01X192411Y140429D02*
X192405Y140412D01*
G01X192416Y140365D02*
X192411Y140429D01*
G01X192404Y141390D02*
X192390Y141024D01*
G01X192411Y141412D02*
X192404Y141390D01*
G01X192418Y141327D02*
X192411Y141412D01*
G01X192482Y139853D02*
X192469Y140340D01*
G01X192488Y139464D02*
X192482Y139853D01*
G01X192493Y138993D02*
X192488Y139464D01*
G01X192497Y138453D02*
X192493Y138993D01*
G01X192501Y137857D02*
X192497Y138453D01*
G01X192503Y137224D02*
X192501Y137857D01*
G01X192503Y136570D02*
Y137224D01*
G01X192508Y134700D02*
X192516Y134627D01*
G01X192504Y134830D02*
X192508Y134700D01*
G01X192501Y135018D02*
X192504Y134830D01*
G01X192498Y135257D02*
X192501Y135018D01*
G01X192496Y135540D02*
X192498Y135257D01*
G01X192494Y135857D02*
X192496Y135540D01*
G01X192493Y136198D02*
X192494Y135857D01*
G01X192492Y136551D02*
X192493Y136198D01*
G01X192477Y139013D02*
X192466Y139379D01*
G01X192481Y138722D02*
X192477Y139013D01*
G01X192485Y138368D02*
X192481Y138722D01*
G01X192488Y137963D02*
X192485Y138368D01*
G01X192490Y137516D02*
X192488Y137963D01*
G01X192492Y137041D02*
X192490Y137516D01*
G01X192492Y136551D02*
Y137041D01*
G01X194123Y140412D02*
X194112Y140365D01*
G01X194128Y140314D02*
X194123Y140412D01*
G01X194133Y140138D02*
X194128Y140314D01*
G01X194038Y137516D02*
X194036Y136551D01*
G01X194040Y137963D02*
X194038Y137516D01*
G01X194043Y138368D02*
X194040Y137963D01*
G01X194047Y138722D02*
X194043Y138368D01*
G01X194051Y139013D02*
X194047Y138722D01*
G01X194056Y139234D02*
X194051Y139013D01*
G01X194062Y139379D02*
X194056Y139234D01*
G01X194034Y135857D02*
X194036Y136551D01*
G01X194032Y135540D02*
X194034Y135857D01*
G01X194030Y135257D02*
X194032Y135540D01*
G01X194027Y135018D02*
X194030Y135257D01*
G01X194024Y134830D02*
X194027Y135018D01*
G01X194020Y134700D02*
X194024Y134830D01*
G01X194016Y134632D02*
X194020Y134700D01*
G01X194012Y134627D02*
X194016Y134632D01*
G01X194027Y137857D02*
X194025Y136570D01*
G01X194031Y138453D02*
X194027Y137857D01*
G01X194035Y138993D02*
X194031Y138453D01*
G01X194040Y139464D02*
X194035Y138993D01*
G01X194046Y139853D02*
X194040Y139464D01*
G01X194052Y140148D02*
X194046Y139853D01*
G01X194059Y140340D02*
X194052Y140148D01*
G01X194124Y141390D02*
X194110Y141327D01*
G01X194131Y141259D02*
X194124Y141390D01*
G01X194138Y141024D02*
X194131Y141259D01*
G01X188473Y145965D02*
X188484Y146012D01*
G01X188467Y146063D02*
X188473Y145965D01*
G01X188462Y146239D02*
X188467Y146063D01*
G01X188558Y148861D02*
X188560Y149826D01*
G01X188556Y148414D02*
X188558Y148861D01*
G01X188553Y148009D02*
X188556Y148414D01*
G01X188549Y147656D02*
X188553Y148009D01*
G01X188544Y147364D02*
X188549Y147656D01*
G01X188539Y147143D02*
X188544Y147364D01*
G01X188534Y146999D02*
X188539Y147143D01*
G01X188568Y148520D02*
X188571Y149807D01*
G01X188565Y147925D02*
X188568Y148520D01*
G01X188561Y147384D02*
X188565Y147925D01*
G01X188556Y146913D02*
X188561Y147384D01*
G01X188550Y146524D02*
X188556Y146913D01*
G01X188543Y146230D02*
X188550Y146524D01*
G01X188536Y146037D02*
X188543Y146230D01*
G01X188471Y144988D02*
X188486Y145050D01*
G01X188464Y145118D02*
X188471Y144988D01*
G01X188457Y145353D02*
X188464Y145118D01*
G01X190192Y144988D02*
X190206Y145353D01*
G01X190185Y144965D02*
X190192Y144988D01*
G01X190177Y145050D02*
X190185Y144965D01*
G01X190113Y146524D02*
X190127Y146037D01*
G01X190107Y146913D02*
X190113Y146524D01*
G01X190102Y147384D02*
X190107Y146913D01*
G01X190098Y147925D02*
X190102Y147384D01*
G01X190095Y148520D02*
X190098Y147925D01*
G01X190093Y149153D02*
X190095Y148520D01*
G01X190092Y149807D02*
X190093Y149153D01*
G01X190119Y147364D02*
X190129Y146999D01*
G01X190115Y147656D02*
X190119Y147364D01*
G01X190111Y148009D02*
X190115Y147656D01*
G01X190108Y148414D02*
X190111Y148009D01*
G01X190105Y148861D02*
X190108Y148414D01*
G01X190104Y149336D02*
X190105Y148861D01*
G01X190103Y149826D02*
X190104Y149336D01*
G01X190191Y145965D02*
X190201Y146239D01*
G01X190185Y145948D02*
X190191Y145965D01*
G01X190180Y146012D02*
X190185Y145948D01*
G01X190191Y140412D02*
X190180Y140365D01*
G01X190196Y140314D02*
X190191Y140412D01*
G01X190201Y140138D02*
X190196Y140314D01*
G01X190105Y137516D02*
X190103Y136551D01*
G01X190108Y137963D02*
X190105Y137516D01*
G01X190111Y138368D02*
X190108Y137963D01*
G01X190115Y138722D02*
X190111Y138368D01*
G01X190119Y139013D02*
X190115Y138722D01*
G01X190124Y139234D02*
X190119Y139013D01*
G01X190129Y139379D02*
X190124Y139234D01*
G01X190095Y137857D02*
X190092Y136570D01*
G01X190098Y138453D02*
X190095Y137857D01*
G01X190102Y138993D02*
X190098Y138453D01*
G01X190107Y139464D02*
X190102Y138993D01*
G01X190113Y139853D02*
X190107Y139464D01*
G01X190120Y140148D02*
X190113Y139853D01*
G01X190127Y140340D02*
X190120Y140148D01*
G01X190192Y141390D02*
X190177Y141327D01*
G01X190199Y141259D02*
X190192Y141390D01*
G01X190206Y141024D02*
X190199Y141259D01*
G01X188471Y141390D02*
X188457Y141024D01*
G01X188479Y141412D02*
X188471Y141390D01*
G01X188486Y141327D02*
X188479Y141412D01*
G01X188550Y139853D02*
X188536Y140340D01*
G01X188556Y139464D02*
X188550Y139853D01*
G01X188561Y138993D02*
X188556Y139464D01*
G01X188565Y138453D02*
X188561Y138993D01*
G01X188568Y137857D02*
X188565Y138453D01*
G01X188570Y137224D02*
X188568Y137857D01*
G01X188571Y136570D02*
X188570Y137224D01*
G01X188544Y139013D02*
X188534Y139379D01*
G01X188549Y138722D02*
X188544Y139013D01*
G01X188553Y138368D02*
X188549Y138722D01*
G01X188556Y137963D02*
X188553Y138368D01*
G01X188558Y137516D02*
X188556Y137963D01*
G01X188559Y137041D02*
X188558Y137516D01*
G01X188560Y136551D02*
X188559Y137041D01*
G01X188473Y140412D02*
X188462Y140138D01*
G01X188478Y140429D02*
X188473Y140412D01*
G01X188484Y140365D02*
X188478Y140429D01*
G01X188317Y134965D02*
X188321Y135117D01*
G01X188313Y134866D02*
X188317Y134965D01*
G01X188308Y134824D02*
X188313Y134866D01*
G01X190343Y152353D02*
X190337Y152147D01*
G01X190349Y152484D02*
X190343Y152353D01*
G01X190355Y152538D02*
X190349Y152484D01*
G01X188320Y134024D02*
X188326Y134231D01*
G01X188314Y133893D02*
X188320Y134024D01*
G01X188308Y133840D02*
X188314Y133893D01*
G01X197954Y150768D02*
Y150762D01*
G01X197955Y150771D02*
X197954Y150768D01*
G01X197955Y150772D02*
Y150771D01*
G01X190080Y151754D02*
Y151750D01*
G01X190081Y151756D02*
X190080Y151754D01*
G01X196456Y150771D02*
Y150772D01*
G01X196457Y150768D02*
X196456Y150771D01*
G01X196457Y150762D02*
Y150768D01*
G01X197955Y135606D02*
Y135605D01*
G01X197954Y135610D02*
X197955Y135606D01*
G01X197954Y135615D02*
Y135610D01*
G01X188572Y136197D02*
X188571Y136570D01*
G01X188574Y135887D02*
X188572Y136197D01*
G01X188578Y135680D02*
X188574Y135887D01*
G01X188582Y135605D02*
X188578Y135680D01*
G01X190091Y150180D02*
X190092Y149807D01*
G01X190089Y150490D02*
X190091Y150180D01*
G01X190086Y150698D02*
X190089Y150490D01*
G01X190081Y150772D02*
X190086Y150698D01*
G01X188314Y152484D02*
X188308Y152538D01*
G01X188320Y152353D02*
X188314Y152484D01*
G01X188326Y152147D02*
X188320Y152353D01*
G01X190349Y133893D02*
X190355Y133840D01*
G01X190343Y134024D02*
X190349Y133893D01*
G01X190337Y134231D02*
X190343Y134024D01*
G01X192256Y152484D02*
X192250Y152538D01*
G01X192262Y152353D02*
X192256Y152484D01*
G01X192268Y152147D02*
X192262Y152353D01*
G01X194281Y133893D02*
X194288Y133840D01*
G01X194275Y134024D02*
X194281Y133893D01*
G01X194270Y134231D02*
X194275Y134024D01*
G01X196188Y152484D02*
X196182Y152538D01*
G01X196194Y152353D02*
X196188Y152484D01*
G01X196200Y152147D02*
X196194Y152353D01*
G01X198223Y133893D02*
X198229Y133840D01*
G01X198217Y134024D02*
X198223Y133893D01*
G01X198211Y134231D02*
X198217Y134024D01*
G01X200130Y152484D02*
X200124Y152538D01*
G01X200136Y152353D02*
X200130Y152484D01*
G01X200142Y152147D02*
X200136Y152353D01*
G01X202155Y133893D02*
X202162Y133840D01*
G01X202149Y134024D02*
X202155Y133893D01*
G01X202144Y134231D02*
X202149Y134024D01*
G01X204062Y152484D02*
X204056Y152538D01*
G01X204068Y152353D02*
X204062Y152484D01*
G01X204074Y152147D02*
X204068Y152353D01*
G01X206097Y133893D02*
X206103Y133840D01*
G01X206091Y134024D02*
X206097Y133893D01*
G01X206085Y134231D02*
X206091Y134024D01*
G01X188313Y151511D02*
X188308Y151553D01*
G01X188317Y151413D02*
X188313Y151511D01*
G01X188321Y151260D02*
X188317Y151413D01*
G01X190351Y134866D02*
X190355Y134824D01*
G01X190346Y134965D02*
X190351Y134866D01*
G01X190342Y135117D02*
X190346Y134965D01*
G01X192254Y151511D02*
X192250Y151553D01*
G01X192259Y151413D02*
X192254Y151511D01*
G01X192263Y151260D02*
X192259Y151413D01*
G01X194283Y134866D02*
X194288Y134824D01*
G01X194279Y134965D02*
X194283Y134866D01*
G01X194274Y135117D02*
X194279Y134965D01*
G01X196187Y151511D02*
X196182Y151553D01*
G01X196191Y151413D02*
X196187Y151511D01*
G01X196195Y151260D02*
X196191Y151413D01*
G01X198225Y134866D02*
X198229Y134824D01*
G01X198220Y134965D02*
X198225Y134866D01*
G01X198216Y135117D02*
X198220Y134965D01*
G01X200128Y151511D02*
X200124Y151553D01*
G01X200133Y151413D02*
X200128Y151511D01*
G01X200137Y151260D02*
X200133Y151413D01*
G01X202157Y134866D02*
X202162Y134824D01*
G01X202153Y134965D02*
X202157Y134866D01*
G01X202148Y135117D02*
X202153Y134965D01*
G01X204061Y151511D02*
X204056Y151553D01*
G01X204065Y151413D02*
X204061Y151511D01*
G01X204069Y151260D02*
X204065Y151413D01*
G01X206099Y134866D02*
X206103Y134824D01*
G01X206094Y134965D02*
X206099Y134866D01*
G01X206090Y135117D02*
X206094Y134965D01*
G01X192511Y135645D02*
X192516Y135615D01*
G01X192507Y135841D02*
X192511Y135645D01*
G01X192504Y136168D02*
X192507Y135841D01*
G01X192503Y136570D02*
X192504Y136168D01*
G01X194026Y150733D02*
X194022Y150762D01*
G01X194030Y150537D02*
X194026Y150733D01*
G01X194033Y150209D02*
X194030Y150537D01*
G01X194034Y149807D02*
X194033Y150209D01*
G01X200385Y135645D02*
X200390Y135615D01*
G01X200381Y135841D02*
X200385Y135645D01*
G01X200378Y136168D02*
X200381Y135841D01*
G01X200377Y136570D02*
X200378Y136168D01*
G01X201900Y150733D02*
X201896Y150762D01*
G01X201904Y150537D02*
X201900Y150733D01*
G01X201907Y150209D02*
X201904Y150537D01*
G01X201908Y149807D02*
X201907Y150209D01*
G01X188574Y134770D02*
X188582Y134621D01*
G01X188567Y135184D02*
X188574Y134770D01*
G01X188562Y135804D02*
X188567Y135184D01*
G01X188560Y136551D02*
X188562Y135804D01*
G01X190090Y151608D02*
X190081Y151756D01*
G01X190097Y151193D02*
X190090Y151608D01*
G01X190102Y150573D02*
X190097Y151193D01*
G01X190103Y149826D02*
X190102Y150573D01*
G01X196448Y134770D02*
X196456Y134621D01*
G01X196441Y135184D02*
X196448Y134770D01*
G01X196436Y135804D02*
X196441Y135184D01*
G01X196434Y136551D02*
X196436Y135804D01*
G01X196452Y135678D02*
X196456Y135605D01*
G01X196448Y135887D02*
X196452Y135678D01*
G01X196446Y136200D02*
X196448Y135887D01*
G01X196445Y136570D02*
X196446Y136200D01*
G01X197960Y150699D02*
X197955Y150772D01*
G01X197963Y150490D02*
X197960Y150699D01*
G01X197965Y150178D02*
X197963Y150490D01*
G01X197966Y149807D02*
X197965Y150178D01*
G01X197964Y151608D02*
X197955Y151756D01*
G01X197971Y151193D02*
X197964Y151608D01*
G01X197976Y150573D02*
X197971Y151193D01*
G01X197977Y149826D02*
X197976Y150573D01*
G01X204322Y134770D02*
X204330Y134621D01*
G01X204315Y135184D02*
X204322Y134770D01*
G01X204310Y135804D02*
X204315Y135184D01*
G01X204308Y136551D02*
X204310Y135804D01*
G01X204326Y135678D02*
X204330Y135605D01*
G01X204322Y135887D02*
X204326Y135678D01*
G01X204320Y136200D02*
X204322Y135887D01*
G01X204319Y136570D02*
X204320Y136200D01*
G01X205834Y150699D02*
X205829Y150772D01*
G01X205837Y150490D02*
X205834Y150699D01*
G01X205840Y150178D02*
X205837Y150490D01*
G01X205840Y149807D02*
Y150178D01*
G01X205838Y151608D02*
X205829Y151756D01*
G01X205845Y151193D02*
X205838Y151608D01*
G01X205850Y150573D02*
X205845Y151193D01*
G01X205851Y149826D02*
X205850Y150573D01*
G01X188578Y150698D02*
X188582Y150772D01*
G01X188574Y150490D02*
X188578Y150698D01*
G01X188572Y150180D02*
X188574Y150490D01*
G01X188571Y149807D02*
X188572Y150180D01*
G01X190086Y135680D02*
X190081Y135605D01*
G01X190089Y135887D02*
X190086Y135680D01*
G01X190091Y136197D02*
X190089Y135887D01*
G01X190092Y136570D02*
X190091Y136197D01*
G01X188562Y150573D02*
X188560Y149826D01*
G01X188567Y151193D02*
X188562Y150573D01*
G01X188574Y151608D02*
X188567Y151193D01*
G01X188582Y151756D02*
X188574Y151608D01*
G01X190102Y135804D02*
X190103Y136551D01*
G01X190097Y135184D02*
X190102Y135804D01*
G01X190090Y134770D02*
X190097Y135184D01*
G01X190081Y134621D02*
X190090Y134770D01*
G01X196436Y150573D02*
X196434Y149826D01*
G01X196441Y151193D02*
X196436Y150573D01*
G01X196448Y151608D02*
X196441Y151193D01*
G01X196456Y151756D02*
X196448Y151608D01*
G01X197976Y135804D02*
X197977Y136551D01*
G01X197971Y135184D02*
X197976Y135804D01*
G01X197964Y134770D02*
X197971Y135184D01*
G01X197955Y134621D02*
X197964Y134770D01*
G01X204310Y150573D02*
X204308Y149826D01*
G01X204315Y151193D02*
X204310Y150573D01*
G01X204322Y151608D02*
X204315Y151193D01*
G01X204330Y151756D02*
X204322Y151608D01*
G01X205850Y135804D02*
X205851Y136551D01*
G01X205845Y135184D02*
X205850Y135804D01*
G01X205838Y134770D02*
X205845Y135184D01*
G01X205829Y134621D02*
X205838Y134770D01*
G01X196446Y150178D02*
X196445Y149807D01*
G01X196448Y150490D02*
X196446Y150178D01*
G01X196452Y150699D02*
X196448Y150490D01*
G01X196456Y150772D02*
X196452Y150699D01*
G01X197965Y136200D02*
X197966Y136570D01*
G01X197963Y135887D02*
X197965Y136200D01*
G01X197960Y135678D02*
X197963Y135887D01*
G01X197955Y135605D02*
X197960Y135678D01*
G01X204320Y150178D02*
X204319Y149807D01*
G01X204322Y150490D02*
X204320Y150178D01*
G01X204326Y150699D02*
X204322Y150490D01*
G01X204330Y150772D02*
X204326Y150699D01*
G01X205840Y136200D02*
Y136570D01*
G01X205837Y135887D02*
X205840Y136200D01*
G01X205834Y135678D02*
X205837Y135887D01*
G01X205829Y135605D02*
X205834Y135678D01*
G01X188582Y135606D02*
Y135605D01*
G01X188583Y135610D02*
X188582Y135606D01*
G01X188584Y135617D02*
X188583Y135610D01*
G01X190081Y150771D02*
Y150772D01*
G01X190080Y150768D02*
X190081Y150771D01*
G01X190080Y150760D02*
Y150768D01*
G01X190346Y151413D02*
X190342Y151260D01*
G01X190351Y151511D02*
X190346Y151413D01*
G01X190355Y151553D02*
X190351Y151511D01*
G01X192249Y134965D02*
X192254Y135117D01*
G01X192245Y134866D02*
X192249Y134965D01*
G01X192240Y134824D02*
X192245Y134866D01*
G01X194288Y151413D02*
X194284Y151260D01*
G01X194292Y151511D02*
X194288Y151413D01*
G01X194297Y151553D02*
X194292Y151511D01*
G01X196191Y134965D02*
X196195Y135117D01*
G01X196187Y134866D02*
X196191Y134965D01*
G01X196182Y134824D02*
X196187Y134866D01*
G01X198220Y151413D02*
X198216Y151260D01*
G01X198225Y151511D02*
X198220Y151413D01*
G01X198229Y151553D02*
X198225Y151511D01*
G01X200123Y134965D02*
X200128Y135117D01*
G01X200119Y134866D02*
X200123Y134965D01*
G01X200114Y134824D02*
X200119Y134866D01*
G01X202162Y151413D02*
X202158Y151260D01*
G01X202166Y151511D02*
X202162Y151413D01*
G01X202171Y151553D02*
X202166Y151511D01*
G01X204065Y134965D02*
X204069Y135117D01*
G01X204061Y134866D02*
X204065Y134965D01*
G01X204056Y134824D02*
X204061Y134866D01*
G01X206094Y151413D02*
X206090Y151260D01*
G01X206099Y151511D02*
X206094Y151413D01*
G01X206103Y151553D02*
X206099Y151511D01*
G01X207997Y134965D02*
X208002Y135117D01*
G01X207993Y134866D02*
X207997Y134965D01*
G01X207988Y134824D02*
X207993Y134866D01*
G01X210036Y151413D02*
X210032Y151260D01*
G01X210040Y151511D02*
X210036Y151413D01*
G01X210045Y151553D02*
X210040Y151511D01*
G01X211939Y134965D02*
X211943Y135117D01*
G01X211935Y134866D02*
X211939Y134965D01*
G01X211930Y134824D02*
X211935Y134866D01*
G01X213968Y151413D02*
X213964Y151260D01*
G01X213973Y151511D02*
X213968Y151413D01*
G01X213977Y151553D02*
X213973Y151511D01*
G01X194285Y152353D02*
X194279Y152147D01*
G01X194291Y152484D02*
X194285Y152353D01*
G01X194297Y152538D02*
X194291Y152484D01*
G01X192253Y134024D02*
X192258Y134231D01*
G01X192247Y133893D02*
X192253Y134024D01*
G01X192240Y133840D02*
X192247Y133893D01*
G01X198217Y152353D02*
X198211Y152147D01*
G01X198223Y152484D02*
X198217Y152353D01*
G01X198229Y152538D02*
X198223Y152484D01*
G01X196194Y134024D02*
X196200Y134231D01*
G01X196188Y133893D02*
X196194Y134024D01*
G01X196182Y133840D02*
X196188Y133893D01*
G01X202159Y152353D02*
X202153Y152147D01*
G01X202165Y152484D02*
X202159Y152353D01*
G01X202171Y152538D02*
X202165Y152484D01*
G01X200127Y134024D02*
X200132Y134231D01*
G01X200121Y133893D02*
X200127Y134024D01*
G01X200114Y133840D02*
X200121Y133893D01*
G01X206091Y152353D02*
X206085Y152147D01*
G01X206097Y152484D02*
X206091Y152353D01*
G01X206103Y152538D02*
X206097Y152484D01*
G01X204068Y134024D02*
X204074Y134231D01*
G01X204062Y133893D02*
X204068Y134024D01*
G01X204056Y133840D02*
X204062Y133893D01*
G01X210033Y152353D02*
X210027Y152147D01*
G01X210039Y152484D02*
X210033Y152353D01*
G01X210045Y152538D02*
X210039Y152484D01*
G01X208001Y134024D02*
X208006Y134231D01*
G01X207995Y133893D02*
X208001Y134024D01*
G01X207988Y133840D02*
X207995Y133893D01*
G01X213965Y152353D02*
X213959Y152147D01*
G01X213971Y152484D02*
X213965Y152353D01*
G01X213977Y152538D02*
X213971Y152484D01*
G01X211942Y134024D02*
X211948Y134231D01*
G01X211936Y133893D02*
X211942Y134024D01*
G01X211930Y133840D02*
X211936Y133893D01*
G01X192514Y150209D02*
X192513Y149807D01*
G01X192516Y150537D02*
X192514Y150209D01*
G01X192521Y150733D02*
X192516Y150537D01*
G01X192525Y150762D02*
X192521Y150733D01*
G01X194024Y136168D02*
X194025Y136570D01*
G01X194021Y135841D02*
X194024Y136168D01*
G01X194017Y135645D02*
X194021Y135841D01*
G01X194012Y135615D02*
X194017Y135645D01*
G01X200388Y150209D02*
X200387Y149807D01*
G01X200391Y150537D02*
X200388Y150209D01*
G01X200395Y150733D02*
X200391Y150537D01*
G01X200399Y150762D02*
X200395Y150733D01*
G01X201898Y136168D02*
X201899Y136570D01*
G01X201895Y135841D02*
X201898Y136168D01*
G01X201891Y135645D02*
X201895Y135841D01*
G01X201886Y135615D02*
X201891Y135645D01*
G01X208262Y150209D02*
X208261Y149807D01*
G01X208265Y150537D02*
X208262Y150209D01*
G01X208269Y150733D02*
X208265Y150537D01*
G01X208273Y150762D02*
X208269Y150733D01*
G01X209772Y136168D02*
X209773Y136570D01*
G01X209769Y135841D02*
X209772Y136168D01*
G01X209765Y135645D02*
X209769Y135841D01*
G01X209760Y135615D02*
X209765Y135645D01*
G01X216136Y150209D02*
X216135Y149807D01*
G01X216139Y150537D02*
X216136Y150209D01*
G01X216143Y150733D02*
X216139Y150537D01*
G01X216147Y150762D02*
X216143Y150733D01*
G01X196457Y135610D02*
Y135615D01*
G01X196456Y135606D02*
X196457Y135610D01*
G01X196456Y135605D02*
Y135606D01*
G01X205828Y150768D02*
Y150762D01*
G01X205829Y150771D02*
X205828Y150768D01*
G01X205829Y150772D02*
Y150771D01*
G01X204331Y135610D02*
Y135615D01*
G01X204330Y135606D02*
X204331Y135610D01*
G01X204330Y135605D02*
Y135606D01*
G01X213702Y150768D02*
Y150762D01*
G01X213703Y150771D02*
X213702Y150768D01*
G01X213703Y150772D02*
Y150771D01*
G01X212205Y135610D02*
Y135615D01*
G01X212204Y135606D02*
X212205Y135610D01*
G01X212204Y135605D02*
Y135606D01*
G01X221576Y150768D02*
Y150762D01*
G01X221577Y150771D02*
X221576Y150768D01*
G01X221577Y150772D02*
Y150771D01*
G01X197954Y151754D02*
Y151750D01*
G01X197955Y151756D02*
X197954Y151754D01*
G01X188583Y134624D02*
X188584Y134627D01*
G01X188583Y134622D02*
Y134624D01*
G01X188582Y134621D02*
X188583Y134622D01*
G01X205828Y151754D02*
Y151750D01*
G01X205829Y151756D02*
X205828Y151754D01*
G01X196457Y134624D02*
X196458Y134627D01*
G01X196457Y134622D02*
Y134624D01*
G01X196456Y134621D02*
X196457Y134622D01*
G01X213702Y151754D02*
Y151750D01*
G01X213703Y151756D02*
X213702Y151754D01*
G01X204331Y134624D02*
X204332Y134627D01*
G01X204331Y134622D02*
Y134624D01*
G01X204330Y134621D02*
X204331Y134622D01*
G01X221576Y151754D02*
Y151750D01*
G01X221577Y151756D02*
X221576Y151754D01*
G01X212205Y134624D02*
X212206Y134627D01*
G01X212205Y134622D02*
Y134624D01*
G01X212204Y134621D02*
X212205Y134622D01*
G01X190081D02*
Y134621D01*
G01X190080Y134624D02*
X190081Y134622D01*
G01X190080Y134627D02*
Y134624D01*
G01X188583Y151756D02*
X188582D01*
G01X188583Y151754D02*
Y151756D01*
G01X188584Y151750D02*
X188583Y151754D01*
G01X197955Y134622D02*
Y134621D01*
G01X197954Y134624D02*
X197955Y134622D01*
G01X197954Y134627D02*
Y134624D01*
G01X204330Y150771D02*
Y150772D01*
G01X204331Y150768D02*
X204330Y150771D01*
G01X204331Y150762D02*
Y150768D01*
G01X205829Y135606D02*
Y135605D01*
G01X205828Y135610D02*
X205829Y135606D01*
G01X205828Y135615D02*
Y135610D01*
G01X212204Y150771D02*
Y150772D01*
G01X212205Y150768D02*
X212204Y150771D01*
G01X212205Y150762D02*
Y150768D01*
G01X213703Y135606D02*
Y135605D01*
G01X213702Y135610D02*
X213703Y135606D01*
G01X213702Y135615D02*
Y135610D01*
G01X220079Y150771D02*
X220078Y150772D01*
G01X220079Y150768D02*
Y150771D01*
G01X220080Y150762D02*
X220079Y150768D01*
G01X221577Y135606D02*
Y135605D01*
G01X221576Y135610D02*
X221577Y135606D01*
G01X221576Y135615D02*
Y135610D01*
G01X208004Y152484D02*
X207998Y152538D01*
G01X208010Y152353D02*
X208004Y152484D01*
G01X208016Y152147D02*
X208010Y152353D01*
G01X210029Y133893D02*
X210036Y133840D01*
G01X210023Y134024D02*
X210029Y133893D01*
G01X210018Y134231D02*
X210023Y134024D01*
G01X211936Y152484D02*
X211930Y152538D01*
G01X211942Y152353D02*
X211936Y152484D01*
G01X211948Y152147D02*
X211942Y152353D01*
G01X213971Y133893D02*
X213977Y133840D01*
G01X213965Y134024D02*
X213971Y133893D01*
G01X213959Y134231D02*
X213965Y134024D01*
G01X215878Y152484D02*
X215872Y152538D01*
G01X215884Y152353D02*
X215878Y152484D01*
G01X215890Y152147D02*
X215884Y152353D01*
G01X217903Y133893D02*
X217910Y133840D01*
G01X217897Y134024D02*
X217903Y133893D01*
G01X217892Y134231D02*
X217897Y134024D01*
G01X219810Y152484D02*
X219804Y152538D01*
G01X219816Y152353D02*
X219810Y152484D01*
G01X219822Y152147D02*
X219816Y152353D01*
G01X221845Y133893D02*
X221851Y133840D01*
G01X221839Y134024D02*
X221845Y133893D01*
G01X221833Y134231D02*
X221839Y134024D01*
G01X223752Y152484D02*
X223746Y152538D01*
G01X223758Y152353D02*
X223752Y152484D01*
G01X223764Y152147D02*
X223758Y152353D01*
G01X225778Y133893D02*
X225784Y133840D01*
G01X225771Y134024D02*
X225778Y133893D01*
G01X225766Y134231D02*
X225771Y134024D01*
G01X227684Y152484D02*
X227678Y152538D01*
G01X227690Y152353D02*
X227684Y152484D01*
G01X227696Y152147D02*
X227690Y152353D01*
G01X229719Y133893D02*
X229725Y133840D01*
G01X229713Y134024D02*
X229719Y133893D01*
G01X229707Y134231D02*
X229713Y134024D01*
G01X208002Y151511D02*
X207998Y151553D01*
G01X208007Y151413D02*
X208002Y151511D01*
G01X208011Y151260D02*
X208007Y151413D01*
G01X210031Y134866D02*
X210036Y134824D01*
G01X210027Y134965D02*
X210031Y134866D01*
G01X210022Y135117D02*
X210027Y134965D01*
G01X211935Y151511D02*
X211930Y151553D01*
G01X211939Y151413D02*
X211935Y151511D01*
G01X211943Y151260D02*
X211939Y151413D01*
G01X213973Y134866D02*
X213977Y134824D01*
G01X213968Y134965D02*
X213973Y134866D01*
G01X213964Y135117D02*
X213968Y134965D01*
G01X215876Y151511D02*
X215872Y151553D01*
G01X215881Y151413D02*
X215876Y151511D01*
G01X215885Y151260D02*
X215881Y151413D01*
G01X217905Y134866D02*
X217910Y134824D01*
G01X217901Y134965D02*
X217905Y134866D01*
G01X217896Y135117D02*
X217901Y134965D01*
G01X219809Y151511D02*
X219804Y151553D01*
G01X219813Y151413D02*
X219809Y151511D01*
G01X219817Y151260D02*
X219813Y151413D01*
G01X221847Y134866D02*
X221851Y134824D01*
G01X221842Y134965D02*
X221847Y134866D01*
G01X221838Y135117D02*
X221842Y134965D01*
G01X223750Y151511D02*
X223746Y151553D01*
G01X223755Y151413D02*
X223750Y151511D01*
G01X223759Y151260D02*
X223755Y151413D01*
G01X225779Y134866D02*
X225784Y134824D01*
G01X225775Y134965D02*
X225779Y134866D01*
G01X225770Y135117D02*
X225775Y134965D01*
G01X227683Y151511D02*
X227678Y151553D01*
G01X227687Y151413D02*
X227683Y151511D01*
G01X227691Y151260D02*
X227687Y151413D01*
G01X229721Y134866D02*
X229725Y134824D01*
G01X229716Y134965D02*
X229721Y134866D01*
G01X229712Y135117D02*
X229716Y134965D01*
G01X208259Y135645D02*
X208264Y135615D01*
G01X208255Y135841D02*
X208259Y135645D01*
G01X208252Y136168D02*
X208255Y135841D01*
G01X208251Y136570D02*
X208252Y136168D01*
G01X209774Y150733D02*
X209770Y150762D01*
G01X209778Y150537D02*
X209774Y150733D01*
G01X209781Y150209D02*
X209778Y150537D01*
G01X209782Y149807D02*
X209781Y150209D01*
G01X216133Y135645D02*
X216138Y135615D01*
G01X216129Y135841D02*
X216133Y135645D01*
G01X216126Y136168D02*
X216129Y135841D01*
G01X216125Y136570D02*
X216126Y136168D01*
G01X217648Y150733D02*
X217644Y150762D01*
G01X217652Y150537D02*
X217648Y150733D01*
G01X217655Y150209D02*
X217652Y150537D01*
G01X217656Y149807D02*
X217655Y150209D01*
G01X224007Y135645D02*
X224012Y135615D01*
G01X224003Y135841D02*
X224007Y135645D01*
G01X224000Y136168D02*
X224003Y135841D01*
G01X223999Y136570D02*
X224000Y136168D01*
G01X225522Y150733D02*
X225518Y150762D01*
G01X225526Y150537D02*
X225522Y150733D01*
G01X225529Y150209D02*
X225526Y150537D01*
G01X225530Y149807D02*
X225529Y150209D01*
G01X231881Y135645D02*
X231886Y135615D01*
G01X231877Y135841D02*
X231881Y135645D01*
G01X231874Y136168D02*
X231877Y135841D01*
G01X231873Y136570D02*
X231874Y136168D01*
G01X212196Y134770D02*
X212204Y134621D01*
G01X212189Y135184D02*
X212196Y134770D01*
G01X212184Y135804D02*
X212189Y135184D01*
G01X212182Y136551D02*
X212184Y135804D01*
G01X212200Y135678D02*
X212204Y135605D01*
G01X212196Y135887D02*
X212200Y135678D01*
G01X212194Y136200D02*
X212196Y135887D01*
G01X212193Y136570D02*
X212194Y136200D01*
G01X213708Y150699D02*
X213703Y150772D01*
G01X213711Y150490D02*
X213708Y150699D01*
G01X213714Y150178D02*
X213711Y150490D01*
G01X213714Y149807D02*
Y150178D01*
G01X213712Y151608D02*
X213703Y151756D01*
G01X213719Y151193D02*
X213712Y151608D01*
G01X213724Y150573D02*
X213719Y151193D01*
G01X213725Y149826D02*
X213724Y150573D01*
G01X220070Y134770D02*
X220078Y134621D01*
G01X220063Y135184D02*
X220070Y134770D01*
G01X220058Y135804D02*
X220063Y135184D01*
G01X220056Y136551D02*
X220058Y135804D01*
G01X220074Y135678D02*
X220078Y135605D01*
G01X220070Y135887D02*
X220074Y135678D01*
G01X220068Y136200D02*
X220070Y135887D01*
G01X220067Y136570D02*
X220068Y136200D01*
G01X221582Y150699D02*
X221577Y150772D01*
G01X221585Y150490D02*
X221582Y150699D01*
G01X221588Y150178D02*
X221585Y150490D01*
G01X221588Y149807D02*
Y150178D01*
G01X221586Y151608D02*
X221577Y151756D01*
G01X221593Y151193D02*
X221586Y151608D01*
G01X221598Y150573D02*
X221593Y151193D01*
G01X221599Y149826D02*
X221598Y150573D01*
G01X227944Y134770D02*
X227952Y134621D01*
G01X227937Y135184D02*
X227944Y134770D01*
G01X227932Y135804D02*
X227937Y135184D01*
G01X227930Y136551D02*
X227932Y135804D01*
G01X227948Y135678D02*
X227952Y135605D01*
G01X227944Y135887D02*
X227948Y135678D01*
G01X227942Y136200D02*
X227944Y135887D01*
G01X227941Y136570D02*
X227942Y136200D01*
G01X229456Y150699D02*
X229451Y150772D01*
G01X229459Y150490D02*
X229456Y150699D01*
G01X229462Y150178D02*
X229459Y150490D01*
G01X229462Y149807D02*
Y150178D01*
G01X229460Y151608D02*
X229451Y151756D01*
G01X229467Y151193D02*
X229460Y151608D01*
G01X229472Y150573D02*
X229467Y151193D01*
G01X229473Y149826D02*
X229472Y150573D01*
G01X212184D02*
X212182Y149826D01*
G01X212189Y151193D02*
X212184Y150573D01*
G01X212196Y151608D02*
X212189Y151193D01*
G01X212204Y151756D02*
X212196Y151608D01*
G01X213724Y135804D02*
X213725Y136551D01*
G01X213719Y135184D02*
X213724Y135804D01*
G01X213712Y134770D02*
X213719Y135184D01*
G01X213703Y134621D02*
X213712Y134770D01*
G01X220058Y150573D02*
X220056Y149826D01*
G01X220063Y151193D02*
X220058Y150573D01*
G01X220070Y151608D02*
X220063Y151193D01*
G01X220078Y151756D02*
X220070Y151608D01*
G01X221598Y135804D02*
X221599Y136551D01*
G01X221593Y135184D02*
X221598Y135804D01*
G01X221586Y134770D02*
X221593Y135184D01*
G01X221577Y134621D02*
X221586Y134770D01*
G01X227932Y150573D02*
X227930Y149826D01*
G01X227937Y151193D02*
X227932Y150573D01*
G01X227944Y151608D02*
X227937Y151193D01*
G01X227952Y151756D02*
X227944Y151608D01*
G01X229472Y135804D02*
X229473Y136551D01*
G01X229467Y135184D02*
X229472Y135804D01*
G01X229460Y134770D02*
X229467Y135184D01*
G01X229451Y134621D02*
X229460Y134770D01*
G01X235806Y150573D02*
X235804Y149826D01*
G01X235811Y151193D02*
X235806Y150573D01*
G01X235818Y151608D02*
X235811Y151193D01*
G01X235826Y151756D02*
X235818Y151608D01*
G01X212194Y150178D02*
X212193Y149807D01*
G01X212196Y150490D02*
X212194Y150178D01*
G01X212200Y150699D02*
X212196Y150490D01*
G01X212204Y150772D02*
X212200Y150699D01*
G01X213714Y136200D02*
Y136570D01*
G01X213711Y135887D02*
X213714Y136200D01*
G01X213708Y135678D02*
X213711Y135887D01*
G01X213703Y135605D02*
X213708Y135678D01*
G01X220068Y150178D02*
X220067Y149807D01*
G01X220070Y150490D02*
X220068Y150178D01*
G01X220074Y150699D02*
X220070Y150490D01*
G01X220078Y150772D02*
X220074Y150699D01*
G01X221588Y136200D02*
Y136570D01*
G01X221585Y135887D02*
X221588Y136200D01*
G01X221582Y135678D02*
X221585Y135887D01*
G01X221577Y135605D02*
X221582Y135678D01*
G01X227942Y150178D02*
X227941Y149807D01*
G01X227944Y150490D02*
X227942Y150178D01*
G01X227948Y150699D02*
X227944Y150490D01*
G01X227952Y150772D02*
X227948Y150699D01*
G01X229462Y136200D02*
Y136570D01*
G01X229459Y135887D02*
X229462Y136200D01*
G01X229456Y135678D02*
X229459Y135887D01*
G01X229451Y135605D02*
X229456Y135678D01*
G01X235816Y150178D02*
X235815Y149807D01*
G01X235818Y150490D02*
X235816Y150178D01*
G01X235822Y150699D02*
X235818Y150490D01*
G01X235826Y150772D02*
X235822Y150699D01*
G01X215871Y134965D02*
X215876Y135117D01*
G01X215867Y134866D02*
X215871Y134965D01*
G01X215862Y134824D02*
X215867Y134866D01*
G01X217910Y151413D02*
X217906Y151260D01*
G01X217914Y151511D02*
X217910Y151413D01*
G01X217919Y151553D02*
X217914Y151511D01*
G01X219813Y134965D02*
X219817Y135117D01*
G01X219809Y134866D02*
X219813Y134965D01*
G01X219804Y134824D02*
X219809Y134866D01*
G01X221842Y151413D02*
X221838Y151260D01*
G01X221847Y151511D02*
X221842Y151413D01*
G01X221851Y151553D02*
X221847Y151511D01*
G01X223745Y134965D02*
X223750Y135117D01*
G01X223741Y134866D02*
X223745Y134965D01*
G01X223736Y134824D02*
X223741Y134866D01*
G01X225784Y151413D02*
X225780Y151260D01*
G01X225788Y151511D02*
X225784Y151413D01*
G01X225793Y151553D02*
X225788Y151511D01*
G01X227687Y134965D02*
X227691Y135117D01*
G01X227683Y134866D02*
X227687Y134965D01*
G01X227678Y134824D02*
X227683Y134866D01*
G01X229716Y151413D02*
X229712Y151260D01*
G01X229721Y151511D02*
X229716Y151413D01*
G01X229725Y151553D02*
X229721Y151511D01*
G01X231619Y134965D02*
X231624Y135117D01*
G01X231615Y134866D02*
X231619Y134965D01*
G01X231610Y134824D02*
X231615Y134866D01*
G01X233658Y151413D02*
X233654Y151260D01*
G01X233663Y151511D02*
X233658Y151413D01*
G01X233667Y151553D02*
X233663Y151511D01*
G01X235561Y134965D02*
X235565Y135117D01*
G01X235557Y134866D02*
X235561Y134965D01*
G01X235552Y134824D02*
X235557Y134866D01*
G01X237590Y151413D02*
X237586Y151260D01*
G01X237595Y151511D02*
X237590Y151413D01*
G01X237599Y151553D02*
X237595Y151511D01*
G01X217907Y152353D02*
X217901Y152147D01*
G01X217913Y152484D02*
X217907Y152353D01*
G01X217919Y152538D02*
X217913Y152484D01*
G01X215875Y134024D02*
X215880Y134231D01*
G01X215869Y133893D02*
X215875Y134024D01*
G01X215862Y133840D02*
X215869Y133893D01*
G01X221839Y152353D02*
X221833Y152147D01*
G01X221845Y152484D02*
X221839Y152353D01*
G01X221851Y152538D02*
X221845Y152484D01*
G01X219816Y134024D02*
X219822Y134231D01*
G01X219810Y133893D02*
X219816Y134024D01*
G01X219804Y133840D02*
X219810Y133893D01*
G01X225781Y152353D02*
X225775Y152147D01*
G01X225787Y152484D02*
X225781Y152353D01*
G01X225793Y152538D02*
X225787Y152484D01*
G01X223749Y134024D02*
X223754Y134231D01*
G01X223743Y133893D02*
X223749Y134024D01*
G01X223736Y133840D02*
X223743Y133893D01*
G01X229713Y152353D02*
X229707Y152147D01*
G01X229719Y152484D02*
X229713Y152353D01*
G01X229725Y152538D02*
X229719Y152484D01*
G01X227690Y134024D02*
X227696Y134231D01*
G01X227684Y133893D02*
X227690Y134024D01*
G01X227678Y133840D02*
X227684Y133893D01*
G01X233655Y152353D02*
X233649Y152147D01*
G01X233661Y152484D02*
X233655Y152353D01*
G01X233667Y152538D02*
X233661Y152484D01*
G01X231623Y134024D02*
X231628Y134231D01*
G01X231617Y133893D02*
X231623Y134024D01*
G01X231610Y133840D02*
X231617Y133893D01*
G01X237587Y152353D02*
X237581Y152147D01*
G01X237593Y152484D02*
X237587Y152353D01*
G01X237599Y152538D02*
X237593Y152484D01*
G01X235564Y134024D02*
X235570Y134231D01*
G01X235558Y133893D02*
X235564Y134024D01*
G01X235552Y133840D02*
X235558Y133893D01*
G01X217646Y136168D02*
X217647Y136570D01*
G01X217643Y135841D02*
X217646Y136168D01*
G01X217639Y135645D02*
X217643Y135841D01*
G01X217634Y135615D02*
X217639Y135645D01*
G01X224010Y150209D02*
X224009Y149807D01*
G01X224013Y150537D02*
X224010Y150209D01*
G01X224017Y150733D02*
X224013Y150537D01*
G01X224021Y150762D02*
X224017Y150733D01*
G01X225520Y136168D02*
X225521Y136570D01*
G01X225517Y135841D02*
X225520Y136168D01*
G01X225513Y135645D02*
X225517Y135841D01*
G01X225508Y135615D02*
X225513Y135645D01*
G01X231884Y150209D02*
X231883Y149807D01*
G01X231887Y150537D02*
X231884Y150209D01*
G01X231891Y150733D02*
X231887Y150537D01*
G01X231895Y150762D02*
X231891Y150733D01*
G01X233394Y136168D02*
X233395Y136570D01*
G01X233391Y135841D02*
X233394Y136168D01*
G01X233387Y135645D02*
X233391Y135841D01*
G01X233382Y135615D02*
X233387Y135645D01*
G01X239758Y150209D02*
X239757Y149807D01*
G01X239761Y150537D02*
X239758Y150209D01*
G01X239765Y150733D02*
X239761Y150537D01*
G01X239769Y150762D02*
X239765Y150733D01*
G01X220079Y135610D02*
X220080Y135615D01*
G01X220079Y135606D02*
Y135610D01*
G01X220078Y135605D02*
X220079Y135606D01*
G01X229450Y150768D02*
Y150762D01*
G01X229451Y150771D02*
X229450Y150768D01*
G01X229451Y150772D02*
Y150771D01*
G01X227953Y135610D02*
X227954Y135615D01*
G01X227953Y135606D02*
Y135610D01*
G01X227952Y135605D02*
X227953Y135606D01*
G01X237324Y150768D02*
Y150762D01*
G01X237325Y150771D02*
X237324Y150768D01*
G01X237325Y150772D02*
Y150771D01*
G01X235827Y135610D02*
X235828Y135615D01*
G01X235827Y135606D02*
Y135610D01*
G01X235826Y135605D02*
X235827Y135606D01*
G01X245199Y150768D02*
X245198Y150762D01*
G01X245199Y150771D02*
Y150768D01*
G01X245200Y150772D02*
X245199Y150771D01*
G01X243701Y135610D02*
X243702Y135615D01*
G01X243701Y135606D02*
Y135610D01*
G01X243700Y135605D02*
X243701Y135606D01*
G01X229450Y151754D02*
Y151750D01*
G01X229451Y151756D02*
X229450Y151754D01*
G01X220079Y134624D02*
X220080Y134627D01*
G01X220079Y134622D02*
Y134624D01*
G01X220078Y134621D02*
X220079Y134622D01*
G01X237324Y151754D02*
Y151750D01*
G01X237325Y151756D02*
X237324Y151754D01*
G01X227953Y134624D02*
X227954Y134627D01*
G01X227953Y134622D02*
Y134624D01*
G01X227952Y134621D02*
X227953Y134622D01*
G01X245198Y151754D02*
Y151750D01*
G01X245199Y151756D02*
X245198Y151754D01*
G01X245200Y151756D02*
X245199D01*
G01X235827Y134624D02*
X235828Y134627D01*
G01X235827Y134622D02*
Y134624D01*
G01X235826Y134621D02*
X235827Y134622D01*
G01X253072Y151754D02*
Y151750D01*
G01X253073Y151756D02*
X253072Y151754D01*
G01X253074Y151756D02*
X253073D01*
G01X243701Y134624D02*
X243702Y134627D01*
G01X243701Y134622D02*
Y134624D01*
G01X243700Y134621D02*
X243701Y134622D01*
G01X190080Y135610D02*
Y135617D01*
G01X190081Y135606D02*
X190080Y135610D01*
G01X190081Y135605D02*
Y135606D01*
G01X188583Y150768D02*
X188584Y150760D01*
G01X188582Y150771D02*
X188583Y150768D01*
G01X188582Y150772D02*
Y150771D01*
G01X196457Y151756D02*
X196456D01*
G01X196457Y151754D02*
Y151756D01*
G01X196458Y151750D02*
X196457Y151754D01*
G01X205829Y134622D02*
Y134621D01*
G01X205828Y134624D02*
X205829Y134622D01*
G01X205828Y134627D02*
Y134624D01*
G01X204331Y151756D02*
X204330D01*
G01X204331Y151754D02*
Y151756D01*
G01X204332Y151750D02*
X204331Y151754D01*
G01X213703Y134622D02*
Y134621D01*
G01X213702Y134624D02*
X213703Y134622D01*
G01X213702Y134627D02*
Y134624D01*
G01X212205Y151756D02*
X212204D01*
G01X212205Y151754D02*
Y151756D01*
G01X212206Y151750D02*
X212205Y151754D01*
G01X221577Y134622D02*
Y134621D01*
G01X221576Y134624D02*
X221577Y134622D01*
G01X221576Y134627D02*
Y134624D01*
G01X227953Y150771D02*
X227952Y150772D01*
G01X227953Y150768D02*
Y150771D01*
G01X227954Y150762D02*
X227953Y150768D01*
G01X229451Y135606D02*
Y135605D01*
G01X229450Y135610D02*
X229451Y135606D01*
G01X229450Y135615D02*
Y135610D01*
G01X235827Y150771D02*
X235826Y150772D01*
G01X235827Y150768D02*
Y150771D01*
G01X235828Y150762D02*
X235827Y150768D01*
G01X237325Y135606D02*
Y135605D01*
G01X237324Y135610D02*
X237325Y135606D01*
G01X237324Y135615D02*
Y135610D01*
G01X243701Y150771D02*
X243700Y150772D01*
G01X243701Y150768D02*
Y150771D01*
G01X243702Y150762D02*
X243701Y150768D01*
G01X245199Y135606D02*
X245200Y135605D01*
G01X245199Y135610D02*
Y135606D01*
G01X245198Y135615D02*
X245199Y135610D01*
G01X251564Y136197D02*
X251563Y136570D01*
G01X251566Y135887D02*
X251564Y136197D01*
G01X251570Y135680D02*
X251566Y135887D01*
G01X251574Y135605D02*
X251570Y135680D01*
G01X253084Y150180D02*
X253085Y149807D01*
G01X253081Y150490D02*
X253084Y150180D01*
G01X253078Y150698D02*
X253081Y150490D01*
G01X253074Y150772D02*
X253078Y150698D01*
G01X231626Y152484D02*
X231620Y152538D01*
G01X231632Y152353D02*
X231626Y152484D01*
G01X231638Y152147D02*
X231632Y152353D01*
G01X233652Y133893D02*
X233658Y133840D01*
G01X233645Y134024D02*
X233652Y133893D01*
G01X233640Y134231D02*
X233645Y134024D01*
G01X235558Y152484D02*
X235552Y152538D01*
G01X235564Y152353D02*
X235558Y152484D01*
G01X235570Y152147D02*
X235564Y152353D01*
G01X237593Y133893D02*
X237599Y133840D01*
G01X237587Y134024D02*
X237593Y133893D01*
G01X237581Y134231D02*
X237587Y134024D01*
G01X239500Y152484D02*
X239494Y152538D01*
G01X239506Y152353D02*
X239500Y152484D01*
G01X239512Y152147D02*
X239506Y152353D01*
G01X241526Y133893D02*
X241532Y133840D01*
G01X241520Y134024D02*
X241526Y133893D01*
G01X241514Y134231D02*
X241520Y134024D01*
G01X243432Y152484D02*
X243426Y152538D01*
G01X243438Y152353D02*
X243432Y152484D01*
G01X243444Y152147D02*
X243438Y152353D01*
G01X245467Y133893D02*
X245473Y133840D01*
G01X245461Y134024D02*
X245467Y133893D01*
G01X245455Y134231D02*
X245461Y134024D01*
G01X247374Y152484D02*
X247368Y152538D01*
G01X247380Y152353D02*
X247374Y152484D01*
G01X247386Y152147D02*
X247380Y152353D01*
G01X249400Y133893D02*
X249406Y133840D01*
G01X249394Y134024D02*
X249400Y133893D01*
G01X249388Y134231D02*
X249394Y134024D01*
G01X251306Y152484D02*
X251300Y152538D01*
G01X251312Y152353D02*
X251306Y152484D01*
G01X251318Y152147D02*
X251312Y152353D01*
G01X253341Y133893D02*
X253347Y133840D01*
G01X253335Y134024D02*
X253341Y133893D01*
G01X253329Y134231D02*
X253335Y134024D01*
G01X255248Y152484D02*
X255242Y152538D01*
G01X255254Y152353D02*
X255248Y152484D01*
G01X255260Y152147D02*
X255254Y152353D01*
G01X231624Y151511D02*
X231620Y151553D01*
G01X231629Y151413D02*
X231624Y151511D01*
G01X231633Y151260D02*
X231629Y151413D01*
G01X233653Y134866D02*
X233658Y134824D01*
G01X233649Y134965D02*
X233653Y134866D01*
G01X233645Y135117D02*
X233649Y134965D01*
G01X235557Y151511D02*
X235552Y151553D01*
G01X235561Y151413D02*
X235557Y151511D01*
G01X235565Y151260D02*
X235561Y151413D01*
G01X237595Y134866D02*
X237599Y134824D01*
G01X237590Y134965D02*
X237595Y134866D01*
G01X237586Y135117D02*
X237590Y134965D01*
G01X239498Y151511D02*
X239494Y151553D01*
G01X239503Y151413D02*
X239498Y151511D01*
G01X239507Y151260D02*
X239503Y151413D01*
G01X241527Y134866D02*
X241532Y134824D01*
G01X241523Y134965D02*
X241527Y134866D01*
G01X241519Y135117D02*
X241523Y134965D01*
G01X243431Y151511D02*
X243426Y151553D01*
G01X243435Y151413D02*
X243431Y151511D01*
G01X243439Y151260D02*
X243435Y151413D01*
G01X245469Y134866D02*
X245473Y134824D01*
G01X245464Y134965D02*
X245469Y134866D01*
G01X245460Y135117D02*
X245464Y134965D01*
G01X247372Y151511D02*
X247368Y151553D01*
G01X247377Y151413D02*
X247372Y151511D01*
G01X247381Y151260D02*
X247377Y151413D01*
G01X249401Y134866D02*
X249406Y134824D01*
G01X249397Y134965D02*
X249401Y134866D01*
G01X249393Y135117D02*
X249397Y134965D01*
G01X251305Y151511D02*
X251300Y151553D01*
G01X251309Y151413D02*
X251305Y151511D01*
G01X251313Y151260D02*
X251309Y151413D01*
G01X253343Y134866D02*
X253347Y134824D01*
G01X253338Y134965D02*
X253343Y134866D01*
G01X253334Y135117D02*
X253338Y134965D01*
G01X255246Y151511D02*
X255242Y151553D01*
G01X255251Y151413D02*
X255246Y151511D01*
G01X255255Y151260D02*
X255251Y151413D01*
G01X233396Y150733D02*
X233392Y150762D01*
G01X233400Y150537D02*
X233396Y150733D01*
G01X233403Y150209D02*
X233400Y150537D01*
G01X233404Y149807D02*
X233403Y150209D01*
G01X239755Y135645D02*
X239760Y135615D01*
G01X239751Y135841D02*
X239755Y135645D01*
G01X239748Y136168D02*
X239751Y135841D01*
G01X239747Y136570D02*
X239748Y136168D01*
G01X241270Y150733D02*
X241266Y150762D01*
G01X241274Y150537D02*
X241270Y150733D01*
G01X241277Y150209D02*
X241274Y150537D01*
G01X241278Y149807D02*
X241277Y150209D01*
G01X247629Y135645D02*
X247634Y135615D01*
G01X247625Y135841D02*
X247629Y135645D01*
G01X247622Y136168D02*
X247625Y135841D01*
G01X247621Y136570D02*
X247622Y136168D01*
G01X249144Y150733D02*
X249140Y150762D01*
G01X249148Y150537D02*
X249144Y150733D01*
G01X249151Y150209D02*
X249148Y150537D01*
G01X249152Y149807D02*
X249151Y150209D01*
G01X255503Y135645D02*
X255508Y135615D01*
G01X255499Y135841D02*
X255503Y135645D01*
G01X255496Y136168D02*
X255499Y135841D01*
G01X255495Y136570D02*
X255496Y136168D01*
G01X257018Y150733D02*
X257014Y150762D01*
G01X257022Y150537D02*
X257018Y150733D01*
G01X257025Y150209D02*
X257022Y150537D01*
G01X257026Y149807D02*
X257025Y150209D01*
G01X235818Y134770D02*
X235826Y134621D01*
G01X235811Y135184D02*
X235818Y134770D01*
G01X235806Y135804D02*
X235811Y135184D01*
G01X235804Y136551D02*
X235806Y135804D01*
G01X235822Y135678D02*
X235826Y135605D01*
G01X235818Y135887D02*
X235822Y135678D01*
G01X235816Y136200D02*
X235818Y135887D01*
G01X235815Y136570D02*
X235816Y136200D01*
G01X237330Y150699D02*
X237325Y150772D01*
G01X237333Y150490D02*
X237330Y150699D01*
G01X237336Y150178D02*
X237333Y150490D01*
G01X237336Y149807D02*
Y150178D01*
G01X237334Y151608D02*
X237325Y151756D01*
G01X237341Y151193D02*
X237334Y151608D01*
G01X237346Y150573D02*
X237341Y151193D01*
G01X237347Y149826D02*
X237346Y150573D01*
G01X243692Y134770D02*
X243700Y134621D01*
G01X243685Y135184D02*
X243692Y134770D01*
G01X243680Y135804D02*
X243685Y135184D01*
G01X243678Y136551D02*
X243680Y135804D01*
G01X243696Y135678D02*
X243700Y135605D01*
G01X243692Y135887D02*
X243696Y135678D01*
G01X243690Y136200D02*
X243692Y135887D01*
G01X243689Y136570D02*
X243690Y136200D01*
G01X245204Y150699D02*
X245200Y150772D01*
G01X245207Y150490D02*
X245204Y150699D01*
G01X245210Y150178D02*
X245207Y150490D01*
G01X245210Y149807D02*
Y150178D01*
G01X245208Y151608D02*
X245200Y151756D01*
G01X245215Y151193D02*
X245208Y151608D01*
G01X245220Y150573D02*
X245215Y151193D01*
G01X245221Y149826D02*
X245220Y150573D01*
G01X251566Y134770D02*
X251574Y134621D01*
G01X251559Y135184D02*
X251566Y134770D01*
G01X251554Y135804D02*
X251559Y135184D01*
G01X251552Y136551D02*
X251554Y135804D01*
G01X253082Y151608D02*
X253074Y151756D01*
G01X253089Y151193D02*
X253082Y151608D01*
G01X253094Y150573D02*
X253089Y151193D01*
G01X253095Y149826D02*
X253094Y150573D01*
G01X251570Y150698D02*
X251574Y150772D01*
G01X251566Y150490D02*
X251570Y150698D01*
G01X251564Y150180D02*
X251566Y150490D01*
G01X251563Y149807D02*
X251564Y150180D01*
G01X253078Y135680D02*
X253074Y135605D01*
G01X253081Y135887D02*
X253078Y135680D01*
G01X253084Y136197D02*
X253081Y135887D01*
G01X253085Y136570D02*
X253084Y136197D01*
G01X237346Y135804D02*
X237347Y136551D01*
G01X237341Y135184D02*
X237346Y135804D01*
G01X237334Y134770D02*
X237341Y135184D01*
G01X237325Y134621D02*
X237334Y134770D01*
G01X243680Y150573D02*
X243678Y149826D01*
G01X243685Y151193D02*
X243680Y150573D01*
G01X243692Y151608D02*
X243685Y151193D01*
G01X243700Y151756D02*
X243692Y151608D01*
G01X245220Y135804D02*
X245221Y136551D01*
G01X245215Y135184D02*
X245220Y135804D01*
G01X245208Y134770D02*
X245215Y135184D01*
G01X245200Y134621D02*
X245208Y134770D01*
G01X251554Y150573D02*
X251552Y149826D01*
G01X251559Y151193D02*
X251554Y150573D01*
G01X251566Y151608D02*
X251559Y151193D01*
G01X251574Y151756D02*
X251566Y151608D01*
G01X253094Y135804D02*
X253095Y136551D01*
G01X253089Y135184D02*
X253094Y135804D01*
G01X253082Y134770D02*
X253089Y135184D01*
G01X253074Y134621D02*
X253082Y134770D01*
G01X259428Y150573D02*
X259426Y149826D01*
G01X259433Y151193D02*
X259428Y150573D01*
G01X259440Y151608D02*
X259433Y151193D01*
G01X259448Y151756D02*
X259440Y151608D01*
G01X237336Y136200D02*
Y136570D01*
G01X237333Y135887D02*
X237336Y136200D01*
G01X237330Y135678D02*
X237333Y135887D01*
G01X237325Y135605D02*
X237330Y135678D01*
G01X243690Y150178D02*
X243689Y149807D01*
G01X243692Y150490D02*
X243690Y150178D01*
G01X243696Y150699D02*
X243692Y150490D01*
G01X243700Y150772D02*
X243696Y150699D01*
G01X245210Y136200D02*
Y136570D01*
G01X245207Y135887D02*
X245210Y136200D01*
G01X245204Y135678D02*
X245207Y135887D01*
G01X245200Y135605D02*
X245204Y135678D01*
G01X251575Y135606D02*
X251574Y135605D01*
G01X251575Y135610D02*
Y135606D01*
G01X251576Y135617D02*
X251575Y135610D01*
G01X253073Y150771D02*
X253074Y150772D01*
G01X253073Y150768D02*
Y150771D01*
G01X253072Y150760D02*
X253073Y150768D01*
G01X259449Y135606D02*
X259448Y135605D01*
G01X259449Y135610D02*
Y135606D01*
G01X259450Y135617D02*
X259449Y135610D01*
G01X260947Y150771D02*
X260948Y150772D01*
G01X260947Y150768D02*
Y150771D01*
G01X260946Y150760D02*
X260947Y150768D01*
G01X239493Y134965D02*
X239498Y135117D01*
G01X239489Y134866D02*
X239493Y134965D01*
G01X239484Y134824D02*
X239489Y134866D01*
G01X241532Y151413D02*
X241528Y151260D01*
G01X241537Y151511D02*
X241532Y151413D01*
G01X241541Y151553D02*
X241537Y151511D01*
G01X243435Y134965D02*
X243439Y135117D01*
G01X243431Y134866D02*
X243435Y134965D01*
G01X243426Y134824D02*
X243431Y134866D01*
G01X245464Y151413D02*
X245460Y151260D01*
G01X245469Y151511D02*
X245464Y151413D01*
G01X245473Y151553D02*
X245469Y151511D01*
G01X247367Y134965D02*
X247372Y135117D01*
G01X247363Y134866D02*
X247367Y134965D01*
G01X247359Y134824D02*
X247363Y134866D01*
G01X249406Y151413D02*
X249402Y151260D01*
G01X249411Y151511D02*
X249406Y151413D01*
G01X249415Y151553D02*
X249411Y151511D01*
G01X251309Y134965D02*
X251313Y135117D01*
G01X251305Y134866D02*
X251309Y134965D01*
G01X251300Y134824D02*
X251305Y134866D01*
G01X253338Y151413D02*
X253334Y151260D01*
G01X253343Y151511D02*
X253338Y151413D01*
G01X253347Y151553D02*
X253343Y151511D01*
G01X255241Y134965D02*
X255246Y135117D01*
G01X255237Y134866D02*
X255241Y134965D01*
G01X255233Y134824D02*
X255237Y134866D01*
G01X257280Y151413D02*
X257276Y151260D01*
G01X257285Y151511D02*
X257280Y151413D01*
G01X257289Y151553D02*
X257285Y151511D01*
G01X259183Y134965D02*
X259187Y135117D01*
G01X259179Y134866D02*
X259183Y134965D01*
G01X259174Y134824D02*
X259179Y134866D01*
G01X261212Y151413D02*
X261208Y151260D01*
G01X261217Y151511D02*
X261212Y151413D01*
G01X261221Y151553D02*
X261217Y151511D01*
G01X241529Y152353D02*
X241523Y152147D01*
G01X241535Y152484D02*
X241529Y152353D01*
G01X241541Y152538D02*
X241535Y152484D01*
G01X239497Y134024D02*
X239502Y134231D01*
G01X239491Y133893D02*
X239497Y134024D01*
G01X239484Y133840D02*
X239491Y133893D01*
G01X245461Y152353D02*
X245455Y152147D01*
G01X245467Y152484D02*
X245461Y152353D01*
G01X245473Y152538D02*
X245467Y152484D01*
G01X243438Y134024D02*
X243444Y134231D01*
G01X243432Y133893D02*
X243438Y134024D01*
G01X243426Y133840D02*
X243432Y133893D01*
G01X249403Y152353D02*
X249397Y152147D01*
G01X249409Y152484D02*
X249403Y152353D01*
G01X249415Y152538D02*
X249409Y152484D01*
G01X247371Y134024D02*
X247376Y134231D01*
G01X247365Y133893D02*
X247371Y134024D01*
G01X247359Y133840D02*
X247365Y133893D01*
G01X253335Y152353D02*
X253329Y152147D01*
G01X253341Y152484D02*
X253335Y152353D01*
G01X253347Y152538D02*
X253341Y152484D01*
G01X251312Y134024D02*
X251318Y134231D01*
G01X251306Y133893D02*
X251312Y134024D01*
G01X251300Y133840D02*
X251306Y133893D01*
G01X257277Y152353D02*
X257271Y152147D01*
G01X257283Y152484D02*
X257277Y152353D01*
G01X257289Y152538D02*
X257283Y152484D01*
G01X255245Y134024D02*
X255251Y134231D01*
G01X255239Y133893D02*
X255245Y134024D01*
G01X255233Y133840D02*
X255239Y133893D01*
G01X261209Y152353D02*
X261203Y152147D01*
G01X261215Y152484D02*
X261209Y152353D01*
G01X261221Y152538D02*
X261215Y152484D01*
G01X259186Y134024D02*
X259192Y134231D01*
G01X259180Y133893D02*
X259186Y134024D01*
G01X259174Y133840D02*
X259180Y133893D01*
G01X241268Y136168D02*
X241269Y136570D01*
G01X241265Y135841D02*
X241268Y136168D01*
G01X241261Y135645D02*
X241265Y135841D01*
G01X241256Y135615D02*
X241261Y135645D01*
G01X247632Y150209D02*
X247631Y149807D01*
G01X247635Y150537D02*
X247632Y150209D01*
G01X247639Y150733D02*
X247635Y150537D01*
G01X247643Y150762D02*
X247639Y150733D01*
G01X249142Y136168D02*
X249143Y136570D01*
G01X249139Y135841D02*
X249142Y136168D01*
G01X249135Y135645D02*
X249139Y135841D01*
G01X249130Y135615D02*
X249135Y135645D01*
G01X255506Y150209D02*
X255505Y149807D01*
G01X255509Y150537D02*
X255506Y150209D01*
G01X255513Y150733D02*
X255509Y150537D01*
G01X255517Y150762D02*
X255513Y150733D01*
G01X257016Y136168D02*
X257017Y136570D01*
G01X257013Y135841D02*
X257016Y136168D01*
G01X257009Y135645D02*
X257013Y135841D01*
G01X257004Y135615D02*
X257009Y135645D01*
G01X263380Y150209D02*
X263379Y149807D01*
G01X263383Y150537D02*
X263380Y150209D01*
G01X263387Y150733D02*
X263383Y150537D01*
G01X263391Y150762D02*
X263387Y150733D01*
G01X260946Y151754D02*
Y151750D01*
G01X260947Y151756D02*
X260946Y151754D01*
G01X260948Y151756D02*
X260947D01*
G01X251575Y134624D02*
X251576Y134627D01*
G01X251575Y134622D02*
Y134624D01*
G01X251574Y134621D02*
X251575Y134622D01*
G01X259449Y134624D02*
X259450Y134627D01*
G01X259449Y134622D02*
Y134624D01*
G01X259448Y134621D02*
X259449Y134622D01*
G01X220079Y151756D02*
X220078D01*
G01X220079Y151754D02*
Y151756D01*
G01X220080Y151750D02*
X220079Y151754D01*
G01X229451Y134622D02*
Y134621D01*
G01X229450Y134624D02*
X229451Y134622D01*
G01X229450Y134627D02*
Y134624D01*
G01X227953Y151756D02*
X227952D01*
G01X227953Y151754D02*
Y151756D01*
G01X227954Y151750D02*
X227953Y151754D01*
G01X237325Y134622D02*
Y134621D01*
G01X237324Y134624D02*
X237325Y134622D01*
G01X237324Y134627D02*
Y134624D01*
G01X235827Y151756D02*
X235826D01*
G01X235827Y151754D02*
Y151756D01*
G01X235828Y151750D02*
X235827Y151754D01*
G01X245199Y134622D02*
X245200Y134621D01*
G01X245198Y134624D02*
X245199Y134622D01*
G01X245198Y134627D02*
Y134624D01*
G01X243701Y151756D02*
X243700D01*
G01X243701Y151754D02*
Y151756D01*
G01X243702Y151750D02*
X243701Y151754D01*
G01X259438Y136197D02*
X259437Y136570D01*
G01X259440Y135887D02*
X259438Y136197D01*
G01X259444Y135680D02*
X259440Y135887D01*
G01X259448Y135605D02*
X259444Y135680D01*
G01X260958Y150180D02*
X260959Y149807D01*
G01X260955Y150490D02*
X260958Y150180D01*
G01X260952Y150698D02*
X260955Y150490D01*
G01X260948Y150772D02*
X260952Y150698D01*
G01X257274Y133893D02*
X257280Y133840D01*
G01X257268Y134024D02*
X257274Y133893D01*
G01X257262Y134231D02*
X257268Y134024D01*
G01X259180Y152484D02*
X259174Y152538D01*
G01X259186Y152353D02*
X259180Y152484D01*
G01X259192Y152147D02*
X259186Y152353D01*
G01X261215Y133893D02*
X261221Y133840D01*
G01X261209Y134024D02*
X261215Y133893D01*
G01X261203Y134231D02*
X261209Y134024D01*
G01X263122Y152484D02*
X263116Y152538D01*
G01X263128Y152353D02*
X263122Y152484D01*
G01X263134Y152147D02*
X263128Y152353D01*
G01X265148Y133893D02*
X265154Y133840D01*
G01X265142Y134024D02*
X265148Y133893D01*
G01X265136Y134231D02*
X265142Y134024D01*
G01X257275Y134866D02*
X257280Y134824D01*
G01X257271Y134965D02*
X257275Y134866D01*
G01X257267Y135117D02*
X257271Y134965D01*
G01X259179Y151511D02*
X259174Y151553D01*
G01X259183Y151413D02*
X259179Y151511D01*
G01X259187Y151260D02*
X259183Y151413D01*
G01X261217Y134866D02*
X261221Y134824D01*
G01X261212Y134965D02*
X261217Y134866D01*
G01X261208Y135117D02*
X261212Y134965D01*
G01X263120Y151511D02*
X263116Y151553D01*
G01X263125Y151413D02*
X263120Y151511D01*
G01X263129Y151260D02*
X263125Y151413D01*
G01X265149Y134866D02*
X265154Y134824D01*
G01X265145Y134965D02*
X265149Y134866D01*
G01X265141Y135117D02*
X265145Y134965D01*
G01X263377Y135645D02*
X263382Y135615D01*
G01X263373Y135841D02*
X263377Y135645D01*
G01X263370Y136168D02*
X263373Y135841D01*
G01X263369Y136570D02*
X263370Y136168D01*
G01X264892Y150733D02*
X264888Y150762D01*
G01X264896Y150537D02*
X264892Y150733D01*
G01X264899Y150209D02*
X264896Y150537D01*
G01X264900Y149807D02*
X264899Y150209D01*
G01X259440Y134770D02*
X259448Y134621D01*
G01X259433Y135184D02*
X259440Y134770D01*
G01X259428Y135804D02*
X259433Y135184D01*
G01X259426Y136551D02*
X259428Y135804D01*
G01X260956Y151608D02*
X260948Y151756D01*
G01X260963Y151193D02*
X260956Y151608D01*
G01X260968Y150573D02*
X260963Y151193D01*
G01X260969Y149826D02*
X260968Y150573D01*
G01X259444Y150698D02*
X259448Y150772D01*
G01X259440Y150490D02*
X259444Y150698D01*
G01X259438Y150180D02*
X259440Y150490D01*
G01X259437Y149807D02*
X259438Y150180D01*
G01X260952Y135680D02*
X260948Y135605D01*
G01X260955Y135887D02*
X260952Y135680D01*
G01X260958Y136197D02*
X260955Y135887D01*
G01X260959Y136570D02*
X260958Y136197D01*
G01X260968Y135804D02*
X260969Y136551D01*
G01X260963Y135184D02*
X260968Y135804D01*
G01X260956Y134770D02*
X260963Y135184D01*
G01X260948Y134621D02*
X260956Y134770D01*
G01X263115Y134965D02*
X263120Y135117D01*
G01X263111Y134866D02*
X263115Y134965D01*
G01X263107Y134824D02*
X263111Y134866D01*
G01X265154Y151413D02*
X265150Y151260D01*
G01X265159Y151511D02*
X265154Y151413D01*
G01X265163Y151553D02*
X265159Y151511D01*
G01X265151Y152353D02*
X265145Y152147D01*
G01X265157Y152484D02*
X265151Y152353D01*
G01X265163Y152538D02*
X265157Y152484D01*
G01X263119Y134024D02*
X263125Y134231D01*
G01X263113Y133893D02*
X263119Y134024D01*
G01X263107Y133840D02*
X263113Y133893D01*
G01X264890Y136168D02*
X264891Y136570D01*
G01X264887Y135841D02*
X264890Y136168D01*
G01X264883Y135645D02*
X264887Y135841D01*
G01X264878Y135615D02*
X264883Y135645D01*
G01X253073Y134622D02*
X253074Y134621D01*
G01X253072Y134624D02*
X253073Y134622D01*
G01X253072Y134627D02*
Y134624D01*
G01X251575Y151756D02*
X251574D01*
G01X251575Y151754D02*
Y151756D01*
G01X251576Y151750D02*
X251575Y151754D01*
G01X260947Y134622D02*
X260948Y134621D01*
G01X260946Y134624D02*
X260947Y134622D01*
G01X260946Y134627D02*
Y134624D01*
G01X259449Y151756D02*
X259448D01*
G01X259449Y151754D02*
Y151756D01*
G01X259450Y151750D02*
X259449Y151754D01*
G01X253073Y135610D02*
X253072Y135617D01*
G01X253073Y135606D02*
Y135610D01*
G01X253074Y135605D02*
X253073Y135606D01*
G01X251575Y150768D02*
X251576Y150760D01*
G01X251575Y150771D02*
Y150768D01*
G01X251574Y150772D02*
X251575Y150771D01*
G01X260947Y135610D02*
X260946Y135617D01*
G01X260947Y135606D02*
Y135610D01*
G01X260948Y135605D02*
X260947Y135606D01*
G01X259449Y150768D02*
X259450Y150760D01*
G01X259449Y150771D02*
Y150768D01*
G01X259448Y150772D02*
X259449Y150771D01*
G01X263077Y133838D02*
X263062D01*
G01X263092Y133839D02*
X263077Y133838D01*
G01X263107Y133840D02*
X263092Y133839D01*
G01X190370D02*
X190355Y133840D01*
G01X190385Y133838D02*
X190370Y133839D01*
G01X190400Y133838D02*
X190385D01*
G01X194303Y133839D02*
X194288Y133840D01*
G01X194318Y133838D02*
X194303Y133839D01*
G01X194333Y133838D02*
X194318D01*
G01X198244Y133839D02*
X198229Y133840D01*
G01X198259Y133838D02*
X198244Y133839D01*
G01X198274Y133838D02*
X198259D01*
G01X202177Y133839D02*
X202162Y133840D01*
G01X202192Y133838D02*
X202177Y133839D01*
G01X202207Y133838D02*
X202192D01*
G01X206118Y133839D02*
X206103Y133840D01*
G01X206133Y133838D02*
X206118Y133839D01*
G01X206148Y133838D02*
X206133D01*
G01X210051Y133839D02*
X210036Y133840D01*
G01X210066Y133838D02*
X210051Y133839D01*
G01X210081Y133838D02*
X210066D01*
G01X213992Y133839D02*
X213977Y133840D01*
G01X214007Y133838D02*
X213992Y133839D01*
G01X214022Y133838D02*
X214007D01*
G01X217925Y133839D02*
X217910Y133840D01*
G01X217940Y133838D02*
X217925Y133839D01*
G01X217955Y133838D02*
X217940D01*
G01X221866Y133839D02*
X221851Y133840D01*
G01X221881Y133838D02*
X221866Y133839D01*
G01X221896Y133838D02*
X221881D01*
G01X225799Y133839D02*
X225784Y133840D01*
G01X225814Y133838D02*
X225799Y133839D01*
G01X225829Y133838D02*
X225814D01*
G01X229740Y133839D02*
X229725Y133840D01*
G01X229755Y133838D02*
X229740Y133839D01*
G01X229770Y133838D02*
X229755D01*
G01X233673Y133839D02*
X233658Y133840D01*
G01X233688Y133838D02*
X233673Y133839D01*
G01X233703Y133838D02*
X233688D01*
G01X237614Y133839D02*
X237599Y133840D01*
G01X237629Y133838D02*
X237614Y133839D01*
G01X237644Y133838D02*
X237629D01*
G01X241547Y133839D02*
X241532Y133840D01*
G01X241562Y133838D02*
X241547Y133839D01*
G01X241577Y133838D02*
X241562D01*
G01X245488Y133839D02*
X245473Y133840D01*
G01X245503Y133838D02*
X245488Y133839D01*
G01X245518Y133838D02*
X245503D01*
G01X249421Y133839D02*
X249406Y133840D01*
G01X249436Y133838D02*
X249421Y133839D01*
G01X249451Y133838D02*
X249436D01*
G01X253362Y133839D02*
X253347Y133840D01*
G01X253377Y133838D02*
X253362Y133839D01*
G01X253392Y133838D02*
X253377D01*
G01X257295Y133839D02*
X257280Y133840D01*
G01X257310Y133838D02*
X257295Y133839D01*
G01X257325Y133838D02*
X257310D01*
G01X261236Y133839D02*
X261221Y133840D01*
G01X261251Y133838D02*
X261236Y133839D01*
G01X261266Y133838D02*
X261251D01*
G01X265169Y133839D02*
X265154Y133840D01*
G01X265184Y133838D02*
X265169Y133839D01*
G01X265199Y133838D02*
X265184D01*
G01X190370Y134823D02*
X190355Y134824D01*
G01X190385Y134823D02*
X190370D01*
G01X190400Y134822D02*
X190385Y134823D01*
G01X194303D02*
X194288Y134824D01*
G01X194318Y134823D02*
X194303D01*
G01X194333Y134822D02*
X194318Y134823D01*
G01X198244D02*
X198229Y134824D01*
G01X198259Y134823D02*
X198244D01*
G01X198274Y134822D02*
X198259Y134823D01*
G01X202177D02*
X202162Y134824D01*
G01X202192Y134823D02*
X202177D01*
G01X202207Y134822D02*
X202192Y134823D01*
G01X206118D02*
X206103Y134824D01*
G01X206133Y134823D02*
X206118D01*
G01X206148Y134822D02*
X206133Y134823D01*
G01X210051D02*
X210036Y134824D01*
G01X210066Y134823D02*
X210051D01*
G01X210081Y134822D02*
X210066Y134823D01*
G01X213992D02*
X213977Y134824D01*
G01X214007Y134823D02*
X213992D01*
G01X214022Y134822D02*
X214007Y134823D01*
G01X217925D02*
X217910Y134824D01*
G01X217940Y134823D02*
X217925D01*
G01X217955Y134822D02*
X217940Y134823D01*
G01X221866D02*
X221851Y134824D01*
G01X221881Y134823D02*
X221866D01*
G01X221896Y134822D02*
X221881Y134823D01*
G01X225799D02*
X225784Y134824D01*
G01X225814Y134823D02*
X225799D01*
G01X225829Y134822D02*
X225814Y134823D01*
G01X229740D02*
X229725Y134824D01*
G01X229755Y134823D02*
X229740D01*
G01X229770Y134822D02*
X229755Y134823D01*
G01X233673D02*
X233658Y134824D01*
G01X233688Y134823D02*
X233673D01*
G01X233703Y134822D02*
X233688Y134823D01*
G01X237614D02*
X237599Y134824D01*
G01X237629Y134823D02*
X237614D01*
G01X237644Y134822D02*
X237629Y134823D01*
G01X241547D02*
X241532Y134824D01*
G01X241562Y134823D02*
X241547D01*
G01X241577Y134822D02*
X241562Y134823D01*
G01X245488D02*
X245473Y134824D01*
G01X245503Y134823D02*
X245488D01*
G01X245518Y134822D02*
X245503Y134823D01*
G01X253362D02*
X253347Y134824D01*
G01X253377Y134823D02*
X253362D01*
G01X253392Y134822D02*
X253377Y134823D01*
G01X261236D02*
X261221Y134824D01*
G01X261251Y134823D02*
X261236D01*
G01X261266Y134822D02*
X261251Y134823D01*
G01X265169D02*
X265154Y134824D01*
G01X265184Y134823D02*
X265169D01*
G01X265199Y134822D02*
X265184Y134823D01*
G01X249436D02*
X249451Y134822D01*
G01X249421Y134823D02*
X249436D01*
G01X249406Y134824D02*
X249421Y134823D01*
G01X257310D02*
X257325Y134822D01*
G01X257295Y134823D02*
X257310D01*
G01X257280Y134824D02*
X257295Y134823D01*
G01X263077D02*
X263062Y134822D01*
G01X263092Y134823D02*
X263077D01*
G01X263107Y134824D02*
X263092Y134823D01*
G01X259144D02*
X259129Y134822D01*
G01X259159Y134823D02*
X259144D01*
G01X259174Y134824D02*
X259159Y134823D01*
G01X251270D02*
X251255Y134822D01*
G01X251285Y134823D02*
X251270D01*
G01X251300Y134824D02*
X251285Y134823D01*
G01X243396D02*
X243381Y134822D01*
G01X243411Y134823D02*
X243396D01*
G01X243426Y134824D02*
X243411Y134823D01*
G01X239454D02*
X239439Y134822D01*
G01X239469Y134823D02*
X239454D01*
G01X239484Y134824D02*
X239469Y134823D01*
G01X235522D02*
X235507Y134822D01*
G01X235537Y134823D02*
X235522D01*
G01X235552Y134824D02*
X235537Y134823D01*
G01X231580D02*
X231565Y134822D01*
G01X231595Y134823D02*
X231580D01*
G01X231610Y134824D02*
X231595Y134823D01*
G01X227648D02*
X227633Y134822D01*
G01X227663Y134823D02*
X227648D01*
G01X227678Y134824D02*
X227663Y134823D01*
G01X223706D02*
X223691Y134822D01*
G01X223721Y134823D02*
X223706D01*
G01X223736Y134824D02*
X223721Y134823D01*
G01X219774D02*
X219759Y134822D01*
G01X219789Y134823D02*
X219774D01*
G01X219804Y134824D02*
X219789Y134823D01*
G01X215832D02*
X215817Y134822D01*
G01X215847Y134823D02*
X215832D01*
G01X215862Y134824D02*
X215847Y134823D01*
G01X211900D02*
X211885Y134822D01*
G01X211915Y134823D02*
X211900D01*
G01X211930Y134824D02*
X211915Y134823D01*
G01X207958D02*
X207943Y134822D01*
G01X207973Y134823D02*
X207958D01*
G01X207988Y134824D02*
X207973Y134823D01*
G01X204026D02*
X204011Y134822D01*
G01X204041Y134823D02*
X204026D01*
G01X204056Y134824D02*
X204041Y134823D01*
G01X200084D02*
X200069Y134822D01*
G01X200099Y134823D02*
X200084D01*
G01X200114Y134824D02*
X200099Y134823D01*
G01X196152D02*
X196137Y134822D01*
G01X196167Y134823D02*
X196152D01*
G01X196182Y134824D02*
X196167Y134823D01*
G01X192210D02*
X192195Y134822D01*
G01X192225Y134823D02*
X192210D01*
G01X192240Y134824D02*
X192225Y134823D01*
G01X188278D02*
X188263Y134822D01*
G01X188293Y134823D02*
X188278D01*
G01X188308Y134824D02*
X188293Y134823D01*
G01X261251Y151555D02*
X261266D01*
G01X261236Y151554D02*
X261251Y151555D01*
G01X261221Y151553D02*
X261236Y151554D01*
G01X257319Y151555D02*
X257334D01*
G01X257304Y151554D02*
X257319Y151555D01*
G01X257289Y151553D02*
X257304Y151554D01*
G01X253377Y151555D02*
X253392D01*
G01X253362Y151554D02*
X253377Y151555D01*
G01X253347Y151553D02*
X253362Y151554D01*
G01X249445Y151555D02*
X249460D01*
G01X249430Y151554D02*
X249445Y151555D01*
G01X249415Y151553D02*
X249430Y151554D01*
G01X245503Y151555D02*
X245518D01*
G01X245488Y151554D02*
X245503Y151555D01*
G01X245473Y151553D02*
X245488Y151554D01*
G01X241571Y151555D02*
X241586D01*
G01X241556Y151554D02*
X241571Y151555D01*
G01X241541Y151553D02*
X241556Y151554D01*
G01X237629Y151555D02*
X237644D01*
G01X237614Y151554D02*
X237629Y151555D01*
G01X237599Y151553D02*
X237614Y151554D01*
G01X229755Y151555D02*
X229770D01*
G01X229740Y151554D02*
X229755Y151555D01*
G01X229725Y151553D02*
X229740Y151554D01*
G01X221881Y151555D02*
X221896D01*
G01X221866Y151554D02*
X221881Y151555D01*
G01X221851Y151553D02*
X221866Y151554D01*
G01X217949Y151555D02*
X217964D01*
G01X217934Y151554D02*
X217949Y151555D01*
G01X217919Y151553D02*
X217934Y151554D01*
G01X214007Y151555D02*
X214022D01*
G01X213992Y151554D02*
X214007Y151555D01*
G01X213977Y151553D02*
X213992Y151554D01*
G01X210075Y151555D02*
X210090D01*
G01X210060Y151554D02*
X210075Y151555D01*
G01X210045Y151553D02*
X210060Y151554D01*
G01X206133Y151555D02*
X206148D01*
G01X206118Y151554D02*
X206133Y151555D01*
G01X206103Y151553D02*
X206118Y151554D01*
G01X198259Y151555D02*
X198274D01*
G01X198244Y151554D02*
X198259Y151555D01*
G01X198229Y151553D02*
X198244Y151554D01*
G01X190385Y151555D02*
X190400D01*
G01X190370Y151554D02*
X190385Y151555D01*
G01X190355Y151553D02*
X190370Y151554D01*
G01X255203Y133838D02*
X255187D01*
G01X255217Y133839D02*
X255203Y133838D01*
G01X255233Y133840D02*
X255217Y133839D01*
G01X247328Y133838D02*
X247313D01*
G01X247343Y133839D02*
X247328Y133838D01*
G01X247359Y133840D02*
X247343Y133839D01*
G01X243396Y133838D02*
X243381D01*
G01X243411Y133839D02*
X243396Y133838D01*
G01X243426Y133840D02*
X243411Y133839D01*
G01X239454Y133838D02*
X239439D01*
G01X239469Y133839D02*
X239454Y133838D01*
G01X239484Y133840D02*
X239469Y133839D01*
G01X235522Y133838D02*
X235507D01*
G01X235537Y133839D02*
X235522Y133838D01*
G01X235552Y133840D02*
X235537Y133839D01*
G01X231580Y133838D02*
X231565D01*
G01X231595Y133839D02*
X231580Y133838D01*
G01X231610Y133840D02*
X231595Y133839D01*
G01X227648Y133838D02*
X227633D01*
G01X227663Y133839D02*
X227648Y133838D01*
G01X227678Y133840D02*
X227663Y133839D01*
G01X223706Y133838D02*
X223691D01*
G01X223721Y133839D02*
X223706Y133838D01*
G01X223736Y133840D02*
X223721Y133839D01*
G01X219774Y133838D02*
X219759D01*
G01X219789Y133839D02*
X219774Y133838D01*
G01X219804Y133840D02*
X219789Y133839D01*
G01X215832Y133838D02*
X215817D01*
G01X215847Y133839D02*
X215832Y133838D01*
G01X215862Y133840D02*
X215847Y133839D01*
G01X211900Y133838D02*
X211885D01*
G01X211915Y133839D02*
X211900Y133838D01*
G01X211930Y133840D02*
X211915Y133839D01*
G01X207958Y133838D02*
X207943D01*
G01X207973Y133839D02*
X207958Y133838D01*
G01X207988Y133840D02*
X207973Y133839D01*
G01X204026Y133838D02*
X204011D01*
G01X204041Y133839D02*
X204026Y133838D01*
G01X204056Y133840D02*
X204041Y133839D01*
G01X200084Y133838D02*
X200069D01*
G01X200099Y133839D02*
X200084Y133838D01*
G01X200114Y133840D02*
X200099Y133839D01*
G01X196152Y133838D02*
X196137D01*
G01X196167Y133839D02*
X196152Y133838D01*
G01X196182Y133840D02*
X196167Y133839D01*
G01X192210Y133838D02*
X192195D01*
G01X192225Y133839D02*
X192210Y133838D01*
G01X192240Y133840D02*
X192225Y133839D01*
G01X265193Y152539D02*
X265208D01*
G01X265178Y152538D02*
X265193Y152539D01*
G01X265163Y152538D02*
X265178D01*
G01X249445Y152539D02*
X249460D01*
G01X249430Y152538D02*
X249445Y152539D01*
G01X249415Y152538D02*
X249430D01*
G01X245503Y152539D02*
X245518D01*
G01X245488Y152538D02*
X245503Y152539D01*
G01X245473Y152538D02*
X245488D01*
G01X241571Y152539D02*
X241586D01*
G01X241556Y152538D02*
X241571Y152539D01*
G01X241541Y152538D02*
X241556D01*
G01X237629Y152539D02*
X237644D01*
G01X237614Y152538D02*
X237629Y152539D01*
G01X237599Y152538D02*
X237614D01*
G01X233697Y152539D02*
X233712D01*
G01X233682Y152538D02*
X233697Y152539D01*
G01X233667Y152538D02*
X233682D01*
G01X229755Y152539D02*
X229770D01*
G01X229740Y152538D02*
X229755Y152539D01*
G01X229725Y152538D02*
X229740D01*
G01X225823Y152539D02*
X225838D01*
G01X225808Y152538D02*
X225823Y152539D01*
G01X225793Y152538D02*
X225808D01*
G01X221881Y152539D02*
X221896D01*
G01X221866Y152538D02*
X221881Y152539D01*
G01X221851Y152538D02*
X221866D01*
G01X217949Y152539D02*
X217964D01*
G01X217934Y152538D02*
X217949Y152539D01*
G01X217919Y152538D02*
X217934D01*
G01X214007Y152539D02*
X214022D01*
G01X213992Y152538D02*
X214007Y152539D01*
G01X213977Y152538D02*
X213992D01*
G01X210075Y152539D02*
X210090D01*
G01X210060Y152538D02*
X210075Y152539D01*
G01X210045Y152538D02*
X210060D01*
G01X206133Y152539D02*
X206148D01*
G01X206118Y152538D02*
X206133Y152539D01*
G01X206103Y152538D02*
X206118D01*
G01X202201Y152539D02*
X202216D01*
G01X202186Y152538D02*
X202201Y152539D01*
G01X202171Y152538D02*
X202186D01*
G01X198259Y152539D02*
X198274D01*
G01X198244Y152538D02*
X198259Y152539D01*
G01X198229Y152538D02*
X198244D01*
G01X194327Y152539D02*
X194342D01*
G01X194312Y152538D02*
X194327Y152539D01*
G01X194297Y152538D02*
X194312D01*
G01X188293D02*
X188308D01*
G01X188278Y152539D02*
X188293Y152538D01*
G01X188263Y152539D02*
X188278D01*
G01X192235Y152538D02*
X192250D01*
G01X192220Y152539D02*
X192235Y152538D01*
G01X192205Y152539D02*
X192220D01*
G01X196167Y152538D02*
X196182D01*
G01X196152Y152539D02*
X196167Y152538D01*
G01X196137Y152539D02*
X196152D01*
G01X200109Y152538D02*
X200124D01*
G01X200094Y152539D02*
X200109Y152538D01*
G01X200079Y152539D02*
X200094D01*
G01X204041Y152538D02*
X204056D01*
G01X204026Y152539D02*
X204041Y152538D01*
G01X204011Y152539D02*
X204026D01*
G01X207983Y152538D02*
X207998D01*
G01X207968Y152539D02*
X207983Y152538D01*
G01X207953Y152539D02*
X207968D01*
G01X211915Y152538D02*
X211930D01*
G01X211900Y152539D02*
X211915Y152538D01*
G01X211885Y152539D02*
X211900D01*
G01X215857Y152538D02*
X215872D01*
G01X215842Y152539D02*
X215857Y152538D01*
G01X215827Y152539D02*
X215842D01*
G01X219789Y152538D02*
X219804D01*
G01X219774Y152539D02*
X219789Y152538D01*
G01X219759Y152539D02*
X219774D01*
G01X223731Y152538D02*
X223746D01*
G01X223716Y152539D02*
X223731Y152538D01*
G01X223701Y152539D02*
X223716D01*
G01X227663Y152538D02*
X227678D01*
G01X227648Y152539D02*
X227663Y152538D01*
G01X227633Y152539D02*
X227648D01*
G01X231605Y152538D02*
X231620D01*
G01X231590Y152539D02*
X231605Y152538D01*
G01X231575Y152539D02*
X231590D01*
G01X235537Y152538D02*
X235552D01*
G01X235522Y152539D02*
X235537Y152538D01*
G01X235507Y152539D02*
X235522D01*
G01X239479Y152538D02*
X239494D01*
G01X239464Y152539D02*
X239479Y152538D01*
G01X239449Y152539D02*
X239464D01*
G01X243411Y152538D02*
X243426D01*
G01X243396Y152539D02*
X243411Y152538D01*
G01X243381Y152539D02*
X243396D01*
G01X247353Y152538D02*
X247368D01*
G01X247338Y152539D02*
X247353Y152538D01*
G01X247323Y152539D02*
X247338D01*
G01X251285Y152538D02*
X251300D01*
G01X251270Y152539D02*
X251285Y152538D01*
G01X251255Y152539D02*
X251270D01*
G01X255227Y152538D02*
X255242D01*
G01X255212Y152539D02*
X255227Y152538D01*
G01X255197Y152539D02*
X255212D01*
G01X259159Y152538D02*
X259174D01*
G01X259144Y152539D02*
X259159Y152538D01*
G01X259129Y152539D02*
X259144D01*
G01X263101Y152538D02*
X263116D01*
G01X263086Y152539D02*
X263101Y152538D01*
G01X263071Y152539D02*
X263086D01*
G01X188293Y151554D02*
X188308Y151553D01*
G01X188278Y151555D02*
X188293Y151554D01*
G01X188263Y151555D02*
X188278D01*
G01X192235Y151554D02*
X192250Y151553D01*
G01X192220Y151555D02*
X192235Y151554D01*
G01X192205Y151555D02*
X192220D01*
G01X196167Y151554D02*
X196182Y151553D01*
G01X196152Y151555D02*
X196167Y151554D01*
G01X196137Y151555D02*
X196152D01*
G01X200109Y151554D02*
X200124Y151553D01*
G01X200094Y151555D02*
X200109Y151554D01*
G01X200079Y151555D02*
X200094D01*
G01X204041Y151554D02*
X204056Y151553D01*
G01X204026Y151555D02*
X204041Y151554D01*
G01X204011Y151555D02*
X204026D01*
G01X211915Y151554D02*
X211930Y151553D01*
G01X211900Y151555D02*
X211915Y151554D01*
G01X211885Y151555D02*
X211900D01*
G01X219789Y151554D02*
X219804Y151553D01*
G01X219774Y151555D02*
X219789Y151554D01*
G01X219759Y151555D02*
X219774D01*
G01X223731Y151554D02*
X223746Y151553D01*
G01X223716Y151555D02*
X223731Y151554D01*
G01X223701Y151555D02*
X223716D01*
G01X227663Y151554D02*
X227678Y151553D01*
G01X227648Y151555D02*
X227663Y151554D01*
G01X227633Y151555D02*
X227648D01*
G01X231605Y151554D02*
X231620Y151553D01*
G01X231590Y151555D02*
X231605Y151554D01*
G01X231575Y151555D02*
X231590D01*
G01X235537Y151554D02*
X235552Y151553D01*
G01X235522Y151555D02*
X235537Y151554D01*
G01X235507Y151555D02*
X235522D01*
G01X243411Y151554D02*
X243426Y151553D01*
G01X243396Y151555D02*
X243411Y151554D01*
G01X243381Y151555D02*
X243396D01*
G01X247353Y151554D02*
X247368Y151553D01*
G01X247338Y151555D02*
X247353Y151554D01*
G01X247323Y151555D02*
X247338D01*
G01X251285Y151554D02*
X251300Y151553D01*
G01X251270Y151555D02*
X251285Y151554D01*
G01X251255Y151555D02*
X251270D01*
G01X255227Y151554D02*
X255242Y151553D01*
G01X255212Y151555D02*
X255227Y151554D01*
G01X255197Y151555D02*
X255212D01*
G01X259159Y151554D02*
X259174Y151553D01*
G01X259144Y151555D02*
X259159Y151554D01*
G01X259129Y151555D02*
X259144D01*
G01X263101Y151554D02*
X263116Y151553D01*
G01X263086Y151555D02*
X263101Y151554D01*
G01X263071Y151555D02*
X263086D01*
G01X207968D02*
X207953D01*
G01X207983Y151554D02*
X207968Y151555D01*
G01X207998Y151553D02*
X207983Y151554D01*
G01X215842Y151555D02*
X215827D01*
G01X215857Y151554D02*
X215842Y151555D01*
G01X215872Y151553D02*
X215857Y151554D01*
G01X239464Y151555D02*
X239449D01*
G01X239479Y151554D02*
X239464Y151555D01*
G01X239494Y151553D02*
X239479Y151554D01*
G01X190001Y129943D02*
X190158Y129981D01*
G01X188505D02*
X188662Y129943D01*
G01X190001Y130965D02*
X190158Y131039D01*
G01X188505D02*
X188662Y130965D01*
G01X188263Y133838D02*
X188308Y133840D01*
G01X188584Y134627D02*
X188595Y134640D01*
G01X190068D02*
X190080Y134627D01*
G01X188662Y156434D02*
X188505Y156396D01*
G01X190158D02*
X190001Y156434D01*
G01X188662Y155412D02*
X188505Y155338D01*
G01X190158D02*
X190001Y155412D01*
G01X188595Y151737D02*
X188584Y151750D01*
G01X190080D02*
X190068Y151737D01*
G01X190400Y152539D02*
X190355Y152538D01*
G01X194001Y134640D02*
X194012Y134627D01*
G01X192516D02*
X192528Y134640D01*
G01X194095Y138680D02*
X193938Y138717D01*
G01X192599D02*
X192442Y138680D01*
G01X194095Y137621D02*
X193938Y137696D01*
G01X192599D02*
X192442Y137621D01*
G01Y147698D02*
X192599Y147660D01*
G01X192442Y148756D02*
X192599Y148681D01*
G01X193938D02*
X194095Y148756D01*
G01X193938Y147660D02*
X194095Y147698D01*
G01X194342Y151555D02*
X194297Y151553D01*
G01X192537Y151737D02*
X192525Y151750D01*
G01X194021D02*
X194010Y151737D01*
G01X196379Y129981D02*
X196536Y129943D01*
G01X197875D02*
X198032Y129981D01*
G01X196379Y131039D02*
X196536Y130965D01*
G01X197875D02*
X198032Y131039D01*
G01X196458Y134627D02*
X196469Y134640D01*
G01X197942D02*
X197954Y134627D01*
G01X198032Y156396D02*
X197875Y156434D01*
G01X196536D02*
X196379Y156396D01*
G01X198032Y155338D02*
X197875Y155412D01*
G01X196536D02*
X196379Y155338D01*
G01X196469Y151737D02*
X196458Y151750D01*
G01X197954D02*
X197942Y151737D01*
G01X201875Y134640D02*
X201886Y134627D01*
G01X200390D02*
X200402Y134640D01*
G01X201969Y138680D02*
X201812Y138717D01*
G01X200473D02*
X200316Y138680D01*
G01X201969Y137621D02*
X201812Y137696D01*
G01X200473D02*
X200316Y137621D01*
G01Y147698D02*
X200473Y147660D01*
G01X200316Y148756D02*
X200473Y148681D01*
G01X201812D02*
X201969Y148756D01*
G01X201812Y147660D02*
X201969Y147698D01*
G01X202216Y151555D02*
X202171Y151553D01*
G01X200411Y151737D02*
X200399Y151750D01*
G01X201895D02*
X201884Y151737D01*
G01X204253Y129981D02*
X204410Y129943D01*
G01X205749D02*
X205906Y129981D01*
G01X204253Y131039D02*
X204410Y130965D01*
G01X205749D02*
X205906Y131039D01*
G01X204332Y134627D02*
X204343Y134640D01*
G01X205816D02*
X205828Y134627D01*
G01X205906Y156396D02*
X205749Y156434D01*
G01X204410D02*
X204253Y156396D01*
G01X205906Y155338D02*
X205749Y155412D01*
G01X204410D02*
X204253Y155338D01*
G01X204343Y151737D02*
X204332Y151750D01*
G01X205828D02*
X205816Y151737D01*
G01X209749Y134640D02*
X209760Y134627D01*
G01X208264D02*
X208276Y134640D01*
G01X209843Y138680D02*
X209686Y138717D01*
G01X208347D02*
X208190Y138680D01*
G01X209843Y137621D02*
X209686Y137696D01*
G01X208347D02*
X208190Y137621D01*
G01Y147698D02*
X208347Y147660D01*
G01X209686D02*
X209843Y147698D01*
G01X208190Y148756D02*
X208347Y148681D01*
G01X209686D02*
X209843Y148756D01*
G01X208285Y151737D02*
X208273Y151750D01*
G01X209769D02*
X209758Y151737D01*
G01X212127Y129981D02*
X212284Y129943D01*
G01X213623D02*
X213780Y129981D01*
G01X212127Y131039D02*
X212284Y130965D01*
G01X213623D02*
X213780Y131039D01*
G01X212206Y134627D02*
X212217Y134640D01*
G01X213690D02*
X213702Y134627D01*
G01X213780Y156396D02*
X213623Y156434D01*
G01X212284D02*
X212127Y156396D01*
G01X213780Y155338D02*
X213623Y155412D01*
G01X212284D02*
X212127Y155338D01*
G01X212217Y151737D02*
X212206Y151750D01*
G01X213702D02*
X213690Y151737D01*
G01X217623Y134640D02*
X217634Y134627D01*
G01X216138D02*
X216150Y134640D01*
G01X217717Y138680D02*
X217560Y138717D01*
G01X216221D02*
X216064Y138680D01*
G01X217717Y137621D02*
X217560Y137696D01*
G01X216221D02*
X216064Y137621D01*
G01Y147698D02*
X216221Y147660D01*
G01X217560D02*
X217717Y147698D01*
G01X216064Y148756D02*
X216221Y148681D01*
G01X217560D02*
X217717Y148756D01*
G01X216159Y151737D02*
X216147Y151750D01*
G01X217643D02*
X217632Y151737D01*
G01X220001Y129981D02*
X220158Y129943D01*
G01X221497D02*
X221655Y129981D01*
G01X220001Y131039D02*
X220158Y130965D01*
G01X221497D02*
X221655Y131039D01*
G01X220080Y134627D02*
X220091Y134640D01*
G01X221564D02*
X221576Y134627D01*
G01X221655Y156396D02*
X221497Y156434D01*
G01X220158D02*
X220001Y156396D01*
G01X221655Y155338D02*
X221497Y155412D01*
G01X220158D02*
X220001Y155338D01*
G01X220091Y151737D02*
X220080Y151750D01*
G01X221576D02*
X221564Y151737D01*
G01X225497Y134640D02*
X225508Y134627D01*
G01X224012D02*
X224024Y134640D01*
G01X225592Y138680D02*
X225434Y138717D01*
G01X224095D02*
X223938Y138680D01*
G01X225592Y137621D02*
X225434Y137696D01*
G01X224095D02*
X223938Y137621D01*
G01Y147698D02*
X224095Y147660D01*
G01X223938Y148756D02*
X224095Y148681D01*
G01X225434D02*
X225592Y148756D01*
G01X225434Y147660D02*
X225592Y147698D01*
G01X225838Y151555D02*
X225793Y151553D01*
G01X224033Y151737D02*
X224021Y151750D01*
G01X225517D02*
X225506Y151737D01*
G01X227875Y129981D02*
X228032Y129943D01*
G01X229371D02*
X229529Y129981D01*
G01X227875Y131039D02*
X228032Y130965D01*
G01X229371D02*
X229529Y131039D01*
G01X227954Y134627D02*
X227965Y134640D01*
G01X229438D02*
X229450Y134627D01*
G01X229529Y156396D02*
X229371Y156434D01*
G01X228032D02*
X227875Y156396D01*
G01X229529Y155338D02*
X229371Y155412D01*
G01X228032D02*
X227875Y155338D01*
G01X227965Y151737D02*
X227954Y151750D01*
G01X229450D02*
X229438Y151737D01*
G01X233371Y134640D02*
X233382Y134627D01*
G01X231886D02*
X231898Y134640D01*
G01X233466Y138680D02*
X233308Y138717D01*
G01X231969D02*
X231812Y138680D01*
G01X233466Y137621D02*
X233308Y137696D01*
G01X231969D02*
X231812Y137621D01*
G01Y147698D02*
X231969Y147660D01*
G01X231812Y148756D02*
X231969Y148681D01*
G01X233308D02*
X233466Y148756D01*
G01X233308Y147660D02*
X233466Y147698D01*
G01X233712Y151555D02*
X233667Y151553D01*
G01X231907Y151737D02*
X231895Y151750D01*
G01X233391D02*
X233380Y151737D01*
G01X235749Y129981D02*
X235906Y129943D01*
G01X237245D02*
X237403Y129981D01*
G01X235749Y131039D02*
X235906Y130965D01*
G01X237245D02*
X237403Y131039D01*
G01X235828Y134627D02*
X235839Y134640D01*
G01X237312D02*
X237324Y134627D01*
G01X237403Y156396D02*
X237245Y156434D01*
G01X235906D02*
X235749Y156396D01*
G01X237403Y155338D02*
X237245Y155412D01*
G01X235906D02*
X235749Y155338D01*
G01X235839Y151737D02*
X235828Y151750D01*
G01X237324D02*
X237312Y151737D01*
G01X241245Y134640D02*
X241256Y134627D01*
G01X239760D02*
X239772Y134640D01*
G01X241340Y138680D02*
X241182Y138717D01*
G01X239843D02*
X239686Y138680D01*
G01X241340Y137621D02*
X241182Y137696D01*
G01X239843D02*
X239686Y137621D01*
G01Y147698D02*
X239843Y147660D01*
G01X241182D02*
X241340Y147698D01*
G01X239686Y148756D02*
X239843Y148681D01*
G01X241182D02*
X241340Y148756D01*
G01X239781Y151737D02*
X239769Y151750D01*
G01X241265D02*
X241254Y151737D01*
G01X243623Y129981D02*
X243780Y129943D01*
G01X245119D02*
X245277Y129981D01*
G01X243623Y131039D02*
X243780Y130965D01*
G01X245119D02*
X245277Y131039D01*
G01X243702Y134627D02*
X243713Y134640D01*
G01X245186D02*
X245198Y134627D01*
G01X245277Y156396D02*
X245119Y156434D01*
G01X243780D02*
X243623Y156396D01*
G01X245277Y155338D02*
X245119Y155412D01*
G01X243780D02*
X243623Y155338D01*
G01X243713Y151737D02*
X243702Y151750D01*
G01X245198D02*
X245186Y151737D01*
G01X249119Y134640D02*
X249130Y134627D01*
G01X247634D02*
X247646Y134640D01*
G01X247313Y134822D02*
X247359Y134824D01*
G01X247717Y138717D02*
X247560Y138680D01*
G01X249214D02*
X249056Y138717D01*
G01X247717Y137696D02*
X247560Y137621D01*
G01X249214D02*
X249056Y137696D01*
G01X247655Y151737D02*
X247643Y151750D01*
G01X249139D02*
X249128Y151737D01*
G01X249056Y147660D02*
X249214Y147698D01*
G01X247560D02*
X247717Y147660D01*
G01X249056Y148681D02*
X249214Y148756D01*
G01X247560D02*
X247717Y148681D01*
G01X252993Y129943D02*
X253151Y129981D01*
G01X251497D02*
X251655Y129943D01*
G01X252993Y130965D02*
X253151Y131039D01*
G01X251497D02*
X251655Y130965D01*
G01X251255Y133838D02*
X251300Y133840D01*
G01X251576Y134627D02*
X251587Y134640D01*
G01X253060D02*
X253072Y134627D01*
G01X251655Y156434D02*
X251497Y156396D01*
G01X253151D02*
X252993Y156434D01*
G01X251655Y155412D02*
X251497Y155338D01*
G01X253151D02*
X252993Y155412D01*
G01X251587Y151737D02*
X251576Y151750D01*
G01X253072D02*
X253060Y151737D01*
G01X253392Y152539D02*
X253347Y152538D01*
G01X257088Y138680D02*
X256930Y138717D01*
G01X255592D02*
X255434Y138680D01*
G01X255592Y137696D02*
X255434Y137621D01*
G01X257088D02*
X256930Y137696D01*
G01X256993Y134640D02*
X257004Y134627D01*
G01X255508D02*
X255520Y134640D01*
G01X255187Y134822D02*
X255233Y134824D01*
G01X255434Y147698D02*
X255592Y147660D01*
G01X256930Y148681D02*
X257088Y148756D01*
G01X255434D02*
X255592Y148681D01*
G01X256930Y147660D02*
X257088Y147698D01*
G01X255529Y151737D02*
X255517Y151750D01*
G01X257014D02*
X257002Y151737D01*
G01X257334Y152539D02*
X257289Y152538D01*
G01X260867Y129943D02*
X261025Y129981D01*
G01X259371D02*
X259529Y129943D01*
G01X260867Y130965D02*
X261025Y131039D01*
G01X259371D02*
X259529Y130965D01*
G01X259129Y133838D02*
X259174Y133840D01*
G01X259450Y134627D02*
X259461Y134640D01*
G01X260934D02*
X260946Y134627D01*
G01X259529Y156434D02*
X259371Y156396D01*
G01X261025D02*
X260867Y156434D01*
G01X259529Y155412D02*
X259371Y155338D01*
G01X261025D02*
X260867Y155412D01*
G01X259461Y151737D02*
X259450Y151750D01*
G01X260946D02*
X260934Y151737D01*
G01X261266Y152539D02*
X261221Y152538D01*
G01X264867Y134640D02*
X264878Y134627D01*
G01X263382D02*
X263394Y134640D01*
G01X264962Y138680D02*
X264804Y138717D01*
G01X263466D02*
X263308Y138680D01*
G01X264962Y137621D02*
X264804Y137696D01*
G01X263466D02*
X263308Y137621D01*
G01Y147698D02*
X263466Y147660D01*
G01X263308Y148756D02*
X263466Y148681D01*
G01X264804D02*
X264962Y148756D01*
G01X264804Y147660D02*
X264962Y147698D01*
G01X265208Y151555D02*
X265163Y151553D01*
G01X263403Y151737D02*
X263391Y151750D01*
G01X264888D02*
X264876Y151737D01*
G01X190513Y156476D02*
X188151D01*
G01X194450D02*
X192088D01*
G01X198387D02*
X196025D01*
G01X202324D02*
X199962D01*
G01X206261D02*
X203899D01*
G01X210198D02*
X207836D01*
G01X214135D02*
X211773D01*
G01X218072D02*
X215710D01*
G01X222009D02*
X219647D01*
G01X225946D02*
X223584D01*
G01X229883D02*
X227521D01*
G01X233820D02*
X231458D01*
G01X237757D02*
X235395D01*
G01X241694D02*
X239332D01*
G01X245631D02*
X243269D01*
G01X249568D02*
X247206D01*
G01X253505D02*
X251143D01*
G01X257442D02*
X255080D01*
G01X261379D02*
X259017D01*
G01X265316D02*
X262954D01*
G01X190001Y155492D02*
X188662D01*
G01X197875D02*
X196536D01*
G01X205749D02*
X204410D01*
G01X213623D02*
X212284D01*
G01X221497D02*
X220158D01*
G01X229371D02*
X228032D01*
G01X237245D02*
X235906D01*
G01X245119D02*
X243780D01*
G01X252993D02*
X251655D01*
G01X260867D02*
X259529D01*
G01X259371Y155393D02*
X261025D01*
G01X251497D02*
X253151D01*
G01X243623D02*
X245277D01*
G01X235749D02*
X237403D01*
G01X227875D02*
X229529D01*
G01X220001D02*
X221655D01*
G01X212127D02*
X213780D01*
G01X204253D02*
X205906D01*
G01X196379D02*
X198032D01*
G01X188505D02*
X190158D01*
G01X190513Y155295D02*
X188151D01*
G01X194450D02*
X192088D01*
G01X198387D02*
X196025D01*
G01X202324D02*
X199962D01*
G01X206261D02*
X203899D01*
G01X210198D02*
X207836D01*
G01X214135D02*
X211773D01*
G01X218072D02*
X215710D01*
G01X222009D02*
X219647D01*
G01X225946D02*
X223584D01*
G01X229883D02*
X227521D01*
G01X233820D02*
X231458D01*
G01X237757D02*
X235395D01*
G01X241694D02*
X239332D01*
G01X245631D02*
X243269D01*
G01X249568D02*
X247206D01*
G01X253505D02*
X251143D01*
G01X257442D02*
X255080D01*
G01X261379D02*
X259017D01*
G01X265316D02*
X262954D01*
G01X190158Y154901D02*
X188505D01*
G01X198032D02*
X196379D01*
G01X205906D02*
X204253D01*
G01X213780D02*
X212127D01*
G01X221655D02*
X220001D01*
G01X229529D02*
X227875D01*
G01X237403D02*
X235749D01*
G01X245277D02*
X243623D01*
G01X253151D02*
X251497D01*
G01X261025D02*
X259371D01*
G01X190749Y154035D02*
X187914D01*
G01X194686D02*
X191851D01*
G01X198623D02*
X195788D01*
G01X202560D02*
X199725D01*
G01X206497D02*
X203662D01*
G01X210434D02*
X207599D01*
G01X214371D02*
X211536D01*
G01X218308D02*
X215473D01*
G01X222245D02*
X219410D01*
G01X226182D02*
X223347D01*
G01X230119D02*
X227284D01*
G01X234056D02*
X231221D01*
G01X237993D02*
X235158D01*
G01X241930D02*
X239095D01*
G01X245867D02*
X243032D01*
G01X249804D02*
X246969D01*
G01X253741D02*
X250906D01*
G01X257678D02*
X254843D01*
G01X261615D02*
X258780D01*
G01X265552D02*
X262717D01*
G01X269489D02*
X266655D01*
G01X190158Y153130D02*
X188505D01*
G01X198032D02*
X196379D01*
G01X205906D02*
X204253D01*
G01X213780D02*
X212127D01*
G01X221655D02*
X220001D01*
G01X229529D02*
X227875D01*
G01X237403D02*
X235749D01*
G01X245277D02*
X243623D01*
G01X253151D02*
X251497D01*
G01X261025D02*
X259371D01*
G01Y152637D02*
X261025D01*
G01X251497D02*
X253151D01*
G01X243623D02*
X245277D01*
G01X235749D02*
X237403D01*
G01X227875D02*
X229529D01*
G01X220001D02*
X221655D01*
G01X212127D02*
X213780D01*
G01X204253D02*
X205906D01*
G01X196379D02*
X198032D01*
G01X188505D02*
X190158D01*
G01X190749Y152539D02*
X187914D01*
G01X194686D02*
X191851D01*
G01X198623D02*
X195788D01*
G01X202560D02*
X199725D01*
G01X206497D02*
X203662D01*
G01X210434D02*
X207599D01*
G01X214371D02*
X211536D01*
G01X218308D02*
X215473D01*
G01X222245D02*
X219410D01*
G01X226182D02*
X223347D01*
G01X230119D02*
X227284D01*
G01X234056D02*
X231221D01*
G01X237993D02*
X235158D01*
G01X241930D02*
X239095D01*
G01X245867D02*
X243032D01*
G01X249804D02*
X246969D01*
G01X253741D02*
X250906D01*
G01X257678D02*
X254843D01*
G01X261615D02*
X258780D01*
G01X265552D02*
X262717D01*
G01X269489D02*
X266655D01*
G01Y152382D02*
X267245D01*
G01X264962D02*
X265552D01*
G01X262717D02*
X263308D01*
G01X261025D02*
X261615D01*
G01X258780D02*
X259371D01*
G01X257088D02*
X257678D01*
G01X254843D02*
X255434D01*
G01X253151D02*
X253741D01*
G01X250906D02*
X251497D01*
G01X249214D02*
X249804D01*
G01X246969D02*
X247560D01*
G01X245277D02*
X245867D01*
G01X243032D02*
X243623D01*
G01X241340D02*
X241930D01*
G01X239095D02*
X239686D01*
G01X237403D02*
X237993D01*
G01X235158D02*
X235749D01*
G01X233466D02*
X234056D01*
G01X231221D02*
X231812D01*
G01X229529D02*
X230119D01*
G01X227284D02*
X227875D01*
G01X225592D02*
X226182D01*
G01X223347D02*
X223938D01*
G01X221655D02*
X222245D01*
G01X219410D02*
X220001D01*
G01X217717D02*
X218308D01*
G01X215473D02*
X216064D01*
G01X213780D02*
X214371D01*
G01X211536D02*
X212127D01*
G01X209843D02*
X210434D01*
G01X207599D02*
X208190D01*
G01X205906D02*
X206497D01*
G01X203662D02*
X204253D01*
G01X201969D02*
X202560D01*
G01X199725D02*
X200316D01*
G01X198032D02*
X198623D01*
G01X195788D02*
X196379D01*
G01X194095D02*
X194686D01*
G01X191851D02*
X192442D01*
G01X190158D02*
X190749D01*
G01X187914D02*
X188505D01*
G01X263134Y152147D02*
X265145D01*
G01X259192D02*
X261203D01*
G01X255260D02*
X257271D01*
G01X251318D02*
X253329D01*
G01X247386D02*
X249397D01*
G01X243444D02*
X245455D01*
G01X239512D02*
X241523D01*
G01X235570D02*
X237581D01*
G01X231638D02*
X233649D01*
G01X227696D02*
X229707D01*
G01X223764D02*
X225775D01*
G01X219822D02*
X221833D01*
G01X215890D02*
X217901D01*
G01X211948D02*
X213959D01*
G01X208016D02*
X210027D01*
G01X204074D02*
X206085D01*
G01X200142D02*
X202153D01*
G01X196200D02*
X198211D01*
G01X192268D02*
X194279D01*
G01X188326D02*
X190337D01*
G01X190081Y151756D02*
X188582D01*
G01X194023D02*
X192524D01*
G01X197955D02*
X196456D01*
G01X201897D02*
X200398D01*
G01X205829D02*
X204330D01*
G01X209771D02*
X208272D01*
G01X213703D02*
X212204D01*
G01X217645D02*
X216146D01*
G01X221577D02*
X220078D01*
G01X225519D02*
X224020D01*
G01X229451D02*
X227952D01*
G01X233393D02*
X231894D01*
G01X237325D02*
X235826D01*
G01X241267D02*
X239768D01*
G01X245200D02*
X243700D01*
G01X249141D02*
X247642D01*
G01X253074D02*
X251574D01*
G01X257015D02*
X255516D01*
G01X260948D02*
X259448D01*
G01X264889D02*
X263390D01*
G01X263403Y151737D02*
X264876D01*
G01X259461D02*
X260934D01*
G01X255529D02*
X257002D01*
G01X251587D02*
X253060D01*
G01X247655D02*
X249128D01*
G01X243713D02*
X245186D01*
G01X239781D02*
X241254D01*
G01X235839D02*
X237312D01*
G01X231907D02*
X233380D01*
G01X227965D02*
X229438D01*
G01X224033D02*
X225506D01*
G01X220091D02*
X221564D01*
G01X216159D02*
X217632D01*
G01X212217D02*
X213690D01*
G01X208285D02*
X209758D01*
G01X204343D02*
X205816D01*
G01X200411D02*
X201884D01*
G01X196469D02*
X197942D01*
G01X192537D02*
X194010D01*
G01X188595D02*
X190068D01*
G01X188505Y151712D02*
X187914D01*
G01X190749D02*
X190158D01*
G01X192442D02*
X191851D01*
G01X194686D02*
X194095D01*
G01X196379D02*
X195788D01*
G01X198623D02*
X198032D01*
G01X200316D02*
X199725D01*
G01X202560D02*
X201969D01*
G01X204253D02*
X203662D01*
G01X206497D02*
X205906D01*
G01X208190D02*
X207599D01*
G01X210434D02*
X209843D01*
G01X212127D02*
X211536D01*
G01X214371D02*
X213780D01*
G01X216064D02*
X215473D01*
G01X218308D02*
X217717D01*
G01X220001D02*
X219410D01*
G01X222245D02*
X221655D01*
G01X223938D02*
X223347D01*
G01X226182D02*
X225592D01*
G01X227875D02*
X227284D01*
G01X230119D02*
X229529D01*
G01X231812D02*
X231221D01*
G01X234056D02*
X233466D01*
G01X235749D02*
X235158D01*
G01X237993D02*
X237403D01*
G01X239686D02*
X239095D01*
G01X241930D02*
X241340D01*
G01X243623D02*
X243032D01*
G01X245867D02*
X245277D01*
G01X247560D02*
X246969D01*
G01X249804D02*
X249214D01*
G01X251497D02*
X250906D01*
G01X253741D02*
X253151D01*
G01X255434D02*
X254843D01*
G01X257678D02*
X257088D01*
G01X259371D02*
X258780D01*
G01X261615D02*
X261025D01*
G01X263308D02*
X262717D01*
G01X265552D02*
X264962D01*
G01X267245D02*
X266655D01*
G01Y151555D02*
X269489D01*
G01X262717D02*
X265552D01*
G01X258780D02*
X261615D01*
G01X254843D02*
X257678D01*
G01X250906D02*
X253741D01*
G01X243032D02*
X245867D01*
G01X239095D02*
X241930D01*
G01X235158D02*
X237993D01*
G01X231221D02*
X234056D01*
G01X227284D02*
X230119D01*
G01X223347D02*
X226182D01*
G01X219410D02*
X222245D01*
G01X211536D02*
X214371D01*
G01X207599D02*
X210434D01*
G01X203662D02*
X206497D01*
G01X199725D02*
X202560D01*
G01X195788D02*
X198623D01*
G01X191851D02*
X194686D01*
G01X187914D02*
X190749D01*
G01X218308D02*
X215473D01*
G01X249804D02*
X246969D01*
G01X194095Y151456D02*
X192442D01*
G01X201969D02*
X200316D01*
G01X209843D02*
X208190D01*
G01X217717D02*
X216064D01*
G01X225592D02*
X223938D01*
G01X233466D02*
X231812D01*
G01X241340D02*
X239686D01*
G01X249214D02*
X247560D01*
G01X257088D02*
X255434D01*
G01X264962D02*
X263308D01*
G01X189814Y151368D02*
X188849D01*
G01X193756D02*
X192791D01*
G01X197688D02*
X196723D01*
G01X201630D02*
X200665D01*
G01X205562D02*
X204597D01*
G01X209504D02*
X208539D01*
G01X213436D02*
X212471D01*
G01X217378D02*
X216413D01*
G01X221310D02*
X220345D01*
G01X225252D02*
X224287D01*
G01X229184D02*
X228219D01*
G01X233126D02*
X232161D01*
G01X237058D02*
X236093D01*
G01X241000D02*
X240035D01*
G01X244932D02*
X243967D01*
G01X248874D02*
X247909D01*
G01X252806D02*
X251841D01*
G01X256748D02*
X255783D01*
G01X260680D02*
X259715D01*
G01X264622D02*
X263657D01*
G01X266655Y151358D02*
X266969D01*
G01X262717D02*
X263032D01*
G01X254843D02*
X255158D01*
G01X246969D02*
X247284D01*
G01X243032D02*
X243347D01*
G01X239095D02*
X239410D01*
G01X235158D02*
X235473D01*
G01X231221D02*
X231536D01*
G01X227284D02*
X227599D01*
G01X223347D02*
X223662D01*
G01X219410D02*
X219725D01*
G01X215473D02*
X215788D01*
G01X211536D02*
X211851D01*
G01X207599D02*
X207914D01*
G01X203662D02*
X203977D01*
G01X199725D02*
X200040D01*
G01X195788D02*
X196103D01*
G01X191851D02*
X192166D01*
G01X188229D02*
X187914D01*
G01X190749D02*
X190434D01*
G01X194686D02*
X194371D01*
G01X198623D02*
X198308D01*
G01X202560D02*
X202245D01*
G01X206497D02*
X206182D01*
G01X210434D02*
X210119D01*
G01X214371D02*
X214056D01*
G01X218308D02*
X217993D01*
G01X222245D02*
X221930D01*
G01X226182D02*
X225867D01*
G01X230119D02*
X229804D01*
G01X234056D02*
X233741D01*
G01X237993D02*
X237678D01*
G01X241930D02*
X241615D01*
G01X245867D02*
X245552D01*
G01X249804D02*
X249489D01*
G01X251221D02*
X250906D01*
G01X253741D02*
X253426D01*
G01X257678D02*
X257363D01*
G01X259095D02*
X258780D01*
G01X261615D02*
X261300D01*
G01X265552D02*
X265237D01*
G01X190342Y151260D02*
X188321D01*
G01X194284D02*
X192263D01*
G01X198216D02*
X196195D01*
G01X202158D02*
X200137D01*
G01X206090D02*
X204069D01*
G01X210032D02*
X208011D01*
G01X213964D02*
X211943D01*
G01X217906D02*
X215885D01*
G01X221838D02*
X219817D01*
G01X225780D02*
X223759D01*
G01X229712D02*
X227691D01*
G01X233654D02*
X231633D01*
G01X237586D02*
X235565D01*
G01X241528D02*
X239507D01*
G01X245460D02*
X243439D01*
G01X249402D02*
X247381D01*
G01X253334D02*
X251313D01*
G01X257276D02*
X255255D01*
G01X261208D02*
X259187D01*
G01X265150D02*
X263129D01*
G01X263308Y150964D02*
X264962D01*
G01X255434D02*
X257088D01*
G01X247560D02*
X249214D01*
G01X239686D02*
X241340D01*
G01X231812D02*
X233466D01*
G01X223938D02*
X225592D01*
G01X216064D02*
X217717D01*
G01X208190D02*
X209843D01*
G01X200316D02*
X201969D01*
G01X192442D02*
X194095D01*
G01X190081Y150772D02*
X188582D01*
G01X194023D02*
X192524D01*
G01X197955D02*
X196456D01*
G01X201897D02*
X200398D01*
G01X205829D02*
X204330D01*
G01X209771D02*
X208272D01*
G01X213703D02*
X212204D01*
G01X217645D02*
X216146D01*
G01X221577D02*
X220078D01*
G01X225519D02*
X224020D01*
G01X229451D02*
X227952D01*
G01X233393D02*
X231894D01*
G01X237325D02*
X235826D01*
G01X241267D02*
X239768D01*
G01X245200D02*
X243700D01*
G01X249141D02*
X247642D01*
G01X253074D02*
X251574D01*
G01X257015D02*
X255516D01*
G01X260948D02*
X259448D01*
G01X264889D02*
X263390D01*
G01X190080Y150762D02*
X188583D01*
G01X194022D02*
X192525D01*
G01X197954D02*
X196457D01*
G01X201896D02*
X200399D01*
G01X205828D02*
X204331D01*
G01X209770D02*
X208273D01*
G01X213702D02*
X212205D01*
G01X217644D02*
X216147D01*
G01X221576D02*
X220080D01*
G01X225518D02*
X224021D01*
G01X229450D02*
X227954D01*
G01X233392D02*
X231895D01*
G01X237324D02*
X235828D01*
G01X241266D02*
X239769D01*
G01X245198D02*
X243702D01*
G01X249140D02*
X247643D01*
G01X253072D02*
X251576D01*
G01X257014D02*
X255517D01*
G01X260946D02*
X259450D01*
G01X264888D02*
X263391D01*
G01X263611Y150441D02*
X264668D01*
G01X259670D02*
X260726D01*
G01X255737D02*
X256794D01*
G01X251796D02*
X252852D01*
G01X247863D02*
X248920D01*
G01X243921D02*
X244978D01*
G01X239989D02*
X241046D01*
G01X236047D02*
X237104D01*
G01X232115D02*
X233172D01*
G01X228173D02*
X229230D01*
G01X224241D02*
X225298D01*
G01X220299D02*
X221356D01*
G01X216367D02*
X217424D01*
G01X212425D02*
X213482D01*
G01X208493D02*
X209550D01*
G01X204551D02*
X205608D01*
G01X200619D02*
X201676D01*
G01X196677D02*
X197734D01*
G01X192745D02*
X193802D01*
G01X188803D02*
X189860D01*
G01X259017Y150393D02*
X261379D01*
G01X255080D02*
X257442D01*
G01X251143D02*
X253505D01*
G01X188151D02*
X190513D01*
G01X194450D02*
X192088D01*
G01X198387D02*
X196025D01*
G01X202324D02*
X199962D01*
G01X206261D02*
X203899D01*
G01X210198D02*
X207836D01*
G01X214135D02*
X211773D01*
G01X218072D02*
X215710D01*
G01X222009D02*
X219647D01*
G01X225946D02*
X223584D01*
G01X229883D02*
X227521D01*
G01X233820D02*
X231458D01*
G01X237757D02*
X235395D01*
G01X241694D02*
X239332D01*
G01X245631D02*
X243269D01*
G01X249568D02*
X247206D01*
G01X265316D02*
X262954D01*
G01X266655Y149862D02*
X266969D01*
G01X265237D02*
X265552D01*
G01X262717D02*
X263032D01*
G01X261300D02*
X261615D01*
G01X258780D02*
X259095D01*
G01X257363D02*
X257678D01*
G01X254843D02*
X255158D01*
G01X253426D02*
X253741D01*
G01X250906D02*
X251221D01*
G01X249489D02*
X249804D01*
G01X246969D02*
X247284D01*
G01X245552D02*
X245867D01*
G01X243032D02*
X243347D01*
G01X241615D02*
X241930D01*
G01X239095D02*
X239410D01*
G01X237678D02*
X237993D01*
G01X235158D02*
X235473D01*
G01X233741D02*
X234056D01*
G01X231221D02*
X231536D01*
G01X229804D02*
X230119D01*
G01X227284D02*
X227599D01*
G01X225867D02*
X226182D01*
G01X223347D02*
X223662D01*
G01X221930D02*
X222245D01*
G01X217993D02*
X218308D01*
G01X219410D02*
X219725D01*
G01X215473D02*
X215788D01*
G01X214056D02*
X214371D01*
G01X211536D02*
X211851D01*
G01X210119D02*
X210434D01*
G01X207599D02*
X207914D01*
G01X206182D02*
X206497D01*
G01X203662D02*
X203977D01*
G01X202245D02*
X202560D01*
G01X199725D02*
X200040D01*
G01X198308D02*
X198623D01*
G01X195788D02*
X196103D01*
G01X194371D02*
X194686D01*
G01X191851D02*
X192166D01*
G01X190434D02*
X190749D01*
G01X187914D02*
X188229D01*
G01X263368Y149826D02*
X264911D01*
G01X259426D02*
X260969D01*
G01X255494D02*
X257037D01*
G01X251552D02*
X253095D01*
G01X247620D02*
X249163D01*
G01X243678D02*
X245221D01*
G01X239746D02*
X241289D01*
G01X235804D02*
X237347D01*
G01X231872D02*
X233415D01*
G01X227930D02*
X229473D01*
G01X223998D02*
X225541D01*
G01X220056D02*
X221599D01*
G01X216124D02*
X217667D01*
G01X212182D02*
X213725D01*
G01X208250D02*
X209793D01*
G01X204308D02*
X205851D01*
G01X200376D02*
X201919D01*
G01X196434D02*
X197977D01*
G01X192502D02*
X194045D01*
G01X188560D02*
X190103D01*
G01X263379Y149807D02*
X264900D01*
G01X259437D02*
X260959D01*
G01X255505D02*
X257026D01*
G01X251563D02*
X253085D01*
G01X247631D02*
X249152D01*
G01X243689D02*
X245210D01*
G01X239757D02*
X241278D01*
G01X235815D02*
X237336D01*
G01X231883D02*
X233404D01*
G01X227941D02*
X229462D01*
G01X224009D02*
X225530D01*
G01X220067D02*
X221588D01*
G01X216135D02*
X217656D01*
G01X212193D02*
X213714D01*
G01X208261D02*
X209782D01*
G01X204319D02*
X205840D01*
G01X200387D02*
X201908D01*
G01X196445D02*
X197966D01*
G01X192513D02*
X194034D01*
G01X188571D02*
X190092D01*
G01X263308Y149193D02*
X264962D01*
G01X255434D02*
X257088D01*
G01X247560D02*
X249214D01*
G01X239686D02*
X241340D01*
G01X231812D02*
X233466D01*
G01X223938D02*
X225592D01*
G01X216064D02*
X217717D01*
G01X208190D02*
X209843D01*
G01X200316D02*
X201969D01*
G01X192442D02*
X194095D01*
G01Y148700D02*
X192442D01*
G01X201969D02*
X200316D01*
G01X209843D02*
X208190D01*
G01X217717D02*
X216064D01*
G01X225592D02*
X223938D01*
G01X233466D02*
X231812D01*
G01X241340D02*
X239686D01*
G01X249214D02*
X247560D01*
G01X257088D02*
X255434D01*
G01X264962D02*
X263308D01*
G01X193938Y148602D02*
X192599D01*
G01X201812D02*
X200473D01*
G01X209686D02*
X208347D01*
G01X217560D02*
X216221D01*
G01X225434D02*
X224095D01*
G01X233308D02*
X231969D01*
G01X241182D02*
X239843D01*
G01X249056D02*
X247717D01*
G01X256930D02*
X255592D01*
G01X264804D02*
X263466D01*
G01Y147618D02*
X264804D01*
G01X255592D02*
X256930D01*
G01X247717D02*
X249056D01*
G01X239843D02*
X241182D01*
G01X231969D02*
X233308D01*
G01X224095D02*
X225434D01*
G01X216221D02*
X217560D01*
G01X208347D02*
X209686D01*
G01X200473D02*
X201812D01*
G01X192599D02*
X193938D01*
G01X190129Y146999D02*
X188534D01*
G01X194071D02*
X192476D01*
G01X198003D02*
X196408D01*
G01X201945D02*
X200350D01*
G01X205877D02*
X204282D01*
G01X209819D02*
X208224D01*
G01X213751D02*
X212156D01*
G01X217693D02*
X216098D01*
G01X221625D02*
X220030D01*
G01X225567D02*
X223972D01*
G01X229499D02*
X227904D01*
G01X233441D02*
X231846D01*
G01X237373D02*
X235778D01*
G01X241315D02*
X239720D01*
G01X245247D02*
X243652D01*
G01X249189D02*
X247594D01*
G01X253121D02*
X251526D01*
G01X257063D02*
X255468D01*
G01X260995D02*
X259400D01*
G01X264937D02*
X263342D01*
G01X190434Y146889D02*
X188229D01*
G01X194371D02*
X192166D01*
G01X198308D02*
X196103D01*
G01X202245D02*
X200040D01*
G01X206182D02*
X203977D01*
G01X210119D02*
X207914D01*
G01X214056D02*
X211851D01*
G01X217993D02*
X215788D01*
G01X221930D02*
X219725D01*
G01X225867D02*
X223662D01*
G01X229804D02*
X227599D01*
G01X233741D02*
X231536D01*
G01X237678D02*
X235473D01*
G01X241615D02*
X239410D01*
G01X245552D02*
X243347D01*
G01X249489D02*
X247284D01*
G01X253426D02*
X251221D01*
G01X257363D02*
X255158D01*
G01X261300D02*
X259095D01*
G01X265237D02*
X263032D01*
G01X190201Y146239D02*
X188462D01*
G01X194143D02*
X192404D01*
G01X198075D02*
X196336D01*
G01X202017D02*
X200278D01*
G01X205949D02*
X204210D01*
G01X209891D02*
X208152D01*
G01X213823D02*
X212084D01*
G01X217765D02*
X216026D01*
G01X221697D02*
X219958D01*
G01X225639D02*
X223900D01*
G01X229571D02*
X227832D01*
G01X233513D02*
X231774D01*
G01X237445D02*
X235706D01*
G01X241387D02*
X239648D01*
G01X245319D02*
X243580D01*
G01X249261D02*
X247522D01*
G01X253193D02*
X251454D01*
G01X257135D02*
X255396D01*
G01X261067D02*
X259328D01*
G01X265009D02*
X263270D01*
G01X263344Y146037D02*
X264935D01*
G01X259403D02*
X260993D01*
G01X255470D02*
X257061D01*
G01X251529D02*
X253119D01*
G01X247596D02*
X249187D01*
G01X243655D02*
X245245D01*
G01X239722D02*
X241313D01*
G01X235781D02*
X237371D01*
G01X231848D02*
X233439D01*
G01X227907D02*
X229497D01*
G01X223974D02*
X225565D01*
G01X220032D02*
X221623D01*
G01X216100D02*
X217691D01*
G01X212158D02*
X213749D01*
G01X208226D02*
X209817D01*
G01X204284D02*
X205875D01*
G01X200352D02*
X201943D01*
G01X196410D02*
X198001D01*
G01X192478D02*
X194069D01*
G01X188536D02*
X190127D01*
G01X263291Y146012D02*
X264988D01*
G01X259350D02*
X261046D01*
G01X255417D02*
X257114D01*
G01X251476D02*
X253172D01*
G01X247543D02*
X249240D01*
G01X243602D02*
X245298D01*
G01X239669D02*
X241366D01*
G01X235728D02*
X237424D01*
G01X231795D02*
X233491D01*
G01X227854D02*
X229550D01*
G01X223921D02*
X225617D01*
G01X219980D02*
X221676D01*
G01X216047D02*
X217743D01*
G01X212106D02*
X213802D01*
G01X208173D02*
X209869D01*
G01X204232D02*
X205928D01*
G01X200299D02*
X201995D01*
G01X196358D02*
X198054D01*
G01X192425D02*
X194121D01*
G01X188484D02*
X190180D01*
G01X190187Y145945D02*
X188477D01*
G01X194128D02*
X192418D01*
G01X198061D02*
X196351D01*
G01X202002D02*
X200292D01*
G01X205935D02*
X204225D01*
G01X209876D02*
X208166D01*
G01X213809D02*
X212099D01*
G01X217750D02*
X216040D01*
G01X221683D02*
X219973D01*
G01X225624D02*
X223914D01*
G01X229557D02*
X227847D01*
G01X233499D02*
X231788D01*
G01X237431D02*
X235721D01*
G01X241373D02*
X239662D01*
G01X245305D02*
X243595D01*
G01X249247D02*
X247536D01*
G01X253179D02*
X251469D01*
G01X257121D02*
X255410D01*
G01X261053D02*
X259343D01*
G01X264995D02*
X263284D01*
G01X263265Y145353D02*
X265014D01*
G01X259324D02*
X261072D01*
G01X255391D02*
X257140D01*
G01X251450D02*
X253198D01*
G01X247517D02*
X249266D01*
G01X243576D02*
X245324D01*
G01X239643D02*
X241392D01*
G01X235702D02*
X237450D01*
G01X231769D02*
X233518D01*
G01X227828D02*
X229576D01*
G01X223895D02*
X225644D01*
G01X219954D02*
X221702D01*
G01X216021D02*
X217770D01*
G01X212080D02*
X213828D01*
G01X208147D02*
X209896D01*
G01X204206D02*
X205954D01*
G01X200273D02*
X202022D01*
G01X196331D02*
X198080D01*
G01X192399D02*
X194148D01*
G01X188457D02*
X190206D01*
G01X190177Y145050D02*
X188486D01*
G01X194119D02*
X192428D01*
G01X198051D02*
X196360D01*
G01X201993D02*
X200302D01*
G01X205925D02*
X204234D01*
G01X209867D02*
X208176D01*
G01X213799D02*
X212108D01*
G01X217741D02*
X216050D01*
G01X221673D02*
X219982D01*
G01X225615D02*
X223924D01*
G01X229547D02*
X227856D01*
G01X233489D02*
X231798D01*
G01X237421D02*
X235730D01*
G01X241363D02*
X239672D01*
G01X245296D02*
X243604D01*
G01X249237D02*
X247546D01*
G01X253170D02*
X251478D01*
G01X257111D02*
X255420D01*
G01X261044D02*
X259352D01*
G01X264985D02*
X263294D01*
G01X190187Y144960D02*
X188477D01*
G01X194128D02*
X192418D01*
G01X198061D02*
X196351D01*
G01X202002D02*
X200292D01*
G01X205935D02*
X204225D01*
G01X209876D02*
X208166D01*
G01X213809D02*
X212099D01*
G01X217750D02*
X216040D01*
G01X221683D02*
X219973D01*
G01X225624D02*
X223914D01*
G01X229557D02*
X227847D01*
G01X233499D02*
X231788D01*
G01X237431D02*
X235721D01*
G01X241373D02*
X239662D01*
G01X245305D02*
X243595D01*
G01X249247D02*
X247536D01*
G01X253179D02*
X251469D01*
G01X257121D02*
X255410D01*
G01X261053D02*
X259343D01*
G01X264995D02*
X263284D01*
G01X263032Y144634D02*
X265237D01*
G01X259095D02*
X261300D01*
G01X255158D02*
X257363D01*
G01X251221D02*
X253426D01*
G01X247284D02*
X249489D01*
G01X243347D02*
X245552D01*
G01X239410D02*
X241615D01*
G01X235473D02*
X237678D01*
G01X231536D02*
X233741D01*
G01X227599D02*
X229804D01*
G01X223662D02*
X225867D01*
G01X219725D02*
X221930D01*
G01X215788D02*
X217993D01*
G01X211851D02*
X214056D01*
G01X207914D02*
X210119D01*
G01X203977D02*
X206182D01*
G01X200040D02*
X202245D01*
G01X196103D02*
X198308D01*
G01X192166D02*
X194371D01*
G01X188229D02*
X190434D01*
G01X263032Y144467D02*
X265237D01*
G01X259095D02*
X261300D01*
G01X255158D02*
X257363D01*
G01X251221D02*
X253426D01*
G01X247284D02*
X249489D01*
G01X243347D02*
X245552D01*
G01X239410D02*
X241615D01*
G01X235473D02*
X237678D01*
G01X231536D02*
X233741D01*
G01X227599D02*
X229804D01*
G01X223662D02*
X225867D01*
G01X219725D02*
X221930D01*
G01X215788D02*
X217993D01*
G01X211851D02*
X214056D01*
G01X207914D02*
X210119D01*
G01X203977D02*
X206182D01*
G01X200040D02*
X202245D01*
G01X196103D02*
X198308D01*
G01X192166D02*
X194371D01*
G01X188229D02*
X190434D01*
G01Y141910D02*
X188229D01*
G01X194371D02*
X192166D01*
G01X198308D02*
X196103D01*
G01X202245D02*
X200040D01*
G01X206182D02*
X203977D01*
G01X210119D02*
X207914D01*
G01X214056D02*
X211851D01*
G01X217993D02*
X215788D01*
G01X221930D02*
X219725D01*
G01X225867D02*
X223662D01*
G01X229804D02*
X227599D01*
G01X233741D02*
X231536D01*
G01X237678D02*
X235473D01*
G01X241615D02*
X239410D01*
G01X245552D02*
X243347D01*
G01X249489D02*
X247284D01*
G01X253426D02*
X251221D01*
G01X257363D02*
X255158D01*
G01X261300D02*
X259095D01*
G01X265237D02*
X263032D01*
G01X190434Y141743D02*
X188229D01*
G01X194371D02*
X192166D01*
G01X198308D02*
X196103D01*
G01X202245D02*
X200040D01*
G01X206182D02*
X203977D01*
G01X210119D02*
X207914D01*
G01X214056D02*
X211851D01*
G01X217993D02*
X215788D01*
G01X221930D02*
X219725D01*
G01X225867D02*
X223662D01*
G01X229804D02*
X227599D01*
G01X233741D02*
X231536D01*
G01X237678D02*
X235473D01*
G01X241615D02*
X239410D01*
G01X245552D02*
X243347D01*
G01X249489D02*
X247284D01*
G01X253426D02*
X251221D01*
G01X257363D02*
X255158D01*
G01X261300D02*
X259095D01*
G01X265237D02*
X263032D01*
G01X263275Y141417D02*
X264985D01*
G01X259343D02*
X261053D01*
G01X255401D02*
X257111D01*
G01X251469D02*
X253179D01*
G01X247527D02*
X249237D01*
G01X243595D02*
X245305D01*
G01X239653D02*
X241363D01*
G01X235721D02*
X237431D01*
G01X231779D02*
X233489D01*
G01X227847D02*
X229557D01*
G01X223905D02*
X225615D01*
G01X219973D02*
X221683D01*
G01X216031D02*
X217741D01*
G01X212099D02*
X213809D01*
G01X208157D02*
X209867D01*
G01X204225D02*
X205935D01*
G01X200283D02*
X201993D01*
G01X196351D02*
X198061D01*
G01X192409D02*
X194119D01*
G01X188477D02*
X190187D01*
G01X263284Y141327D02*
X264976D01*
G01X259352D02*
X261044D01*
G01X255410D02*
X257102D01*
G01X251478D02*
X253170D01*
G01X247536D02*
X249228D01*
G01X243604D02*
X245296D01*
G01X239662D02*
X241354D01*
G01X235730D02*
X237421D01*
G01X231788D02*
X233480D01*
G01X227856D02*
X229547D01*
G01X223914D02*
X225606D01*
G01X219982D02*
X221673D01*
G01X216040D02*
X217732D01*
G01X212108D02*
X213799D01*
G01X208166D02*
X209858D01*
G01X204234D02*
X205925D01*
G01X200292D02*
X201984D01*
G01X196360D02*
X198051D01*
G01X192418D02*
X194110D01*
G01X188486D02*
X190177D01*
G01X190206Y141024D02*
X188457D01*
G01X194138D02*
X192390D01*
G01X198080D02*
X196331D01*
G01X202012D02*
X200264D01*
G01X205954D02*
X204206D01*
G01X209886D02*
X208138D01*
G01X213828D02*
X212080D01*
G01X217760D02*
X216012D01*
G01X221702D02*
X219954D01*
G01X225634D02*
X223886D01*
G01X229576D02*
X227828D01*
G01X233508D02*
X231760D01*
G01X237450D02*
X235702D01*
G01X241382D02*
X239634D01*
G01X245324D02*
X243576D01*
G01X249256D02*
X247508D01*
G01X253198D02*
X251450D01*
G01X257130D02*
X255382D01*
G01X261072D02*
X259324D01*
G01X265004D02*
X263256D01*
G01X263275Y140433D02*
X264985D01*
G01X259343D02*
X261053D01*
G01X255401D02*
X257111D01*
G01X251469D02*
X253179D01*
G01X247527D02*
X249237D01*
G01X243595D02*
X245305D01*
G01X239653D02*
X241363D01*
G01X235721D02*
X237431D01*
G01X231779D02*
X233489D01*
G01X227847D02*
X229557D01*
G01X223905D02*
X225615D01*
G01X219973D02*
X221683D01*
G01X216031D02*
X217741D01*
G01X212099D02*
X213809D01*
G01X208157D02*
X209867D01*
G01X204225D02*
X205935D01*
G01X200283D02*
X201993D01*
G01X196351D02*
X198061D01*
G01X192409D02*
X194119D01*
G01X188477D02*
X190187D01*
G01X190180Y140365D02*
X188484D01*
G01X194112D02*
X192416D01*
G01X198054D02*
X196358D01*
G01X201986D02*
X200290D01*
G01X205928D02*
X204232D01*
G01X209860D02*
X208164D01*
G01X213802D02*
X212106D01*
G01X217734D02*
X216038D01*
G01X221676D02*
X219980D01*
G01X225608D02*
X223912D01*
G01X229550D02*
X227854D01*
G01X233482D02*
X231786D01*
G01X237424D02*
X235728D01*
G01X241356D02*
X239660D01*
G01X245298D02*
X243602D01*
G01X249230D02*
X247534D01*
G01X253172D02*
X251476D01*
G01X257104D02*
X255408D01*
G01X261046D02*
X259350D01*
G01X264978D02*
X263282D01*
G01X190127Y140340D02*
X188536D01*
G01X194059D02*
X192469D01*
G01X198001D02*
X196410D01*
G01X201933D02*
X200343D01*
G01X205875D02*
X204284D01*
G01X209807D02*
X208217D01*
G01X213749D02*
X212158D01*
G01X217681D02*
X216091D01*
G01X221623D02*
X220032D01*
G01X225555D02*
X223965D01*
G01X229497D02*
X227907D01*
G01X233429D02*
X231839D01*
G01X237371D02*
X235781D01*
G01X241303D02*
X239713D01*
G01X245245D02*
X243655D01*
G01X249177D02*
X247587D01*
G01X253119D02*
X251529D01*
G01X257051D02*
X255461D01*
G01X260993D02*
X259403D01*
G01X264925D02*
X263335D01*
G01X263261Y140138D02*
X265000D01*
G01X259328D02*
X261067D01*
G01X255387D02*
X257126D01*
G01X251454D02*
X253193D01*
G01X247513D02*
X249252D01*
G01X243580D02*
X245319D01*
G01X239639D02*
X241378D01*
G01X235706D02*
X237445D01*
G01X231765D02*
X233503D01*
G01X227832D02*
X229571D01*
G01X223891D02*
X225629D01*
G01X219958D02*
X221697D01*
G01X216017D02*
X217755D01*
G01X212084D02*
X213823D01*
G01X208143D02*
X209881D01*
G01X204210D02*
X205949D01*
G01X200269D02*
X202007D01*
G01X196336D02*
X198075D01*
G01X192395D02*
X194133D01*
G01X188462D02*
X190201D01*
G01X263032Y139488D02*
X265237D01*
G01X259095D02*
X261300D01*
G01X255158D02*
X257363D01*
G01X251221D02*
X253426D01*
G01X247284D02*
X249489D01*
G01X243347D02*
X245552D01*
G01X239410D02*
X241615D01*
G01X235473D02*
X237678D01*
G01X231536D02*
X233741D01*
G01X227599D02*
X229804D01*
G01X223662D02*
X225867D01*
G01X219725D02*
X221930D01*
G01X215788D02*
X217993D01*
G01X211851D02*
X214056D01*
G01X207914D02*
X210119D01*
G01X203977D02*
X206182D01*
G01X200040D02*
X202245D01*
G01X196103D02*
X198308D01*
G01X192166D02*
X194371D01*
G01X188229D02*
X190434D01*
G01X263333Y139379D02*
X264928D01*
G01X259400D02*
X260995D01*
G01X255459D02*
X257054D01*
G01X251526D02*
X253121D01*
G01X247585D02*
X249180D01*
G01X243652D02*
X245247D01*
G01X239711D02*
X241306D01*
G01X235778D02*
X237373D01*
G01X231837D02*
X233432D01*
G01X227904D02*
X229499D01*
G01X223962D02*
X225558D01*
G01X220030D02*
X221625D01*
G01X216088D02*
X217684D01*
G01X212156D02*
X213751D01*
G01X208214D02*
X209810D01*
G01X204282D02*
X205877D01*
G01X200340D02*
X201936D01*
G01X196408D02*
X198003D01*
G01X192466D02*
X194062D01*
G01X188534D02*
X190129D01*
G01X193938Y138760D02*
X192599D01*
G01X201812D02*
X200473D01*
G01X209686D02*
X208347D01*
G01X217560D02*
X216221D01*
G01X225434D02*
X224095D01*
G01X233308D02*
X231969D01*
G01X241182D02*
X239843D01*
G01X249056D02*
X247717D01*
G01X256930D02*
X255592D01*
G01X264804D02*
X263466D01*
G01X193938Y137775D02*
X192599D01*
G01X201812D02*
X200473D01*
G01X209686D02*
X208347D01*
G01X217560D02*
X216221D01*
G01X225434D02*
X224095D01*
G01X233308D02*
X231969D01*
G01X241182D02*
X239843D01*
G01X249056D02*
X247717D01*
G01X256930D02*
X255592D01*
G01X264804D02*
X263466D01*
G01X263308Y137677D02*
X264962D01*
G01X255434D02*
X257088D01*
G01X247560D02*
X249214D01*
G01X239686D02*
X241340D01*
G01X231812D02*
X233466D01*
G01X223938D02*
X225592D01*
G01X216064D02*
X217717D01*
G01X208190D02*
X209843D01*
G01X200316D02*
X201969D01*
G01X192442D02*
X194095D01*
G01Y137185D02*
X192442D01*
G01X201969D02*
X200316D01*
G01X209843D02*
X208190D01*
G01X217717D02*
X216064D01*
G01X225592D02*
X223938D01*
G01X233466D02*
X231812D01*
G01X241340D02*
X239686D01*
G01X249214D02*
X247560D01*
G01X257088D02*
X255434D01*
G01X264962D02*
X263308D01*
G01X190092Y136570D02*
X188571D01*
G01X194025D02*
X192503D01*
G01X197966D02*
X196445D01*
G01X201899D02*
X200377D01*
G01X205840D02*
X204319D01*
G01X209773D02*
X208251D01*
G01X213714D02*
X212193D01*
G01X217647D02*
X216125D01*
G01X221588D02*
X220067D01*
G01X225521D02*
X223999D01*
G01X229462D02*
X227941D01*
G01X233395D02*
X231873D01*
G01X237336D02*
X235815D01*
G01X241269D02*
X239747D01*
G01X245210D02*
X243689D01*
G01X249143D02*
X247621D01*
G01X253085D02*
X251563D01*
G01X257017D02*
X255495D01*
G01X260959D02*
X259437D01*
G01X264891D02*
X263369D01*
G01X190103Y136551D02*
X188560D01*
G01X194036D02*
X192492D01*
G01X197977D02*
X196434D01*
G01X201910D02*
X200366D01*
G01X205851D02*
X204308D01*
G01X209784D02*
X208240D01*
G01X213725D02*
X212182D01*
G01X217658D02*
X216114D01*
G01X221599D02*
X220056D01*
G01X225532D02*
X223988D01*
G01X229473D02*
X227930D01*
G01X233406D02*
X231862D01*
G01X237347D02*
X235804D01*
G01X241280D02*
X239736D01*
G01X245221D02*
X243678D01*
G01X249154D02*
X247610D01*
G01X253095D02*
X251552D01*
G01X257028D02*
X255484D01*
G01X260969D02*
X259426D01*
G01X264902D02*
X263358D01*
G01X188229Y136515D02*
X187914D01*
G01X190749D02*
X190434D01*
G01X192166D02*
X191851D01*
G01X194686D02*
X194371D01*
G01X196103D02*
X195788D01*
G01X198623D02*
X198308D01*
G01X200040D02*
X199725D01*
G01X202560D02*
X202245D01*
G01X203977D02*
X203662D01*
G01X206497D02*
X206182D01*
G01X207914D02*
X207599D01*
G01X210434D02*
X210119D01*
G01X211851D02*
X211536D01*
G01X214371D02*
X214056D01*
G01X215788D02*
X215473D01*
G01X218308D02*
X217993D01*
G01X219725D02*
X219410D01*
G01X222245D02*
X221930D01*
G01X223662D02*
X223347D01*
G01X226182D02*
X225867D01*
G01X227599D02*
X227284D01*
G01X230119D02*
X229804D01*
G01X231536D02*
X231221D01*
G01X234056D02*
X233741D01*
G01X235473D02*
X235158D01*
G01X239410D02*
X239095D01*
G01X237993D02*
X237678D01*
G01X241930D02*
X241615D01*
G01X243347D02*
X243032D01*
G01X245867D02*
X245552D01*
G01X247284D02*
X246969D01*
G01X249804D02*
X249489D01*
G01X251221D02*
X250906D01*
G01X253741D02*
X253426D01*
G01X255158D02*
X254843D01*
G01X257678D02*
X257363D01*
G01X259095D02*
X258780D01*
G01X261615D02*
X261300D01*
G01X263032D02*
X262717D01*
G01X265552D02*
X265237D01*
G01X266969D02*
X266655D01*
G01X190513Y135984D02*
X188151D01*
G01X194450D02*
X192088D01*
G01X198387D02*
X196025D01*
G01X202324D02*
X199962D01*
G01X206261D02*
X203899D01*
G01X210198D02*
X207836D01*
G01X214135D02*
X211773D01*
G01X218072D02*
X215710D01*
G01X222009D02*
X219647D01*
G01X225946D02*
X223584D01*
G01X229883D02*
X227521D01*
G01X233820D02*
X231458D01*
G01X237757D02*
X235395D01*
G01X241694D02*
X239332D01*
G01X245631D02*
X243269D01*
G01X249568D02*
X247206D01*
G01X253505D02*
X251143D01*
G01X257442D02*
X255080D01*
G01X261379D02*
X259017D01*
G01X265316D02*
X262954D01*
G01X189860Y135937D02*
X188803D01*
G01X193792D02*
X192736D01*
G01X197734D02*
X196677D01*
G01X201666D02*
X200610D01*
G01X205608D02*
X204551D01*
G01X209540D02*
X208484D01*
G01X213482D02*
X212425D01*
G01X217414D02*
X216358D01*
G01X221356D02*
X220299D01*
G01X225288D02*
X224232D01*
G01X229230D02*
X228173D01*
G01X233162D02*
X232106D01*
G01X237104D02*
X236047D01*
G01X241036D02*
X239980D01*
G01X244978D02*
X243921D01*
G01X248910D02*
X247854D01*
G01X252852D02*
X251796D01*
G01X256784D02*
X255728D01*
G01X260726D02*
X259670D01*
G01X264658D02*
X263602D01*
G01X263382Y135615D02*
X264878D01*
G01X259450D02*
X260946D01*
G01X255508D02*
X257004D01*
G01X251576D02*
X253072D01*
G01X247634D02*
X249130D01*
G01X243702D02*
X245198D01*
G01X239760D02*
X241256D01*
G01X235828D02*
X237324D01*
G01X231886D02*
X233382D01*
G01X227954D02*
X229450D01*
G01X224012D02*
X225508D01*
G01X220080D02*
X221576D01*
G01X216138D02*
X217634D01*
G01X212205D02*
X213702D01*
G01X208264D02*
X209760D01*
G01X204331D02*
X205828D01*
G01X200390D02*
X201886D01*
G01X196457D02*
X197954D01*
G01X192516D02*
X194012D01*
G01X188583D02*
X190080D01*
G01X263380Y135605D02*
X264880D01*
G01X259448D02*
X260948D01*
G01X255506D02*
X257006D01*
G01X251574D02*
X253074D01*
G01X247632D02*
X249132D01*
G01X243700D02*
X245200D01*
G01X239758D02*
X241258D01*
G01X235826D02*
X237325D01*
G01X231884D02*
X233384D01*
G01X227952D02*
X229451D01*
G01X224010D02*
X225510D01*
G01X220078D02*
X221577D01*
G01X216136D02*
X217636D01*
G01X212204D02*
X213703D01*
G01X208262D02*
X209762D01*
G01X204330D02*
X205829D01*
G01X200388D02*
X201888D01*
G01X196456D02*
X197955D01*
G01X192514D02*
X194014D01*
G01X188582D02*
X190081D01*
G01X194095Y135413D02*
X192442D01*
G01X201969D02*
X200316D01*
G01X209843D02*
X208190D01*
G01X217717D02*
X216064D01*
G01X225592D02*
X223938D01*
G01X233466D02*
X231812D01*
G01X241340D02*
X239686D01*
G01X249214D02*
X247560D01*
G01X257088D02*
X255434D01*
G01X264962D02*
X263308D01*
G01X263120Y135117D02*
X265141D01*
G01X259187D02*
X261208D01*
G01X255246D02*
X257267D01*
G01X251313D02*
X253334D01*
G01X247372D02*
X249393D01*
G01X243439D02*
X245460D01*
G01X239498D02*
X241519D01*
G01X235565D02*
X237586D01*
G01X231624D02*
X233645D01*
G01X227691D02*
X229712D01*
G01X223750D02*
X225770D01*
G01X219817D02*
X221838D01*
G01X215876D02*
X217896D01*
G01X211943D02*
X213964D01*
G01X208002D02*
X210022D01*
G01X204069D02*
X206090D01*
G01X200128D02*
X202148D01*
G01X196195D02*
X198216D01*
G01X192254D02*
X194274D01*
G01X188321D02*
X190342D01*
G01X265237Y135019D02*
X265552D01*
G01X257363D02*
X257678D01*
G01X249489D02*
X249804D01*
G01X245552D02*
X245867D01*
G01X241615D02*
X241930D01*
G01X237678D02*
X237993D01*
G01X233741D02*
X234056D01*
G01X229804D02*
X230119D01*
G01X225867D02*
X226182D01*
G01X221930D02*
X222245D01*
G01X217993D02*
X218308D01*
G01X214056D02*
X214371D01*
G01X210119D02*
X210434D01*
G01X206182D02*
X206497D01*
G01X202245D02*
X202560D01*
G01X198308D02*
X198623D01*
G01X194371D02*
X194686D01*
G01X188229D02*
X187914D01*
G01X190749D02*
X190434D01*
G01X192166D02*
X191851D01*
G01X196103D02*
X195788D01*
G01X200040D02*
X199725D01*
G01X203977D02*
X203662D01*
G01X207914D02*
X207599D01*
G01X211851D02*
X211536D01*
G01X215788D02*
X215473D01*
G01X219725D02*
X219410D01*
G01X223662D02*
X223347D01*
G01X227599D02*
X227284D01*
G01X231536D02*
X231221D01*
G01X235473D02*
X235158D01*
G01X239410D02*
X239095D01*
G01X243347D02*
X243032D01*
G01X247284D02*
X246969D01*
G01X251221D02*
X250906D01*
G01X253741D02*
X253426D01*
G01X255158D02*
X254843D01*
G01X259095D02*
X258780D01*
G01X261615D02*
X261300D01*
G01X263032D02*
X262717D01*
G01X266969D02*
X266655D01*
G01X263647Y135009D02*
X264613D01*
G01X259715D02*
X260680D01*
G01X255773D02*
X256739D01*
G01X251841D02*
X252806D01*
G01X247899D02*
X248865D01*
G01X243967D02*
X244932D01*
G01X240025D02*
X240991D01*
G01X236093D02*
X237058D01*
G01X232151D02*
X233117D01*
G01X228219D02*
X229184D01*
G01X224277D02*
X225243D01*
G01X220345D02*
X221310D01*
G01X216403D02*
X217369D01*
G01X212471D02*
X213436D01*
G01X208529D02*
X209495D01*
G01X204597D02*
X205562D01*
G01X200655D02*
X201621D01*
G01X196723D02*
X197688D01*
G01X192781D02*
X193747D01*
G01X188849D02*
X189814D01*
G01X263308Y134921D02*
X264962D01*
G01X255434D02*
X257088D01*
G01X247560D02*
X249214D01*
G01X239686D02*
X241340D01*
G01X231812D02*
X233466D01*
G01X223938D02*
X225592D01*
G01X216064D02*
X217717D01*
G01X208190D02*
X209843D01*
G01X200316D02*
X201969D01*
G01X192442D02*
X194095D01*
G01X266655Y134822D02*
X269489D01*
G01X262717D02*
X265552D01*
G01X258780D02*
X261615D01*
G01X254843D02*
X257678D01*
G01X250906D02*
X253741D01*
G01X246969D02*
X249804D01*
G01X243032D02*
X245867D01*
G01X239095D02*
X241930D01*
G01X235158D02*
X237993D01*
G01X231221D02*
X234056D01*
G01X227284D02*
X230119D01*
G01X223347D02*
X226182D01*
G01X219410D02*
X222245D01*
G01X215473D02*
X218308D01*
G01X211536D02*
X214371D01*
G01X207599D02*
X210434D01*
G01X203662D02*
X206497D01*
G01X199725D02*
X202560D01*
G01X195788D02*
X198623D01*
G01X191851D02*
X194686D01*
G01X187914D02*
X190749D01*
G01X266655Y134665D02*
X267245D01*
G01X264962D02*
X265552D01*
G01X262717D02*
X263308D01*
G01X261025D02*
X261615D01*
G01X258780D02*
X259371D01*
G01X257088D02*
X257678D01*
G01X254843D02*
X255434D01*
G01X253151D02*
X253741D01*
G01X250906D02*
X251497D01*
G01X249214D02*
X249804D01*
G01X246969D02*
X247560D01*
G01X245277D02*
X245867D01*
G01X243032D02*
X243623D01*
G01X241340D02*
X241930D01*
G01X239095D02*
X239686D01*
G01X237403D02*
X237993D01*
G01X235158D02*
X235749D01*
G01X233466D02*
X234056D01*
G01X231221D02*
X231812D01*
G01X229529D02*
X230119D01*
G01X227284D02*
X227875D01*
G01X225592D02*
X226182D01*
G01X223347D02*
X223938D01*
G01X221655D02*
X222245D01*
G01X219410D02*
X220001D01*
G01X217717D02*
X218308D01*
G01X215473D02*
X216064D01*
G01X213780D02*
X214371D01*
G01X211536D02*
X212127D01*
G01X209843D02*
X210434D01*
G01X207599D02*
X208190D01*
G01X205906D02*
X206497D01*
G01X203662D02*
X204253D01*
G01X201969D02*
X202560D01*
G01X199725D02*
X200316D01*
G01X198032D02*
X198623D01*
G01X195788D02*
X196379D01*
G01X194095D02*
X194686D01*
G01X191851D02*
X192442D01*
G01X190158D02*
X190749D01*
G01X187914D02*
X188505D01*
G01X190068Y134640D02*
X188595D01*
G01X194001D02*
X192528D01*
G01X197942D02*
X196469D01*
G01X201875D02*
X200402D01*
G01X205816D02*
X204343D01*
G01X209749D02*
X208276D01*
G01X213690D02*
X212217D01*
G01X217623D02*
X216150D01*
G01X221564D02*
X220091D01*
G01X225497D02*
X224024D01*
G01X229438D02*
X227965D01*
G01X233371D02*
X231898D01*
G01X237312D02*
X235839D01*
G01X241245D02*
X239772D01*
G01X245186D02*
X243713D01*
G01X249119D02*
X247646D01*
G01X253060D02*
X251587D01*
G01X256993D02*
X255520D01*
G01X260934D02*
X259461D01*
G01X264867D02*
X263394D01*
G01X263380Y134621D02*
X264880D01*
G01X259448D02*
X260948D01*
G01X255506D02*
X257006D01*
G01X251574D02*
X253074D01*
G01X247632D02*
X249132D01*
G01X243700D02*
X245200D01*
G01X239758D02*
X241258D01*
G01X235826D02*
X237325D01*
G01X231884D02*
X233384D01*
G01X227952D02*
X229451D01*
G01X224010D02*
X225510D01*
G01X220078D02*
X221577D01*
G01X216136D02*
X217636D01*
G01X212204D02*
X213703D01*
G01X208262D02*
X209762D01*
G01X204330D02*
X205829D01*
G01X200388D02*
X201888D01*
G01X196456D02*
X197955D01*
G01X192514D02*
X194014D01*
G01X188582D02*
X190081D01*
G01X190337Y134231D02*
X188326D01*
G01X194270D02*
X192258D01*
G01X198211D02*
X196200D01*
G01X202144D02*
X200132D01*
G01X206085D02*
X204074D01*
G01X210018D02*
X208006D01*
G01X213959D02*
X211948D01*
G01X217892D02*
X215880D01*
G01X221833D02*
X219822D01*
G01X225766D02*
X223754D01*
G01X229707D02*
X227696D01*
G01X233640D02*
X231628D01*
G01X237581D02*
X235570D01*
G01X241514D02*
X239502D01*
G01X245455D02*
X243444D01*
G01X249388D02*
X247376D01*
G01X253329D02*
X251318D01*
G01X257262D02*
X255251D01*
G01X261203D02*
X259192D01*
G01X265136D02*
X263125D01*
G01X188505Y133996D02*
X187914D01*
G01X190749D02*
X190158D01*
G01X192442D02*
X191851D01*
G01X194686D02*
X194095D01*
G01X196379D02*
X195788D01*
G01X198623D02*
X198032D01*
G01X200316D02*
X199725D01*
G01X202560D02*
X201969D01*
G01X204253D02*
X203662D01*
G01X206497D02*
X205906D01*
G01X208190D02*
X207599D01*
G01X210434D02*
X209843D01*
G01X212127D02*
X211536D01*
G01X214371D02*
X213780D01*
G01X216064D02*
X215473D01*
G01X218308D02*
X217717D01*
G01X220001D02*
X219410D01*
G01X222245D02*
X221655D01*
G01X223938D02*
X223347D01*
G01X226182D02*
X225592D01*
G01X227875D02*
X227284D01*
G01X230119D02*
X229529D01*
G01X231812D02*
X231221D01*
G01X234056D02*
X233466D01*
G01X235749D02*
X235158D01*
G01X237993D02*
X237403D01*
G01X239686D02*
X239095D01*
G01X241930D02*
X241340D01*
G01X243623D02*
X243032D01*
G01X245867D02*
X245277D01*
G01X247560D02*
X246969D01*
G01X249804D02*
X249214D01*
G01X251497D02*
X250906D01*
G01X253741D02*
X253151D01*
G01X255434D02*
X254843D01*
G01X257678D02*
X257088D01*
G01X259371D02*
X258780D01*
G01X261615D02*
X261025D01*
G01X263308D02*
X262717D01*
G01X265552D02*
X264962D01*
G01X267245D02*
X266655D01*
G01X190749Y133838D02*
X187914D01*
G01X194686D02*
X191851D01*
G01X198623D02*
X195788D01*
G01X202560D02*
X199725D01*
G01X206497D02*
X203662D01*
G01X210434D02*
X207599D01*
G01X214371D02*
X211536D01*
G01X218308D02*
X215473D01*
G01X222245D02*
X219410D01*
G01X226182D02*
X223347D01*
G01X230119D02*
X227284D01*
G01X234056D02*
X231221D01*
G01X237993D02*
X235158D01*
G01X241930D02*
X239095D01*
G01X245867D02*
X243032D01*
G01X249804D02*
X246969D01*
G01X253741D02*
X250906D01*
G01X257678D02*
X254843D01*
G01X261615D02*
X258780D01*
G01X265552D02*
X262717D01*
G01X269489D02*
X266655D01*
G01X190158Y133740D02*
X188505D01*
G01X198032D02*
X196379D01*
G01X205906D02*
X204253D01*
G01X213780D02*
X212127D01*
G01X221655D02*
X220001D01*
G01X229529D02*
X227875D01*
G01X237403D02*
X235749D01*
G01X245277D02*
X243623D01*
G01X253151D02*
X251497D01*
G01X261025D02*
X259371D01*
G01Y133248D02*
X261025D01*
G01X251497D02*
X253151D01*
G01X243623D02*
X245277D01*
G01X235749D02*
X237403D01*
G01X227875D02*
X229529D01*
G01X220001D02*
X221655D01*
G01X212127D02*
X213780D01*
G01X204253D02*
X205906D01*
G01X196379D02*
X198032D01*
G01X188505D02*
X190158D01*
G01X266655Y132342D02*
X269489D01*
G01X262717D02*
X265552D01*
G01X258780D02*
X261615D01*
G01X254843D02*
X257678D01*
G01X250906D02*
X253741D01*
G01X246969D02*
X249804D01*
G01X243032D02*
X245867D01*
G01X239095D02*
X241930D01*
G01X235158D02*
X237993D01*
G01X231221D02*
X234056D01*
G01X227284D02*
X230119D01*
G01X223347D02*
X226182D01*
G01X219410D02*
X222245D01*
G01X215473D02*
X218308D01*
G01X211536D02*
X214371D01*
G01X207599D02*
X210434D01*
G01X203662D02*
X206497D01*
G01X199725D02*
X202560D01*
G01X195788D02*
X198623D01*
G01X191851D02*
X194686D01*
G01X187914D02*
X190749D01*
G01X259371Y131476D02*
X261025D01*
G01X251497D02*
X253151D01*
G01X243623D02*
X245277D01*
G01X235749D02*
X237403D01*
G01X227875D02*
X229529D01*
G01X220001D02*
X221655D01*
G01X212127D02*
X213780D01*
G01X204253D02*
X205906D01*
G01X196379D02*
X198032D01*
G01X188505D02*
X190158D01*
G01X259017Y131082D02*
X261379D01*
G01X255080D02*
X257442D01*
G01X251143D02*
X253505D01*
G01X247206D02*
X249568D01*
G01X188151D02*
X190513D01*
G01X194450D02*
X192088D01*
G01X198387D02*
X196025D01*
G01X202324D02*
X199962D01*
G01X206261D02*
X203899D01*
G01X210198D02*
X207836D01*
G01X214135D02*
X211773D01*
G01X218072D02*
X215710D01*
G01X222009D02*
X219647D01*
G01X225946D02*
X223584D01*
G01X229883D02*
X227521D01*
G01X233820D02*
X231458D01*
G01X237757D02*
X235395D01*
G01X241694D02*
X239332D01*
G01X245631D02*
X243269D01*
G01X265316D02*
X262954D01*
G01X190158Y130984D02*
X188505D01*
G01X198032D02*
X196379D01*
G01X205906D02*
X204253D01*
G01X213780D02*
X212127D01*
G01X221655D02*
X220001D01*
G01X229529D02*
X227875D01*
G01X237403D02*
X235749D01*
G01X245277D02*
X243623D01*
G01X253151D02*
X251497D01*
G01X261025D02*
X259371D01*
G01X190001Y130885D02*
X188662D01*
G01X197875D02*
X196536D01*
G01X205749D02*
X204410D01*
G01X213623D02*
X212284D01*
G01X221497D02*
X220158D01*
G01X229371D02*
X228032D01*
G01X237245D02*
X235906D01*
G01X245119D02*
X243780D01*
G01X252993D02*
X251655D01*
G01X260867D02*
X259529D01*
G01X262954Y129901D02*
X265316D01*
G01X259017D02*
X261379D01*
G01X255080D02*
X257442D01*
G01X251143D02*
X253505D01*
G01X247206D02*
X249568D01*
G01X243269D02*
X245631D01*
G01X239332D02*
X241694D01*
G01X235395D02*
X237757D01*
G01X231458D02*
X233820D01*
G01X227521D02*
X229883D01*
G01X223584D02*
X225946D01*
G01X219647D02*
X222009D01*
G01X215710D02*
X218072D01*
G01X211773D02*
X214135D01*
G01X207836D02*
X210198D01*
G01X203899D02*
X206261D01*
G01X199962D02*
X202324D01*
G01X196025D02*
X198387D01*
G01X192088D02*
X194450D01*
G01X188151D02*
X190513D01*
G01X252324Y123011D02*
X272009D01*
G01X228702D02*
X248387D01*
G01X205080D02*
X224765D01*
G01X263403Y151737D02*
X263657Y151368D01*
G01X263611Y150441D02*
X263390Y150762D01*
G01X259715Y151368D02*
X259461Y151737D01*
G01X259450Y150760D02*
X259670Y150441D01*
G01X255783Y151368D02*
X255529Y151737D01*
G01X255737Y150441D02*
X255516Y150762D01*
G01X264658Y135937D02*
X264880Y135615D01*
G01X264867Y134640D02*
X264613Y135009D01*
G01X251841Y151368D02*
X251587Y151737D01*
G01X251576Y150760D02*
X251796Y150441D01*
G01X260946Y135617D02*
X260726Y135937D01*
G01X260680Y135009D02*
X260934Y134640D01*
G01X247909Y151368D02*
X247655Y151737D01*
G01X247863Y150441D02*
X247642Y150762D01*
G01X256784Y135937D02*
X257006Y135615D01*
G01X256739Y135009D02*
X256993Y134640D01*
G01X243713Y151737D02*
X243967Y151368D01*
G01X243921Y150441D02*
X243700Y150762D01*
G01X253072Y135617D02*
X252852Y135937D01*
G01X252806Y135009D02*
X253060Y134640D01*
G01X239781Y151737D02*
X240035Y151368D01*
G01X239989Y150441D02*
X239768Y150762D01*
G01X248910Y135937D02*
X249132Y135615D01*
G01X248865Y135009D02*
X249119Y134640D01*
G01X235839Y151737D02*
X236093Y151368D01*
G01X236047Y150441D02*
X235826Y150762D01*
G01X244978Y135937D02*
X245199Y135615D01*
G01X245186Y134640D02*
X244932Y135009D01*
G01X231907Y151737D02*
X232161Y151368D01*
G01X232115Y150441D02*
X231894Y150762D01*
G01X241036Y135937D02*
X241258Y135615D01*
G01X241245Y134640D02*
X240991Y135009D01*
G01X227965Y151737D02*
X228219Y151368D01*
G01X228173Y150441D02*
X227952Y150762D01*
G01X237104Y135937D02*
X237325Y135615D01*
G01X263611Y150441D02*
X263621Y150393D01*
G01X264658Y135937D02*
X264649Y135984D01*
G01X259679Y150393D02*
X259670Y150441D01*
G01X260717Y135984D02*
X260726Y135937D01*
G01X255737Y150441D02*
X255747Y150393D01*
G01X256784Y135937D02*
X256775Y135984D01*
G01X251805Y150393D02*
X251796Y150441D01*
G01X252842Y135984D02*
X252852Y135937D01*
G01X247863Y150441D02*
X247873Y150393D01*
G01X248910Y135937D02*
X248901Y135984D01*
G01X243921Y150441D02*
X243931Y150393D01*
G01X237312Y134640D02*
X237058Y135009D01*
G01X224033Y151737D02*
X224287Y151368D01*
G01X224241Y150441D02*
X224020Y150762D01*
G01X233162Y135937D02*
X233384Y135615D01*
G01X233371Y134640D02*
X233117Y135009D01*
G01X220091Y151737D02*
X220345Y151368D01*
G01X220299Y150441D02*
X220078Y150762D01*
G01X229230Y135937D02*
X229451Y135615D01*
G01X229438Y134640D02*
X229184Y135009D01*
G01X216159Y151737D02*
X216413Y151368D01*
G01X216367Y150441D02*
X216146Y150762D01*
G01X225288Y135937D02*
X225510Y135615D01*
G01X225497Y134640D02*
X225243Y135009D01*
G01X212217Y151737D02*
X212471Y151368D01*
G01X212425Y150441D02*
X212204Y150762D01*
G01X221356Y135937D02*
X221577Y135615D01*
G01X221564Y134640D02*
X221310Y135009D01*
G01X208285Y151737D02*
X208539Y151368D01*
G01X208493Y150441D02*
X208272Y150762D01*
G01X217414Y135937D02*
X217636Y135615D01*
G01X217623Y134640D02*
X217369Y135009D01*
G01X204343Y151737D02*
X204597Y151368D01*
G01X204551Y150441D02*
X204330Y150762D01*
G01X213482Y135937D02*
X213703Y135615D01*
G01X213690Y134640D02*
X213436Y135009D01*
G01X200411Y151737D02*
X200665Y151368D01*
G01X200619Y150441D02*
X200398Y150762D01*
G01X209540Y135937D02*
X209762Y135615D01*
G01X209749Y134640D02*
X209495Y135009D01*
G01X196469Y151737D02*
X196723Y151368D01*
G01X264928Y139379D02*
X264978Y140365D01*
G01X264976Y141327D02*
X264925Y140340D01*
G01X263294Y145050D02*
X263344Y146037D01*
G01X263342Y146999D02*
X263291Y146012D01*
G01X260995Y139379D02*
X261046Y140365D01*
G01X261044Y141327D02*
X260993Y140340D01*
G01X265014Y145353D02*
X265150Y151260D01*
G01X265145Y152147D02*
X265009Y146239D01*
G01X263125Y134231D02*
X263261Y140138D01*
G01X263256Y141024D02*
X263120Y135117D01*
G01X261072Y145353D02*
X261208Y151260D01*
G01X261203Y152147D02*
X261067Y146239D01*
G01X259192Y134231D02*
X259328Y140138D01*
G01X259324Y141024D02*
X259187Y135117D01*
G01X264626Y135984D02*
X264613Y135009D01*
G01X263644Y150393D02*
X263657Y151368D01*
G01X260694Y135984D02*
X260680Y135009D01*
G01X259702Y150393D02*
X259715Y151368D01*
G01X266694Y134822D02*
Y133838D01*
G01Y152539D02*
Y151555D01*
G01X266689Y152539D02*
Y151555D01*
G01X266655Y136515D02*
Y132342D01*
G01Y154035D02*
Y149862D01*
G01X265552D02*
Y154035D01*
G01Y132342D02*
Y136515D01*
G01X265517Y152539D02*
Y151555D01*
G01X265513Y134822D02*
Y133838D01*
G01X265508Y134822D02*
Y133838D01*
G01X265316Y135984D02*
Y129901D01*
G01Y156476D02*
Y150393D01*
G01X265237Y133838D02*
Y152539D01*
G01X265163Y152538D02*
Y151553D01*
G01X265154Y134824D02*
Y133840D01*
G01X264962Y147698D02*
Y152539D01*
G01Y133838D02*
Y138680D01*
G01X264888Y150760D02*
Y151750D01*
G01X264878Y134627D02*
Y135617D01*
G01X264804Y138760D02*
Y137696D01*
G01Y148681D02*
Y147618D01*
G01X264529D02*
Y148602D01*
G01Y138760D02*
Y137775D01*
G01X263741Y147618D02*
Y148602D01*
G01Y137775D02*
Y138760D01*
G01X263466D02*
Y137696D01*
G01Y148681D02*
Y147618D01*
G01X263391Y151750D02*
Y150760D01*
G01X263382Y135617D02*
Y134627D01*
G01X263308Y147698D02*
Y152539D01*
G01Y133838D02*
Y138680D01*
G01X263116Y151553D02*
Y152538D01*
G01X263107Y133840D02*
Y134824D01*
G01X263032Y152539D02*
Y133838D01*
G01X262954Y135984D02*
Y129901D01*
G01Y156476D02*
Y150393D01*
G01X262762Y152539D02*
Y151555D01*
G01X262757Y152539D02*
Y151555D01*
G01X262752Y134822D02*
Y133838D01*
G01X262717Y136515D02*
Y132342D01*
G01Y154035D02*
Y149862D01*
G01X261615D02*
Y154035D01*
G01Y132342D02*
Y136515D01*
G01X261580Y134822D02*
Y133838D01*
G01X261576Y134822D02*
Y133838D01*
G01Y152539D02*
Y151555D01*
G01X261379Y135984D02*
Y129901D01*
G01Y156476D02*
Y150393D01*
G01X261300Y133838D02*
Y152539D01*
G01X261221Y134824D02*
Y133840D01*
G01Y152538D02*
Y151553D01*
G01X261025Y151555D02*
Y156396D01*
G01Y129981D02*
Y134822D01*
G01X260946Y150760D02*
Y151750D01*
G01Y134627D02*
Y135617D01*
G01X260867Y130965D02*
Y129901D01*
G01Y156476D02*
Y155412D01*
G01X260592Y129901D02*
Y130885D01*
G01Y156476D02*
Y155492D01*
G01X259804Y130885D02*
Y129901D01*
G01Y156476D02*
Y155492D01*
G01X259529Y130965D02*
Y129901D01*
G01Y156476D02*
Y155412D01*
G01X259450Y135617D02*
Y134627D01*
G01Y151750D02*
Y150760D01*
G01X259371Y151555D02*
Y156396D01*
G01Y129981D02*
Y134822D01*
G01X259174Y133840D02*
Y134824D01*
G01Y151553D02*
Y152538D01*
G01X259095Y152539D02*
Y133838D01*
G01X259017Y135984D02*
Y129901D01*
G01Y156476D02*
Y150393D01*
G01X258820Y134822D02*
Y133838D01*
G01Y152539D02*
Y151555D01*
G01X258815Y152539D02*
Y151555D01*
G01X258780Y136515D02*
Y132342D01*
G01Y154035D02*
Y149862D01*
G01X257678D02*
Y154035D01*
G01Y132342D02*
Y136515D01*
G01X257643Y152539D02*
Y151555D01*
G01X257639Y134822D02*
Y133838D01*
G01X257634Y134822D02*
Y133838D01*
G01X257442Y135984D02*
Y129901D01*
G01Y156476D02*
Y150393D01*
G01X257363Y133838D02*
Y152539D01*
G01X257289Y152538D02*
Y151553D01*
G01X257280Y134824D02*
Y133840D01*
G01X264622Y151368D02*
X264635Y150393D01*
G01X263647Y135009D02*
X263634Y135984D01*
G01X260680Y151368D02*
X260694Y150393D01*
G01X259715Y135009D02*
X259702Y135984D01*
G01X256748Y151368D02*
X256761Y150393D01*
G01X265141Y135117D02*
X265004Y141024D01*
G01X265000Y140138D02*
X265136Y134231D01*
G01X263270Y146239D02*
X263134Y152147D01*
G01X263129Y151260D02*
X263265Y145353D01*
G01X261208Y135117D02*
X261072Y141024D01*
G01X261067Y140138D02*
X261203Y134231D01*
G01X259328Y146239D02*
X259192Y152147D01*
G01X259187Y151260D02*
X259324Y145353D01*
G01X257267Y135117D02*
X257130Y141024D01*
G01X257126Y140138D02*
X257262Y134231D01*
G01X264988Y146012D02*
X264937Y146999D01*
G01X264935Y146037D02*
X264985Y145050D01*
G01X263335Y140340D02*
X263284Y141327D01*
G01X263282Y140365D02*
X263333Y139379D01*
G01X261046Y146012D02*
X260995Y146999D01*
G01X260993Y146037D02*
X261044Y145050D01*
G01X259403Y140340D02*
X259352Y141327D01*
G01X259350Y140365D02*
X259400Y139379D01*
G01X257114Y146012D02*
X257063Y146999D01*
G01X257061Y146037D02*
X257111Y145050D01*
G01X255461Y140340D02*
X255410Y141327D01*
G01X255408Y140365D02*
X255459Y139379D01*
G01X244978Y135937D02*
X244968Y135984D01*
G01X239989Y150441D02*
X239999Y150393D01*
G01X241036Y135937D02*
X241027Y135984D01*
G01X236047Y150441D02*
X236057Y150393D01*
G01X237104Y135937D02*
X237094Y135984D01*
G01X232115Y150441D02*
X232125Y150393D01*
G01X233162Y135937D02*
X233153Y135984D01*
G01X228173Y150441D02*
X228183Y150393D01*
G01X229230Y135937D02*
X229220Y135984D01*
G01X224241Y150441D02*
X224251Y150393D01*
G01X225288Y135937D02*
X225279Y135984D01*
G01X220299Y150441D02*
X220309Y150393D01*
G01X221356Y135937D02*
X221346Y135984D01*
G01X196677Y150441D02*
X196456Y150762D01*
G01X205608Y135937D02*
X205829Y135615D01*
G01X205816Y134640D02*
X205562Y135009D01*
G01X192537Y151737D02*
X192791Y151368D01*
G01X192745Y150441D02*
X192524Y150762D01*
G01X201666Y135937D02*
X201888Y135615D01*
G01X201875Y134640D02*
X201621Y135009D01*
G01X188849Y151368D02*
X188595Y151737D01*
G01X188584Y150760D02*
X188803Y150441D01*
G01X197734Y135937D02*
X197955Y135615D01*
G01X197942Y134640D02*
X197688Y135009D01*
G01X193792Y135937D02*
X194014Y135615D01*
G01X194001Y134640D02*
X193747Y135009D01*
G01X190080Y135617D02*
X189860Y135937D01*
G01X189814Y135009D02*
X190068Y134640D01*
G01X263394D02*
X263647Y135009D01*
G01X263381Y135615D02*
X263602Y135937D01*
G01X259461Y134640D02*
X259715Y135009D01*
G01X259670Y135937D02*
X259450Y135617D01*
G01X255520Y134640D02*
X255773Y135009D01*
G01X255507Y135615D02*
X255728Y135937D01*
G01X264889Y150762D02*
X264668Y150441D01*
G01X264876Y151737D02*
X264622Y151368D01*
G01X251587Y134640D02*
X251841Y135009D01*
G01X251796Y135937D02*
X251576Y135617D01*
G01X260726Y150441D02*
X260946Y150760D01*
G01X260934Y151737D02*
X260680Y151368D01*
G01X247646Y134640D02*
X247899Y135009D01*
G01X247632Y135615D02*
X247854Y135937D01*
G01X263611Y135984D02*
X263602Y135937D01*
G01X264658Y150393D02*
X264668Y150441D01*
G01X259670Y135937D02*
X259679Y135984D01*
G01X260726Y150441D02*
X260717Y150393D01*
G01X255737Y135984D02*
X255728Y135937D01*
G01X256784Y150393D02*
X256794Y150441D01*
G01X251796Y135937D02*
X251805Y135984D01*
G01X252852Y150441D02*
X252842Y150393D01*
G01X247863Y135984D02*
X247854Y135937D01*
G01X248910Y150393D02*
X248920Y150441D01*
G01X243931Y135984D02*
X243921Y135937D01*
G01X244968Y150393D02*
X244978Y150441D01*
G01X259352Y145050D02*
X259403Y146037D01*
G01X259400Y146999D02*
X259350Y146012D01*
G01X257054Y139379D02*
X257104Y140365D01*
G01X257102Y141327D02*
X257051Y140340D01*
G01X255420Y145050D02*
X255470Y146037D01*
G01X255468Y146999D02*
X255417Y146012D01*
G01X253121Y139379D02*
X253172Y140365D01*
G01X253170Y141327D02*
X253119Y140340D01*
G01X251478Y145050D02*
X251529Y146037D01*
G01X251526Y146999D02*
X251476Y146012D01*
G01X249180Y139379D02*
X249230Y140365D01*
G01X249228Y141327D02*
X249177Y140340D01*
G01X247546Y145050D02*
X247596Y146037D01*
G01X247594Y146999D02*
X247543Y146012D01*
G01X245247Y139379D02*
X245298Y140365D01*
G01X245296Y141327D02*
X245245Y140340D01*
G01X243604Y145050D02*
X243655Y146037D01*
G01X243652Y146999D02*
X243602Y146012D01*
G01X241306Y139379D02*
X241356Y140365D01*
G01X241354Y141327D02*
X241303Y140340D01*
G01X239672Y145050D02*
X239722Y146037D01*
G01X239720Y146999D02*
X239669Y146012D01*
G01X237373Y139379D02*
X237424Y140365D01*
G01X237421Y141327D02*
X237371Y140340D01*
G01X235730Y145050D02*
X235781Y146037D01*
G01X257140Y145353D02*
X257276Y151260D01*
G01X257271Y152147D02*
X257135Y146239D01*
G01X255251Y134231D02*
X255387Y140138D01*
G01X255382Y141024D02*
X255246Y135117D01*
G01X253198Y145353D02*
X253334Y151260D01*
G01X253329Y152147D02*
X253193Y146239D01*
G01X251318Y134231D02*
X251454Y140138D01*
G01X251450Y141024D02*
X251313Y135117D01*
G01X249266Y145353D02*
X249402Y151260D01*
G01X249397Y152147D02*
X249261Y146239D01*
G01X247376Y134231D02*
X247513Y140138D01*
G01X247508Y141024D02*
X247372Y135117D01*
G01X245324Y145353D02*
X245460Y151260D01*
G01X245455Y152147D02*
X245319Y146239D01*
G01X243444Y134231D02*
X243580Y140138D01*
G01X243576Y141024D02*
X243439Y135117D01*
G01X241392Y145353D02*
X241528Y151260D01*
G01X241523Y152147D02*
X241387Y146239D01*
G01X239502Y134231D02*
X239639Y140138D01*
G01X239634Y141024D02*
X239498Y135117D01*
G01X237450Y145353D02*
X237586Y151260D01*
G01X237581Y152147D02*
X237445Y146239D01*
G01X235570Y134231D02*
X235706Y140138D01*
G01X235702Y141024D02*
X235565Y135117D01*
G01X256752Y135984D02*
X256739Y135009D01*
G01X255770Y150393D02*
X255783Y151368D01*
G01X252820Y135984D02*
X252806Y135009D01*
G01X251828Y150393D02*
X251841Y151368D01*
G01X248878Y135984D02*
X248865Y135009D01*
G01X247896Y150393D02*
X247909Y151368D01*
G01X244946Y135984D02*
X244932Y135009D01*
G01X243954Y150393D02*
X243967Y151368D01*
G01X241004Y135984D02*
X240991Y135009D01*
G01X240022Y150393D02*
X240035Y151368D01*
G01X237072Y135984D02*
X237058Y135009D01*
G01X236080Y150393D02*
X236093Y151368D01*
G01X257088Y147698D02*
Y152539D01*
G01Y133838D02*
Y138680D01*
G01X257014Y150760D02*
Y151750D01*
G01X257004Y134627D02*
Y135617D01*
G01X256930Y138760D02*
Y137696D01*
G01Y148681D02*
Y147618D01*
G01X256655D02*
Y148602D01*
G01Y138760D02*
Y137775D01*
G01X255867Y147618D02*
Y148602D01*
G01Y138760D02*
Y137775D01*
G01X255592Y138760D02*
Y137696D01*
G01Y148681D02*
Y147618D01*
G01X255517Y151750D02*
Y150760D01*
G01X255508Y135617D02*
Y134627D01*
G01X255473Y128523D02*
Y123011D01*
G01X255434Y147698D02*
Y152539D01*
G01Y133838D02*
Y138680D01*
G01X255242Y151553D02*
Y152538D01*
G01X255233Y133840D02*
Y134824D01*
G01X255158Y152539D02*
Y133838D01*
G01X255080Y135984D02*
Y129901D01*
G01Y156476D02*
Y150393D01*
G01X254888Y152539D02*
Y151555D01*
G01X254883Y152539D02*
Y151555D01*
G01X254878Y134822D02*
Y133838D01*
G01X254843Y136515D02*
Y132342D01*
G01Y154035D02*
Y149862D01*
G01X253741D02*
Y154035D01*
G01Y132342D02*
Y136515D01*
G01X253706Y134822D02*
Y133838D01*
G01X253702Y134822D02*
Y133838D01*
G01Y152539D02*
Y151555D01*
G01X253505Y135984D02*
Y129901D01*
G01Y156476D02*
Y150393D01*
G01X253426Y133838D02*
Y152539D01*
G01X253347Y134824D02*
Y133840D01*
G01Y152538D02*
Y151553D01*
G01X253151Y151555D02*
Y156396D01*
G01Y129981D02*
Y134822D01*
G01X253072Y150760D02*
Y151750D01*
G01Y134627D02*
Y135617D01*
G01X252993Y130965D02*
Y129901D01*
G01Y156476D02*
Y155412D01*
G01X252717Y129901D02*
Y130885D01*
G01Y156476D02*
Y155492D01*
G01X252324Y128523D02*
Y123011D01*
G01X251930Y130885D02*
Y129901D01*
G01Y156476D02*
Y155492D01*
G01X251655Y130965D02*
Y129901D01*
G01Y156476D02*
Y155412D01*
G01X251576Y135617D02*
Y134627D01*
G01Y151750D02*
Y150760D01*
G01X251497Y151555D02*
Y156396D01*
G01Y129981D02*
Y134822D01*
G01X251300Y133840D02*
Y134824D01*
G01Y151553D02*
Y152538D01*
G01X251221Y152539D02*
Y133838D01*
G01X251143Y135984D02*
Y129901D01*
G01Y156476D02*
Y150393D01*
G01X250946Y134822D02*
Y133838D01*
G01Y152539D02*
Y151555D01*
G01X250941Y152539D02*
Y151555D01*
G01X250906Y136515D02*
Y132342D01*
G01Y154035D02*
Y149862D01*
G01X249804D02*
Y154035D01*
G01Y132342D02*
Y136515D01*
G01X249769Y152539D02*
Y151555D01*
G01X249765Y134822D02*
Y133838D01*
G01X249760Y134822D02*
Y133838D01*
G01X249568Y135984D02*
Y129901D01*
G01Y156476D02*
Y150393D01*
G01X249489Y133838D02*
Y152539D01*
G01X249415Y152538D02*
Y151553D01*
G01X249406Y134824D02*
Y133840D01*
G01X249214Y147698D02*
Y152539D01*
G01Y133838D02*
Y138680D01*
G01X249139Y150760D02*
Y151750D01*
G01X249130Y134627D02*
Y135617D01*
G01X249056Y138760D02*
Y137696D01*
G01Y148681D02*
Y147618D01*
G01X248780D02*
Y148602D01*
G01Y138760D02*
Y137775D01*
G01X248387Y128523D02*
Y123011D01*
G01X247993Y147618D02*
Y148602D01*
G01Y138760D02*
Y137775D01*
G01X247717Y138760D02*
Y137696D01*
G01Y148681D02*
Y147618D01*
G01X247643Y151750D02*
Y150760D01*
G01X247634Y135617D02*
Y134627D01*
G01X247560Y147698D02*
Y152539D01*
G01Y133838D02*
Y138680D01*
G01X247368Y151553D02*
Y152538D01*
G01X247359Y133840D02*
Y134824D01*
G01X247284Y152539D02*
Y133838D01*
G01X247206Y135984D02*
Y129901D01*
G01Y156476D02*
Y150393D01*
G01X247014Y152539D02*
Y151555D01*
G01X247009Y152539D02*
Y151555D01*
G01X247004Y134822D02*
Y133838D01*
G01X246969Y136515D02*
Y132342D01*
G01Y154035D02*
Y149862D01*
G01X245867D02*
Y154035D01*
G01Y132342D02*
Y136515D01*
G01X245832Y134822D02*
Y133838D01*
G01X245828Y134822D02*
Y133838D01*
G01Y152539D02*
Y151555D01*
G01X245631Y135984D02*
Y129901D01*
G01Y156476D02*
Y150393D01*
G01X245552Y133838D02*
Y152539D01*
G01X245473Y134824D02*
Y133840D01*
G01Y152538D02*
Y151553D01*
G01X245277Y151555D02*
Y156396D01*
G01Y129981D02*
Y134822D01*
G01X245237Y128523D02*
Y123011D01*
G01X245198Y150760D02*
Y151750D01*
G01Y134627D02*
Y135617D01*
G01X245119Y130965D02*
Y129901D01*
G01Y156476D02*
Y155412D01*
G01X244843Y130885D02*
Y129901D01*
G01Y156476D02*
Y155492D01*
G01X244056D02*
Y156476D01*
G01Y130885D02*
Y129901D01*
G01X243780Y130965D02*
Y129901D01*
G01Y156476D02*
Y155412D01*
G01X243702Y135617D02*
Y134627D01*
G01Y151750D02*
Y150760D01*
G01X243623Y151555D02*
Y156396D01*
G01Y129981D02*
Y134822D01*
G01X243426Y151553D02*
Y152538D01*
G01Y133840D02*
Y134824D01*
G01X243347Y152539D02*
Y133838D01*
G01X243269Y135984D02*
Y129901D01*
G01Y156476D02*
Y150393D01*
G01X243072Y134822D02*
Y133838D01*
G01Y152539D02*
Y151555D01*
G01X243067Y152539D02*
Y151555D01*
G01X243032Y136515D02*
Y132342D01*
G01Y154035D02*
Y149862D01*
G01X241930D02*
Y154035D01*
G01Y132342D02*
Y136515D01*
G01X241895Y152539D02*
Y151555D01*
G01X241891Y134822D02*
Y133838D01*
G01X241886Y134822D02*
Y133838D01*
G01X241694Y135984D02*
Y129901D01*
G01Y156476D02*
Y150393D01*
G01X241615Y133838D02*
Y152539D01*
G01X241541Y152538D02*
Y151553D01*
G01X241532Y134824D02*
Y133840D01*
G01X241340Y147698D02*
Y152539D01*
G01Y133838D02*
Y138680D01*
G01X241265Y150760D02*
Y151750D01*
G01X241256Y134627D02*
Y135617D01*
G01X241182Y138760D02*
Y137696D01*
G01Y148681D02*
Y147618D01*
G01X240906Y138760D02*
Y137775D01*
G01Y148602D02*
Y147618D01*
G01X240119Y138760D02*
Y137775D01*
G01Y148602D02*
Y147618D01*
G01X239843Y138760D02*
Y137696D01*
G01Y148681D02*
Y147618D01*
G01X239769Y151750D02*
Y150760D01*
G01X239760Y135617D02*
Y134627D01*
G01X239686Y147698D02*
Y152539D01*
G01Y133838D02*
Y138680D01*
G01X239494Y151553D02*
Y152538D01*
G01X239484Y133840D02*
Y134824D01*
G01X239410Y152539D02*
Y133838D01*
G01X239332Y135984D02*
Y129901D01*
G01Y156476D02*
Y150393D01*
G01X239139Y152539D02*
Y151555D01*
G01X239135Y152539D02*
Y151555D01*
G01X239130Y134822D02*
Y133838D01*
G01X239095Y136515D02*
Y132342D01*
G01Y154035D02*
Y149862D01*
G01X237993D02*
Y154035D01*
G01Y132342D02*
Y136515D01*
G01X237958Y134822D02*
Y133838D01*
G01X237954Y134822D02*
Y133838D01*
G01Y152539D02*
Y151555D01*
G01X237757Y135984D02*
Y129901D01*
G01Y156476D02*
Y150393D01*
G01X237678Y133838D02*
Y152539D01*
G01X237599Y134824D02*
Y133840D01*
G01Y152538D02*
Y151553D01*
G01X237403Y151555D02*
Y156396D01*
G01Y129981D02*
Y134822D01*
G01X237324Y150760D02*
Y151750D01*
G01Y134627D02*
Y135617D01*
G01X237245Y130965D02*
Y129901D01*
G01Y156476D02*
Y155412D01*
G01X236969Y130885D02*
Y129901D01*
G01Y156476D02*
Y155492D01*
G01X236182D02*
Y156476D01*
G01Y130885D02*
Y129901D01*
G01X235906Y130965D02*
Y129901D01*
G01Y156476D02*
Y155412D01*
G01X235828Y135617D02*
Y134627D01*
G01Y151750D02*
Y150760D01*
G01X235749Y151555D02*
Y156396D01*
G01Y129981D02*
Y134822D01*
G01X235552Y151553D02*
Y152538D01*
G01Y133840D02*
Y134824D01*
G01X235473Y152539D02*
Y133838D01*
G01X235395Y135984D02*
Y129901D01*
G01Y156476D02*
Y150393D01*
G01X235198Y134822D02*
Y133838D01*
G01Y152539D02*
Y151555D01*
G01X235193Y152539D02*
Y151555D01*
G01X235158Y136515D02*
Y132342D01*
G01Y154035D02*
Y149862D01*
G01X234056D02*
Y154035D01*
G01Y132342D02*
Y136515D01*
G01X234021Y152539D02*
Y151555D01*
G01X234017Y134822D02*
Y133838D01*
G01X234012Y134822D02*
Y133838D01*
G01X233820Y135984D02*
Y129901D01*
G01Y156476D02*
Y150393D01*
G01X233741Y133838D02*
Y152539D01*
G01X233667Y152538D02*
Y151553D01*
G01X233658Y134824D02*
Y133840D01*
G01X233466Y147698D02*
Y152539D01*
G01Y133838D02*
Y138680D01*
G01X233391Y150760D02*
Y151750D01*
G01X233382Y134627D02*
Y135617D01*
G01X233308Y138760D02*
Y137696D01*
G01Y148681D02*
Y147618D01*
G01X233032D02*
Y148602D01*
G01Y138760D02*
Y137775D01*
G01X255773Y135009D02*
X255760Y135984D01*
G01X252806Y151368D02*
X252820Y150393D01*
G01X251841Y135009D02*
X251828Y135984D01*
G01X248874Y151368D02*
X248887Y150393D01*
G01X247899Y135009D02*
X247886Y135984D01*
G01X244932Y151368D02*
X244946Y150393D01*
G01X243967Y135009D02*
X243954Y135984D01*
G01X241000Y151368D02*
X241013Y150393D01*
G01X240025Y135009D02*
X240012Y135984D01*
G01X237058Y151368D02*
X237072Y150393D01*
G01X236093Y135009D02*
X236080Y135984D01*
G01X233126Y151368D02*
X233139Y150393D01*
G01X232151Y135009D02*
X232138Y135984D01*
G01X255396Y146239D02*
X255260Y152147D01*
G01X255255Y151260D02*
X255391Y145353D01*
G01X253334Y135117D02*
X253198Y141024D01*
G01X253193Y140138D02*
X253329Y134231D01*
G01X251454Y146239D02*
X251318Y152147D01*
G01X251313Y151260D02*
X251450Y145353D01*
G01X249393Y135117D02*
X249256Y141024D01*
G01X249252Y140138D02*
X249388Y134231D01*
G01X247522Y146239D02*
X247386Y152147D01*
G01X247381Y151260D02*
X247517Y145353D01*
G01X245460Y135117D02*
X245324Y141024D01*
G01X245319Y140138D02*
X245455Y134231D01*
G01X243580Y146239D02*
X243444Y152147D01*
G01X243439Y151260D02*
X243576Y145353D01*
G01X241519Y135117D02*
X241382Y141024D01*
G01X241378Y140138D02*
X241514Y134231D01*
G01X239648Y146239D02*
X239512Y152147D01*
G01X239507Y151260D02*
X239643Y145353D01*
G01X237586Y135117D02*
X237450Y141024D01*
G01X237445Y140138D02*
X237581Y134231D01*
G01X235706Y146239D02*
X235570Y152147D01*
G01X235565Y151260D02*
X235702Y145353D01*
G01X233645Y135117D02*
X233508Y141024D01*
G01X233503Y140138D02*
X233640Y134231D01*
G01X231774Y146239D02*
X231638Y152147D01*
G01X231633Y151260D02*
X231769Y145353D01*
G01X253172Y146012D02*
X253121Y146999D01*
G01X253119Y146037D02*
X253170Y145050D01*
G01X251529Y140340D02*
X251478Y141327D01*
G01X251476Y140365D02*
X251526Y139379D01*
G01X249240Y146012D02*
X249189Y146999D01*
G01X249187Y146037D02*
X249237Y145050D01*
G01X247587Y140340D02*
X247536Y141327D01*
G01X247534Y140365D02*
X247585Y139379D01*
G01X245298Y146012D02*
X245247Y146999D01*
G01X245245Y146037D02*
X245296Y145050D01*
G01X243655Y140340D02*
X243604Y141327D01*
G01X243602Y140365D02*
X243652Y139379D01*
G01X241366Y146012D02*
X241315Y146999D01*
G01X241313Y146037D02*
X241363Y145050D01*
G01X239713Y140340D02*
X239662Y141327D01*
G01X239660Y140365D02*
X239711Y139379D01*
G01X237424Y146012D02*
X237373Y146999D01*
G01X237371Y146037D02*
X237421Y145050D01*
G01X235781Y140340D02*
X235730Y141327D01*
G01X235728Y140365D02*
X235778Y139379D01*
G01X233491Y146012D02*
X233441Y146999D01*
G01X233439Y146037D02*
X233489Y145050D01*
G01X231839Y140340D02*
X231788Y141327D01*
G01X231786Y140365D02*
X231837Y139379D01*
G01X229550Y146012D02*
X229499Y146999D01*
G01X229497Y146037D02*
X229547Y145050D01*
G01X216367Y150441D02*
X216377Y150393D01*
G01X217414Y135937D02*
X217405Y135984D01*
G01X212425Y150441D02*
X212435Y150393D01*
G01X213482Y135937D02*
X213472Y135984D01*
G01X208493Y150441D02*
X208503Y150393D01*
G01X209540Y135937D02*
X209531Y135984D01*
G01X204551Y150441D02*
X204561Y150393D01*
G01X205608Y135937D02*
X205598Y135984D01*
G01X200619Y150441D02*
X200629Y150393D01*
G01X201666Y135937D02*
X201657Y135984D01*
G01X196677Y150441D02*
X196687Y150393D01*
G01X197734Y135937D02*
X197724Y135984D01*
G01X192745Y150441D02*
X192755Y150393D01*
G01X257015Y150762D02*
X256794Y150441D01*
G01X257002Y151737D02*
X256748Y151368D01*
G01X243713Y134640D02*
X243967Y135009D01*
G01X243700Y135615D02*
X243921Y135937D01*
G01X252852Y150441D02*
X253072Y150760D01*
G01X253060Y151737D02*
X252806Y151368D01*
G01X239772Y134640D02*
X240025Y135009D01*
G01X239758Y135615D02*
X239980Y135937D01*
G01X249141Y150762D02*
X248920Y150441D01*
G01X249128Y151737D02*
X248874Y151368D01*
G01X235839Y134640D02*
X236093Y135009D01*
G01X235826Y135615D02*
X236047Y135937D01*
G01X245199Y150762D02*
X244978Y150441D01*
G01X245186Y151737D02*
X244932Y151368D01*
G01X231898Y134640D02*
X232151Y135009D01*
G01X231884Y135615D02*
X232106Y135937D01*
G01X241267Y150762D02*
X241046Y150441D01*
G01X241254Y151737D02*
X241000Y151368D01*
G01X227965Y134640D02*
X228219Y135009D01*
G01X227952Y135615D02*
X228173Y135937D01*
G01X237325Y150762D02*
X237104Y150441D01*
G01X237312Y151737D02*
X237058Y151368D01*
G01X224024Y134640D02*
X224277Y135009D01*
G01X224010Y135615D02*
X224232Y135937D01*
G01X233393Y150762D02*
X233172Y150441D01*
G01X233380Y151737D02*
X233126Y151368D01*
G01X220091Y134640D02*
X220345Y135009D01*
G01X220078Y135615D02*
X220299Y135937D01*
G01X229451Y150762D02*
X229230Y150441D01*
G01X229438Y151737D02*
X229184Y151368D01*
G01X239989Y135984D02*
X239980Y135937D01*
G01X241036Y150393D02*
X241046Y150441D01*
G01X236057Y135984D02*
X236047Y135937D01*
G01X237094Y150393D02*
X237104Y150441D01*
G01X232115Y135984D02*
X232106Y135937D01*
G01X233162Y150393D02*
X233172Y150441D01*
G01X228183Y135984D02*
X228173Y135937D01*
G01X229220Y150393D02*
X229230Y150441D01*
G01X224241Y135984D02*
X224232Y135937D01*
G01X225288Y150393D02*
X225298Y150441D01*
G01X220309Y135984D02*
X220299Y135937D01*
G01X221346Y150393D02*
X221356Y150441D01*
G01X216367Y135984D02*
X216358Y135937D01*
G01X235778Y146999D02*
X235728Y146012D01*
G01X233432Y139379D02*
X233482Y140365D01*
G01X233480Y141327D02*
X233429Y140340D01*
G01X231798Y145050D02*
X231848Y146037D01*
G01X231846Y146999D02*
X231795Y146012D01*
G01X229499Y139379D02*
X229550Y140365D01*
G01X229547Y141327D02*
X229497Y140340D01*
G01X227856Y145050D02*
X227907Y146037D01*
G01X227904Y146999D02*
X227854Y146012D01*
G01X225558Y139379D02*
X225608Y140365D01*
G01X225606Y141327D02*
X225555Y140340D01*
G01X223924Y145050D02*
X223974Y146037D01*
G01X223972Y146999D02*
X223921Y146012D01*
G01X221625Y139379D02*
X221676Y140365D01*
G01X221673Y141327D02*
X221623Y140340D01*
G01X219982Y145050D02*
X220032Y146037D01*
G01X220030Y146999D02*
X219980Y146012D01*
G01X217684Y139379D02*
X217734Y140365D01*
G01X217732Y141327D02*
X217681Y140340D01*
G01X216050Y145050D02*
X216100Y146037D01*
G01X216098Y146999D02*
X216047Y146012D01*
G01X213751Y139379D02*
X213802Y140365D01*
G01X213799Y141327D02*
X213749Y140340D01*
G01X212108Y145050D02*
X212158Y146037D01*
G01X212156Y146999D02*
X212106Y146012D01*
G01X233518Y145353D02*
X233654Y151260D01*
G01X233649Y152147D02*
X233513Y146239D01*
G01X231628Y134231D02*
X231765Y140138D01*
G01X231760Y141024D02*
X231624Y135117D01*
G01X229576Y145353D02*
X229712Y151260D01*
G01X229707Y152147D02*
X229571Y146239D01*
G01X227696Y134231D02*
X227832Y140138D01*
G01X227828Y141024D02*
X227691Y135117D01*
G01X225644Y145353D02*
X225780Y151260D01*
G01X225775Y152147D02*
X225639Y146239D01*
G01X223754Y134231D02*
X223891Y140138D01*
G01X223886Y141024D02*
X223750Y135117D01*
G01X221702Y145353D02*
X221838Y151260D01*
G01X221833Y152147D02*
X221697Y146239D01*
G01X219822Y134231D02*
X219958Y140138D01*
G01X219954Y141024D02*
X219817Y135117D01*
G01X217770Y145353D02*
X217906Y151260D01*
G01X217901Y152147D02*
X217765Y146239D01*
G01X215880Y134231D02*
X216017Y140138D01*
G01X216012Y141024D02*
X215876Y135117D01*
G01X213828Y145353D02*
X213964Y151260D01*
G01X213959Y152147D02*
X213823Y146239D01*
G01X211948Y134231D02*
X212084Y140138D01*
G01X212080Y141024D02*
X211943Y135117D01*
G01X209896Y145353D02*
X210032Y151260D01*
G01X210027Y152147D02*
X209891Y146239D01*
G01X233130Y135984D02*
X233117Y135009D01*
G01X232148Y150393D02*
X232161Y151368D01*
G01X229198Y135984D02*
X229184Y135009D01*
G01X228206Y150393D02*
X228219Y151368D01*
G01X225256Y135984D02*
X225243Y135009D01*
G01X224274Y150393D02*
X224287Y151368D01*
G01X221324Y135984D02*
X221310Y135009D01*
G01X220332Y150393D02*
X220345Y151368D01*
G01X217382Y135984D02*
X217369Y135009D01*
G01X216400Y150393D02*
X216413Y151368D01*
G01X213450Y135984D02*
X213436Y135009D01*
G01X212458Y150393D02*
X212471Y151368D01*
G01X209508Y135984D02*
X209495Y135009D01*
G01X232245Y147618D02*
Y148602D01*
G01Y137775D02*
Y138760D01*
G01X231969D02*
Y137696D01*
G01Y148681D02*
Y147618D01*
G01X231895Y151750D02*
Y150760D01*
G01X231886Y135617D02*
Y134627D01*
G01X231851Y128523D02*
Y123011D01*
G01X231812Y147698D02*
Y152539D01*
G01Y133838D02*
Y138680D01*
G01X231620Y151553D02*
Y152538D01*
G01X231610Y133840D02*
Y134824D01*
G01X231536Y152539D02*
Y133838D01*
G01X231458Y135984D02*
Y129901D01*
G01Y156476D02*
Y150393D01*
G01X231265Y152539D02*
Y151555D01*
G01X231261Y152539D02*
Y151555D01*
G01X231256Y134822D02*
Y133838D01*
G01X231221Y136515D02*
Y132342D01*
G01Y154035D02*
Y149862D01*
G01X230119D02*
Y154035D01*
G01Y132342D02*
Y136515D01*
G01X230084Y134822D02*
Y133838D01*
G01X230080Y134822D02*
Y133838D01*
G01Y152539D02*
Y151555D01*
G01X229883Y135984D02*
Y129901D01*
G01Y156476D02*
Y150393D01*
G01X229804Y133838D02*
Y152539D01*
G01X229725Y134824D02*
Y133840D01*
G01Y152538D02*
Y151553D01*
G01X229529Y151555D02*
Y156396D01*
G01Y129981D02*
Y134822D01*
G01X229450Y150760D02*
Y151750D01*
G01Y134627D02*
Y135617D01*
G01X229371Y130965D02*
Y129901D01*
G01Y156476D02*
Y155412D01*
G01X229095Y130885D02*
Y129901D01*
G01Y156476D02*
Y155492D01*
G01X228702Y128523D02*
Y123011D01*
G01X228308Y155492D02*
Y156476D01*
G01Y130885D02*
Y129901D01*
G01X228032Y130965D02*
Y129901D01*
G01Y156476D02*
Y155412D01*
G01X227954Y135617D02*
Y134627D01*
G01Y151750D02*
Y150760D01*
G01X227875Y151555D02*
Y156396D01*
G01Y129981D02*
Y134822D01*
G01X227678Y151553D02*
Y152538D01*
G01Y133840D02*
Y134824D01*
G01X227599Y152539D02*
Y133838D01*
G01X227521Y135984D02*
Y129901D01*
G01Y156476D02*
Y150393D01*
G01X227324Y134822D02*
Y133838D01*
G01Y152539D02*
Y151555D01*
G01X227319Y152539D02*
Y151555D01*
G01X227284Y136515D02*
Y132342D01*
G01Y154035D02*
Y149862D01*
G01X226182D02*
Y154035D01*
G01Y132342D02*
Y136515D01*
G01X226147Y152539D02*
Y151555D01*
G01X226143Y134822D02*
Y133838D01*
G01X226138Y134822D02*
Y133838D01*
G01X225946Y135984D02*
Y129901D01*
G01Y156476D02*
Y150393D01*
G01X225867Y133838D02*
Y152539D01*
G01X225793Y152538D02*
Y151553D01*
G01X225784Y134824D02*
Y133840D01*
G01X225592Y147698D02*
Y152539D01*
G01Y133838D02*
Y138680D01*
G01X225517Y150760D02*
Y151750D01*
G01X225508Y134627D02*
Y135617D01*
G01X225434Y138760D02*
Y137696D01*
G01Y148681D02*
Y147618D01*
G01X225158D02*
Y148602D01*
G01Y138760D02*
Y137775D01*
G01X224765Y128523D02*
Y123011D01*
G01X224371Y147618D02*
Y148602D01*
G01Y137775D02*
Y138760D01*
G01X224095D02*
Y137696D01*
G01Y148681D02*
Y147618D01*
G01X224021Y151750D02*
Y150760D01*
G01X224012Y135617D02*
Y134627D01*
G01X223938Y147698D02*
Y152539D01*
G01Y133838D02*
Y138680D01*
G01X223746Y151553D02*
Y152538D01*
G01X223736Y133840D02*
Y134824D01*
G01X223662Y152539D02*
Y133838D01*
G01X223584Y135984D02*
Y129901D01*
G01Y156476D02*
Y150393D01*
G01X223391Y152539D02*
Y151555D01*
G01X223387Y152539D02*
Y151555D01*
G01X223382Y134822D02*
Y133838D01*
G01X223347Y136515D02*
Y132342D01*
G01Y154035D02*
Y149862D01*
G01X222245D02*
Y154035D01*
G01Y132342D02*
Y136515D01*
G01X222210Y134822D02*
Y133838D01*
G01X222206Y134822D02*
Y133838D01*
G01Y152539D02*
Y151555D01*
G01X222009Y135984D02*
Y129901D01*
G01Y156476D02*
Y150393D01*
G01X221930Y133838D02*
Y152539D01*
G01X221851Y134824D02*
Y133840D01*
G01Y152538D02*
Y151553D01*
G01X221655Y151555D02*
Y156396D01*
G01Y129981D02*
Y134822D01*
G01X221615Y128523D02*
Y123011D01*
G01X221576Y150760D02*
Y151750D01*
G01Y134627D02*
Y135617D01*
G01X221497Y130965D02*
Y129901D01*
G01Y156476D02*
Y155412D01*
G01X221221Y130885D02*
Y129901D01*
G01Y156476D02*
Y155492D01*
G01X220434D02*
Y156476D01*
G01Y130885D02*
Y129901D01*
G01X220158Y130965D02*
Y129901D01*
G01Y156476D02*
Y155412D01*
G01X220080Y135617D02*
Y134627D01*
G01Y151750D02*
Y150760D01*
G01X220001Y151555D02*
Y156396D01*
G01Y129981D02*
Y134822D01*
G01X219804Y151553D02*
Y152538D01*
G01Y133840D02*
Y134824D01*
G01X219725Y152539D02*
Y133838D01*
G01X219647Y135984D02*
Y129901D01*
G01Y156476D02*
Y150393D01*
G01X219450Y134822D02*
Y133838D01*
G01Y152539D02*
Y151555D01*
G01X219445Y152539D02*
Y151555D01*
G01X219410Y136515D02*
Y132342D01*
G01Y154035D02*
Y149862D01*
G01X218308D02*
Y154035D01*
G01Y132342D02*
Y136515D01*
G01X218273Y152539D02*
Y151555D01*
G01X218269Y134822D02*
Y133838D01*
G01X218264Y134822D02*
Y133838D01*
G01X218072Y135984D02*
Y129901D01*
G01Y156476D02*
Y150393D01*
G01X217993Y133838D02*
Y152539D01*
G01X217919Y152538D02*
Y151553D01*
G01X217910Y134824D02*
Y133840D01*
G01X217717Y147698D02*
Y152539D01*
G01Y133838D02*
Y138680D01*
G01X217643Y150760D02*
Y151750D01*
G01X217634Y134627D02*
Y135617D01*
G01X217560Y138760D02*
Y137696D01*
G01Y148681D02*
Y147618D01*
G01X217284Y138760D02*
Y137775D01*
G01Y148602D02*
Y147618D01*
G01X216497Y138760D02*
Y137775D01*
G01Y148602D02*
Y147618D01*
G01X216221Y138760D02*
Y137696D01*
G01Y148681D02*
Y147618D01*
G01X216147Y151750D02*
Y150760D01*
G01X216138Y135617D02*
Y134627D01*
G01X216064Y147698D02*
Y152539D01*
G01Y133838D02*
Y138680D01*
G01X215872Y151553D02*
Y152538D01*
G01X215862Y133840D02*
Y134824D01*
G01X215788Y152539D02*
Y133838D01*
G01X215710Y135984D02*
Y129901D01*
G01Y156476D02*
Y150393D01*
G01X215517Y152539D02*
Y151555D01*
G01X215513Y152539D02*
Y151555D01*
G01X215508Y134822D02*
Y133838D01*
G01X215473Y136515D02*
Y132342D01*
G01Y154035D02*
Y149862D01*
G01X214371D02*
Y154035D01*
G01Y132342D02*
Y136515D01*
G01X214336Y134822D02*
Y133838D01*
G01X214332Y134822D02*
Y133838D01*
G01Y152539D02*
Y151555D01*
G01X214135Y135984D02*
Y129901D01*
G01Y156476D02*
Y150393D01*
G01X214056Y133838D02*
Y152539D01*
G01X213977Y134824D02*
Y133840D01*
G01Y152538D02*
Y151553D01*
G01X213780Y151555D02*
Y156396D01*
G01Y129981D02*
Y134822D01*
G01X213702Y150760D02*
Y151750D01*
G01Y134627D02*
Y135617D01*
G01X213623Y130965D02*
Y129901D01*
G01Y156476D02*
Y155412D01*
G01X213347Y130885D02*
Y129901D01*
G01Y156476D02*
Y155492D01*
G01X212560D02*
Y156476D01*
G01Y130885D02*
Y129901D01*
G01X212284Y130965D02*
Y129901D01*
G01Y156476D02*
Y155412D01*
G01X212206Y135617D02*
Y134627D01*
G01Y151750D02*
Y150760D01*
G01X212127Y151555D02*
Y156396D01*
G01Y129981D02*
Y134822D01*
G01X211930Y151553D02*
Y152538D01*
G01Y133840D02*
Y134824D01*
G01X211851Y152539D02*
Y133838D01*
G01X211773Y135984D02*
Y129901D01*
G01Y156476D02*
Y150393D01*
G01X211576Y134822D02*
Y133838D01*
G01Y152539D02*
Y151555D01*
G01X211571Y152539D02*
Y151555D01*
G01X211536Y136515D02*
Y132342D01*
G01Y154035D02*
Y149862D01*
G01X210434D02*
Y154035D01*
G01Y132342D02*
Y136515D01*
G01X210399Y152539D02*
Y151555D01*
G01X210395Y134822D02*
Y133838D01*
G01X210390Y134822D02*
Y133838D01*
G01X210198Y135984D02*
Y129901D01*
G01Y156476D02*
Y150393D01*
G01X210119Y133838D02*
Y152539D01*
G01X210045Y152538D02*
Y151553D01*
G01X210036Y134824D02*
Y133840D01*
G01X209843Y147698D02*
Y152539D01*
G01Y133838D02*
Y138680D01*
G01X209769Y150760D02*
Y151750D01*
G01X209760Y134627D02*
Y135617D01*
G01X209686Y138760D02*
Y137696D01*
G01Y148681D02*
Y147618D01*
G01X209410Y138760D02*
Y137775D01*
G01Y148602D02*
Y147618D01*
G01X208623Y138760D02*
Y137775D01*
G01Y148602D02*
Y147618D01*
G01X208347Y138760D02*
Y137696D01*
G01Y148681D02*
Y147618D01*
G01X208273Y151750D02*
Y150760D01*
G01X208264Y135617D02*
Y134627D01*
G01X229184Y151368D02*
X229198Y150393D01*
G01X228219Y135009D02*
X228206Y135984D01*
G01X225252Y151368D02*
X225265Y150393D01*
G01X224277Y135009D02*
X224264Y135984D01*
G01X221310Y151368D02*
X221324Y150393D01*
G01X220345Y135009D02*
X220332Y135984D01*
G01X217378Y151368D02*
X217391Y150393D01*
G01X216403Y135009D02*
X216390Y135984D01*
G01X213436Y151368D02*
X213450Y150393D01*
G01X212471Y135009D02*
X212458Y135984D01*
G01X209504Y151368D02*
X209517Y150393D01*
G01X208529Y135009D02*
X208516Y135984D01*
G01X229712Y135117D02*
X229576Y141024D01*
G01X229571Y140138D02*
X229707Y134231D01*
G01X227832Y146239D02*
X227696Y152147D01*
G01X227691Y151260D02*
X227828Y145353D01*
G01X225770Y135117D02*
X225634Y141024D01*
G01X225629Y140138D02*
X225766Y134231D01*
G01X223900Y146239D02*
X223764Y152147D01*
G01X223759Y151260D02*
X223895Y145353D01*
G01X221838Y135117D02*
X221702Y141024D01*
G01X221697Y140138D02*
X221833Y134231D01*
G01X219958Y146239D02*
X219822Y152147D01*
G01X219817Y151260D02*
X219954Y145353D01*
G01X217896Y135117D02*
X217760Y141024D01*
G01X217755Y140138D02*
X217892Y134231D01*
G01X216026Y146239D02*
X215890Y152147D01*
G01X215885Y151260D02*
X216021Y145353D01*
G01X213964Y135117D02*
X213828Y141024D01*
G01X213823Y140138D02*
X213959Y134231D01*
G01X212084Y146239D02*
X211948Y152147D01*
G01X211943Y151260D02*
X212080Y145353D01*
G01X210022Y135117D02*
X209886Y141024D01*
G01X209881Y140138D02*
X210018Y134231D01*
G01X208152Y146239D02*
X208016Y152147D01*
G01X208011Y151260D02*
X208147Y145353D01*
G01X227907Y140340D02*
X227856Y141327D01*
G01X227854Y140365D02*
X227904Y139379D01*
G01X225617Y146012D02*
X225567Y146999D01*
G01X225565Y146037D02*
X225615Y145050D01*
G01X223965Y140340D02*
X223914Y141327D01*
G01X223912Y140365D02*
X223962Y139379D01*
G01X221676Y146012D02*
X221625Y146999D01*
G01X221623Y146037D02*
X221673Y145050D01*
G01X220032Y140340D02*
X219982Y141327D01*
G01X219980Y140365D02*
X220030Y139379D01*
G01X217743Y146012D02*
X217693Y146999D01*
G01X217691Y146037D02*
X217741Y145050D01*
G01X216091Y140340D02*
X216040Y141327D01*
G01X216038Y140365D02*
X216088Y139379D01*
G01X213802Y146012D02*
X213751Y146999D01*
G01X213749Y146037D02*
X213799Y145050D01*
G01X212158Y140340D02*
X212108Y141327D01*
G01X212106Y140365D02*
X212156Y139379D01*
G01X209869Y146012D02*
X209819Y146999D01*
G01X209817Y146037D02*
X209867Y145050D01*
G01X208217Y140340D02*
X208166Y141327D01*
G01X208164Y140365D02*
X208214Y139379D01*
G01X205928Y146012D02*
X205877Y146999D01*
G01X205875Y146037D02*
X205925Y145050D01*
G01X193792Y135937D02*
X193783Y135984D01*
G01X188813Y150393D02*
X188803Y150441D01*
G01X189850Y135984D02*
X189860Y135937D01*
G01X216150Y134640D02*
X216403Y135009D01*
G01X216136Y135615D02*
X216358Y135937D01*
G01X225519Y150762D02*
X225298Y150441D01*
G01X225506Y151737D02*
X225252Y151368D01*
G01X212217Y134640D02*
X212471Y135009D01*
G01X212204Y135615D02*
X212425Y135937D01*
G01X221577Y150762D02*
X221356Y150441D01*
G01X221564Y151737D02*
X221310Y151368D01*
G01X208276Y134640D02*
X208529Y135009D01*
G01X208262Y135615D02*
X208484Y135937D01*
G01X217645Y150762D02*
X217424Y150441D01*
G01X217632Y151737D02*
X217378Y151368D01*
G01X204343Y134640D02*
X204597Y135009D01*
G01X204330Y135615D02*
X204551Y135937D01*
G01X213703Y150762D02*
X213482Y150441D01*
G01X213690Y151737D02*
X213436Y151368D01*
G01X200402Y134640D02*
X200655Y135009D01*
G01X200388Y135615D02*
X200610Y135937D01*
G01X209771Y150762D02*
X209550Y150441D01*
G01X209758Y151737D02*
X209504Y151368D01*
G01X196469Y134640D02*
X196723Y135009D01*
G01X196456Y135615D02*
X196677Y135937D01*
G01X205829Y150762D02*
X205608Y150441D01*
G01X205816Y151737D02*
X205562Y151368D01*
G01X192528Y134640D02*
X192781Y135009D01*
G01X192514Y135615D02*
X192736Y135937D01*
G01X201897Y150762D02*
X201676Y150441D01*
G01X201884Y151737D02*
X201630Y151368D01*
G01X188595Y134640D02*
X188849Y135009D01*
G01X188803Y135937D02*
X188584Y135617D01*
G01X217414Y150393D02*
X217424Y150441D01*
G01X212435Y135984D02*
X212425Y135937D01*
G01X213472Y150393D02*
X213482Y150441D01*
G01X208493Y135984D02*
X208484Y135937D01*
G01X209540Y150393D02*
X209550Y150441D01*
G01X204561Y135984D02*
X204551Y135937D01*
G01X205598Y150393D02*
X205608Y150441D01*
G01X200619Y135984D02*
X200610Y135937D01*
G01X201666Y150393D02*
X201676Y150441D01*
G01X196687Y135984D02*
X196677Y135937D01*
G01X197724Y150393D02*
X197734Y150441D01*
G01X192745Y135984D02*
X192736Y135937D01*
G01X209810Y139379D02*
X209860Y140365D01*
G01X209858Y141327D02*
X209807Y140340D01*
G01X208176Y145050D02*
X208226Y146037D01*
G01X208224Y146999D02*
X208173Y146012D01*
G01X205877Y139379D02*
X205928Y140365D01*
G01X205925Y141327D02*
X205875Y140340D01*
G01X204234Y145050D02*
X204284Y146037D01*
G01X204282Y146999D02*
X204232Y146012D01*
G01X201936Y139379D02*
X201986Y140365D01*
G01X201984Y141327D02*
X201933Y140340D01*
G01X200302Y145050D02*
X200352Y146037D01*
G01X200350Y146999D02*
X200299Y146012D01*
G01X198003Y139379D02*
X198054Y140365D01*
G01X198051Y141327D02*
X198001Y140340D01*
G01X196360Y145050D02*
X196410Y146037D01*
G01X196408Y146999D02*
X196358Y146012D01*
G01X194062Y139379D02*
X194112Y140365D01*
G01X194110Y141327D02*
X194059Y140340D01*
G01X192428Y145050D02*
X192478Y146037D01*
G01X192476Y146999D02*
X192425Y146012D01*
G01X190129Y139379D02*
X190180Y140365D01*
G01X190177Y141327D02*
X190127Y140340D01*
G01X188486Y145050D02*
X188536Y146037D01*
G01X188534Y146999D02*
X188484Y146012D01*
G01X208006Y134231D02*
X208143Y140138D01*
G01X208138Y141024D02*
X208002Y135117D01*
G01X205954Y145353D02*
X206090Y151260D01*
G01X206085Y152147D02*
X205949Y146239D01*
G01X204074Y134231D02*
X204210Y140138D01*
G01X204206Y141024D02*
X204069Y135117D01*
G01X202022Y145353D02*
X202158Y151260D01*
G01X202153Y152147D02*
X202017Y146239D01*
G01X200132Y134231D02*
X200269Y140138D01*
G01X200264Y141024D02*
X200128Y135117D01*
G01X198080Y145353D02*
X198216Y151260D01*
G01X198211Y152147D02*
X198075Y146239D01*
G01X196200Y134231D02*
X196336Y140138D01*
G01X196331Y141024D02*
X196195Y135117D01*
G01X194148Y145353D02*
X194284Y151260D01*
G01X194279Y152147D02*
X194143Y146239D01*
G01X192258Y134231D02*
X192395Y140138D01*
G01X192390Y141024D02*
X192254Y135117D01*
G01X190206Y145353D02*
X190342Y151260D01*
G01X190337Y152147D02*
X190201Y146239D01*
G01X188326Y134231D02*
X188462Y140138D01*
G01X188457Y141024D02*
X188321Y135117D01*
G01X208526Y150393D02*
X208539Y151368D01*
G01X205576Y135984D02*
X205562Y135009D01*
G01X204584Y150393D02*
X204597Y151368D01*
G01X201634Y135984D02*
X201621Y135009D01*
G01X200652Y150393D02*
X200665Y151368D01*
G01X197701Y135984D02*
X197688Y135009D01*
G01X196710Y150393D02*
X196723Y151368D01*
G01X193760Y135984D02*
X193747Y135009D01*
G01X192778Y150393D02*
X192791Y151368D01*
G01X189827Y135984D02*
X189814Y135009D01*
G01X188836Y150393D02*
X188849Y151368D01*
G01X208229Y128523D02*
Y123011D01*
G01X208190Y147698D02*
Y152539D01*
G01Y133838D02*
Y138680D01*
G01X207998Y151553D02*
Y152538D01*
G01X207988Y133840D02*
Y134824D01*
G01X207914Y152539D02*
Y133838D01*
G01X207836Y135984D02*
Y129901D01*
G01Y156476D02*
Y150393D01*
G01X207643Y152539D02*
Y151555D01*
G01X207639Y152539D02*
Y151555D01*
G01X207634Y134822D02*
Y133838D01*
G01X207599Y136515D02*
Y132342D01*
G01Y154035D02*
Y149862D01*
G01X206497D02*
Y154035D01*
G01Y132342D02*
Y136515D01*
G01X206462Y134822D02*
Y133838D01*
G01X206458Y134822D02*
Y133838D01*
G01Y152539D02*
Y151555D01*
G01X206261Y135984D02*
Y129901D01*
G01Y156476D02*
Y150393D01*
G01X206182Y133838D02*
Y152539D01*
G01X206103Y134824D02*
Y133840D01*
G01Y152538D02*
Y151553D01*
G01X205906Y151555D02*
Y156396D01*
G01Y129981D02*
Y134822D01*
G01X205828Y150760D02*
Y151750D01*
G01Y134627D02*
Y135617D01*
G01X205749Y130965D02*
Y129901D01*
G01Y156476D02*
Y155412D01*
G01X205473Y130885D02*
Y129901D01*
G01Y156476D02*
Y155492D01*
G01X205080Y128523D02*
Y123011D01*
G01X204686Y155492D02*
Y156476D01*
G01Y130885D02*
Y129901D01*
G01X204410Y130965D02*
Y129901D01*
G01Y156476D02*
Y155412D01*
G01X204332Y135617D02*
Y134627D01*
G01Y151750D02*
Y150760D01*
G01X204253Y151555D02*
Y156396D01*
G01Y129981D02*
Y134822D01*
G01X204056Y133840D02*
Y134824D01*
G01Y151553D02*
Y152538D01*
G01X203977Y152539D02*
Y133838D01*
G01X203899Y135984D02*
Y129901D01*
G01Y156476D02*
Y150393D01*
G01X203702Y134822D02*
Y133838D01*
G01Y152539D02*
Y151555D01*
G01X203697Y152539D02*
Y151555D01*
G01X203662Y136515D02*
Y132342D01*
G01Y154035D02*
Y149862D01*
G01X202560D02*
Y154035D01*
G01Y132342D02*
Y136515D01*
G01X202525Y152539D02*
Y151555D01*
G01X202521Y134822D02*
Y133838D01*
G01X202516Y134822D02*
Y133838D01*
G01X202324Y135984D02*
Y129901D01*
G01Y156476D02*
Y150393D01*
G01X202245Y133838D02*
Y152539D01*
G01X202171Y152538D02*
Y151553D01*
G01X202162Y134824D02*
Y133840D01*
G01X201969Y147698D02*
Y152539D01*
G01Y133838D02*
Y138680D01*
G01X201895Y150760D02*
Y151750D01*
G01X201886Y134627D02*
Y135617D01*
G01X201812Y138760D02*
Y137696D01*
G01Y148681D02*
Y147618D01*
G01X201536D02*
Y148602D01*
G01Y138760D02*
Y137775D01*
G01X201143Y128523D02*
Y123011D01*
G01X200749Y147618D02*
Y148602D01*
G01Y137775D02*
Y138760D01*
G01X200473D02*
Y137696D01*
G01Y148681D02*
Y147618D01*
G01X200399Y151750D02*
Y150760D01*
G01X200390Y135617D02*
Y134627D01*
G01X200316Y147698D02*
Y152539D01*
G01Y133838D02*
Y138680D01*
G01X200124Y151553D02*
Y152538D01*
G01X200114Y133840D02*
Y134824D01*
G01X200040Y152539D02*
Y133838D01*
G01X199962Y135984D02*
Y129901D01*
G01Y156476D02*
Y150393D01*
G01X199769Y152539D02*
Y151555D01*
G01X199765Y152539D02*
Y151555D01*
G01X199760Y134822D02*
Y133838D01*
G01X199725Y136515D02*
Y132342D01*
G01Y154035D02*
Y149862D01*
G01X198623D02*
Y154035D01*
G01Y132342D02*
Y136515D01*
G01X198588Y134822D02*
Y133838D01*
G01X198584Y134822D02*
Y133838D01*
G01Y152539D02*
Y151555D01*
G01X198387Y135984D02*
Y129901D01*
G01Y156476D02*
Y150393D01*
G01X198308Y133838D02*
Y152539D01*
G01X198229Y134824D02*
Y133840D01*
G01Y152538D02*
Y151553D01*
G01X198032Y151555D02*
Y156396D01*
G01Y129981D02*
Y134822D01*
G01X197993Y128523D02*
Y123011D01*
G01X197954Y150760D02*
Y151750D01*
G01Y134627D02*
Y135617D01*
G01X197875Y130965D02*
Y129901D01*
G01Y156476D02*
Y155412D01*
G01X197599Y130885D02*
Y129901D01*
G01Y156476D02*
Y155492D01*
G01X196812D02*
Y156476D01*
G01Y130885D02*
Y129901D01*
G01X196536Y130965D02*
Y129901D01*
G01Y156476D02*
Y155412D01*
G01X196458Y135617D02*
Y134627D01*
G01Y151750D02*
Y150760D01*
G01X196379Y151555D02*
Y156396D01*
G01Y129981D02*
Y134822D01*
G01X196182Y151553D02*
Y152538D01*
G01Y133840D02*
Y134824D01*
G01X196103Y152539D02*
Y133838D01*
G01X196025Y135984D02*
Y129901D01*
G01Y156476D02*
Y150393D01*
G01X195828Y134822D02*
Y133838D01*
G01Y152539D02*
Y151555D01*
G01X195823Y152539D02*
Y151555D01*
G01X195788Y136515D02*
Y132342D01*
G01Y154035D02*
Y149862D01*
G01X194686D02*
Y154035D01*
G01Y132342D02*
Y136515D01*
G01X194651Y152539D02*
Y151555D01*
G01X194647Y134822D02*
Y133838D01*
G01X194642Y134822D02*
Y133838D01*
G01X194450Y135984D02*
Y129901D01*
G01Y156476D02*
Y150393D01*
G01X194371Y133838D02*
Y152539D01*
G01X194297Y152538D02*
Y151553D01*
G01X194288Y134824D02*
Y133840D01*
G01X194095Y147698D02*
Y152539D01*
G01Y133838D02*
Y138680D01*
G01X194021Y150760D02*
Y151750D01*
G01X194012Y134627D02*
Y135617D01*
G01X193938Y138760D02*
Y137696D01*
G01Y148681D02*
Y147618D01*
G01X193662D02*
Y148602D01*
G01Y138760D02*
Y137775D01*
G01X192875Y147618D02*
Y148602D01*
G01Y137775D02*
Y138760D01*
G01X192599D02*
Y137696D01*
G01Y148681D02*
Y147618D01*
G01X192525Y151750D02*
Y150760D01*
G01X192516Y135617D02*
Y134627D01*
G01X192442Y147698D02*
Y152539D01*
G01Y133838D02*
Y138680D01*
G01X192250Y151553D02*
Y152538D01*
G01X192240Y133840D02*
Y134824D01*
G01X192166Y152539D02*
Y133838D01*
G01X192088Y135984D02*
Y129901D01*
G01Y156476D02*
Y150393D01*
G01X191895Y152539D02*
Y151555D01*
G01X191891Y152539D02*
Y151555D01*
G01X191886Y134822D02*
Y133838D01*
G01X191851Y136515D02*
Y132342D01*
G01Y154035D02*
Y149862D01*
G01X190749D02*
Y154035D01*
G01Y132342D02*
Y136515D01*
G01X190714Y134822D02*
Y133838D01*
G01X190710Y134822D02*
Y133838D01*
G01Y152539D02*
Y151555D01*
G01X190513Y135984D02*
Y129901D01*
G01Y156476D02*
Y150393D01*
G01X190434Y133838D02*
Y152539D01*
G01X190355Y134824D02*
Y133840D01*
G01Y152538D02*
Y151553D01*
G01X190158Y151555D02*
Y156396D01*
G01Y129981D02*
Y134822D01*
G01X190080Y150760D02*
Y151750D01*
G01Y134627D02*
Y135617D01*
G01X190001Y130965D02*
Y129901D01*
G01Y156476D02*
Y155412D01*
G01X189725Y129901D02*
Y130885D01*
G01Y156476D02*
Y155492D01*
G01X188938Y130885D02*
Y129901D01*
G01Y156476D02*
Y155492D01*
G01X188662Y130965D02*
Y129901D01*
G01Y156476D02*
Y155412D01*
G01X188584Y135617D02*
Y134627D01*
G01Y151750D02*
Y150760D01*
G01X188505Y151555D02*
Y156396D01*
G01Y129981D02*
Y134822D01*
G01X188308Y151553D02*
Y152538D01*
G01Y133840D02*
Y134824D01*
G01X188229Y152539D02*
Y133838D01*
G01X188151Y135984D02*
Y129901D01*
G01Y156476D02*
Y150393D01*
G01X187954Y134822D02*
Y133838D01*
G01Y152539D02*
Y151555D01*
G01X187949Y152539D02*
Y151555D01*
G01X187914Y136515D02*
Y132342D01*
G01Y154035D02*
Y149862D01*
G01X186812D02*
Y154035D01*
G01Y132342D02*
Y136515D01*
G01X205562Y151368D02*
X205576Y150393D01*
G01X204597Y135009D02*
X204584Y135984D01*
G01X201630Y151368D02*
X201643Y150393D01*
G01X200655Y135009D02*
X200642Y135984D01*
G01X197688Y151368D02*
X197701Y150393D01*
G01X196723Y135009D02*
X196710Y135984D01*
G01X193756Y151368D02*
X193769Y150393D01*
G01X192781Y135009D02*
X192768Y135984D01*
G01X189814Y151368D02*
X189827Y150393D01*
G01X188849Y135009D02*
X188836Y135984D01*
G01X206090Y135117D02*
X205954Y141024D01*
G01X205949Y140138D02*
X206085Y134231D01*
G01X204210Y146239D02*
X204074Y152147D01*
G01X204069Y151260D02*
X204206Y145353D01*
G01X202148Y135117D02*
X202012Y141024D01*
G01X202007Y140138D02*
X202144Y134231D01*
G01X200278Y146239D02*
X200142Y152147D01*
G01X200137Y151260D02*
X200273Y145353D01*
G01X198216Y135117D02*
X198080Y141024D01*
G01X198075Y140138D02*
X198211Y134231D01*
G01X196336Y146239D02*
X196200Y152147D01*
G01X196195Y151260D02*
X196331Y145353D01*
G01X194274Y135117D02*
X194138Y141024D01*
G01X194133Y140138D02*
X194270Y134231D01*
G01X192404Y146239D02*
X192268Y152147D01*
G01X192263Y151260D02*
X192399Y145353D01*
G01X190342Y135117D02*
X190206Y141024D01*
G01X190201Y140138D02*
X190337Y134231D01*
G01X188462Y146239D02*
X188326Y152147D01*
G01X188321Y151260D02*
X188457Y145353D01*
G01X204284Y140340D02*
X204234Y141327D01*
G01X204232Y140365D02*
X204282Y139379D01*
G01X201995Y146012D02*
X201945Y146999D01*
G01X201943Y146037D02*
X201993Y145050D01*
G01X200343Y140340D02*
X200292Y141327D01*
G01X200290Y140365D02*
X200340Y139379D01*
G01X198054Y146012D02*
X198003Y146999D01*
G01X198001Y146037D02*
X198051Y145050D01*
G01X196410Y140340D02*
X196360Y141327D01*
G01X196358Y140365D02*
X196408Y139379D01*
G01X194121Y146012D02*
X194071Y146999D01*
G01X194069Y146037D02*
X194119Y145050D01*
G01X192469Y140340D02*
X192418Y141327D01*
G01X192416Y140365D02*
X192466Y139379D01*
G01X190180Y146012D02*
X190129Y146999D01*
G01X190127Y146037D02*
X190177Y145050D01*
G01X188536Y140340D02*
X188486Y141327D01*
G01X188484Y140365D02*
X188534Y139379D01*
G01X197955Y150762D02*
X197734Y150441D01*
G01X197942Y151737D02*
X197688Y151368D01*
G01X194023Y150762D02*
X193802Y150441D01*
G01X194010Y151737D02*
X193756Y151368D01*
G01X189860Y150441D02*
X190080Y150760D01*
G01X190068Y151737D02*
X189814Y151368D01*
G01X193792Y150393D02*
X193802Y150441D01*
G01X188803Y135937D02*
X188813Y135984D01*
G01X189860Y150441D02*
X189850Y150393D01*
G01X264998Y225965D02*
X265009Y226239D01*
G01X264993Y225948D02*
X264998Y225965D01*
G01X264988Y226012D02*
X264993Y225948D01*
G01X265000Y224988D02*
X265014Y225353D01*
G01X264992Y224965D02*
X265000Y224988D01*
G01X264985Y225050D02*
X264992Y224965D01*
G01X264921Y226524D02*
X264935Y226037D01*
G01X264915Y226913D02*
X264921Y226524D01*
G01X264910Y227384D02*
X264915Y226913D01*
G01X264906Y227925D02*
X264910Y227384D01*
G01X264903Y228520D02*
X264906Y227925D01*
G01X264901Y229153D02*
X264903Y228520D01*
G01X264900Y229807D02*
X264901Y229153D01*
G01X264895Y231677D02*
X264888Y231750D01*
G01X264899Y231547D02*
X264895Y231677D01*
G01X264902Y231359D02*
X264899Y231547D01*
G01X264905Y231120D02*
X264902Y231359D01*
G01X264908Y230838D02*
X264905Y231120D01*
G01X264910Y230521D02*
X264908Y230838D01*
G01X264911Y230180D02*
X264910Y230521D01*
G01X264911Y229826D02*
Y230180D01*
G01X264927Y227364D02*
X264937Y226999D01*
G01X264922Y227656D02*
X264927Y227364D01*
G01X264919Y228009D02*
X264922Y227656D01*
G01X264916Y228414D02*
X264919Y228009D01*
G01X264913Y228861D02*
X264916Y228414D01*
G01X264912Y229336D02*
X264913Y228861D01*
G01X264911Y229826D02*
X264912Y229336D01*
G01X263281Y225965D02*
X263291Y226012D01*
G01X263275Y226063D02*
X263281Y225965D01*
G01X263270Y226239D02*
X263275Y226063D01*
G01X263366Y228861D02*
X263368Y229826D01*
G01X263363Y228414D02*
X263366Y228861D01*
G01X263360Y228009D02*
X263363Y228414D01*
G01X263357Y227656D02*
X263360Y228009D01*
G01X263352Y227364D02*
X263357Y227656D01*
G01X263347Y227143D02*
X263352Y227364D01*
G01X263342Y226999D02*
X263347Y227143D01*
G01X263369Y230521D02*
X263368Y229826D01*
G01X263371Y230838D02*
X263369Y230521D01*
G01X263374Y231120D02*
X263371Y230838D01*
G01X263377Y231359D02*
X263374Y231120D01*
G01X263380Y231547D02*
X263377Y231359D01*
G01X263384Y231677D02*
X263380Y231547D01*
G01X263387Y231746D02*
X263384Y231677D01*
G01X263391Y231750D02*
X263387Y231746D01*
G01X263376Y228520D02*
X263379Y229807D01*
G01X263373Y227925D02*
X263376Y228520D01*
G01X263369Y227384D02*
X263373Y227925D01*
G01X263364Y226913D02*
X263369Y227384D01*
G01X263358Y226524D02*
X263364Y226913D01*
G01X263351Y226230D02*
X263358Y226524D01*
G01X263344Y226037D02*
X263351Y226230D01*
G01X263279Y224988D02*
X263294Y225050D01*
G01X263272Y225118D02*
X263279Y224988D01*
G01X263265Y225353D02*
X263272Y225118D01*
G01X263271Y220412D02*
X263261Y220138D01*
G01X263277Y220429D02*
X263271Y220412D01*
G01X263282Y220365D02*
X263277Y220429D01*
G01X263270Y221390D02*
X263256Y221024D01*
G01X263277Y221412D02*
X263270Y221390D01*
G01X263284Y221327D02*
X263277Y221412D01*
G01X263348Y219853D02*
X263335Y220340D01*
G01X263354Y219464D02*
X263348Y219853D01*
G01X263359Y218993D02*
X263354Y219464D01*
G01X263364Y218453D02*
X263359Y218993D01*
G01X263367Y217857D02*
X263364Y218453D01*
G01X263369Y217224D02*
X263367Y217857D01*
G01X263369Y216570D02*
Y217224D01*
G01X263374Y214700D02*
X263382Y214627D01*
G01X263371Y214830D02*
X263374Y214700D01*
G01X263367Y215018D02*
X263371Y214830D01*
G01X263364Y215257D02*
X263367Y215018D01*
G01X263362Y215540D02*
X263364Y215257D01*
G01X263360Y215857D02*
X263362Y215540D01*
G01X263359Y216198D02*
X263360Y215857D01*
G01X263358Y216551D02*
X263359Y216198D01*
G01X263343Y219013D02*
X263333Y219379D01*
G01X263347Y218722D02*
X263343Y219013D01*
G01X263351Y218368D02*
X263347Y218722D01*
G01X263354Y217963D02*
X263351Y218368D01*
G01X263356Y217516D02*
X263354Y217963D01*
G01X263358Y217041D02*
X263356Y217516D01*
G01X263358Y216551D02*
Y217041D01*
G01X264989Y220412D02*
X264978Y220365D01*
G01X264994Y220314D02*
X264989Y220412D01*
G01X265000Y220138D02*
X264994Y220314D01*
G01X264904Y217516D02*
X264902Y216551D01*
G01X264906Y217963D02*
X264904Y217516D01*
G01X264909Y218368D02*
X264906Y217963D01*
G01X264913Y218722D02*
X264909Y218368D01*
G01X264918Y219013D02*
X264913Y218722D01*
G01X264922Y219234D02*
X264918Y219013D01*
G01X264928Y219379D02*
X264922Y219234D01*
G01X264900Y215857D02*
X264902Y216551D01*
G01X264898Y215540D02*
X264900Y215857D01*
G01X264896Y215257D02*
X264898Y215540D01*
G01X264893Y215018D02*
X264896Y215257D01*
G01X264890Y214830D02*
X264893Y215018D01*
G01X264886Y214700D02*
X264890Y214830D01*
G01X264882Y214632D02*
X264886Y214700D01*
G01X264878Y214627D02*
X264882Y214632D01*
G01X264894Y217857D02*
X264891Y216570D01*
G01X264897Y218453D02*
X264894Y217857D01*
G01X264901Y218993D02*
X264897Y218453D01*
G01X264906Y219464D02*
X264901Y218993D01*
G01X264912Y219853D02*
X264906Y219464D01*
G01X264918Y220148D02*
X264912Y219853D01*
G01X264925Y220340D02*
X264918Y220148D01*
G01X264990Y221390D02*
X264976Y221327D01*
G01X264998Y221259D02*
X264990Y221390D01*
G01X265004Y221024D02*
X264998Y221259D01*
G01X259339Y225965D02*
X259350Y226012D01*
G01X259334Y226063D02*
X259339Y225965D01*
G01X259328Y226239D02*
X259334Y226063D01*
G01X259424Y228861D02*
X259426Y229826D01*
G01X259422Y228414D02*
X259424Y228861D01*
G01X259419Y228009D02*
X259422Y228414D01*
G01X259415Y227656D02*
X259419Y228009D01*
G01X259410Y227364D02*
X259415Y227656D01*
G01X259405Y227143D02*
X259410Y227364D01*
G01X259400Y226999D02*
X259405Y227143D01*
G01X259434Y228520D02*
X259437Y229807D01*
G01X259431Y227925D02*
X259434Y228520D01*
G01X259427Y227384D02*
X259431Y227925D01*
G01X259422Y226913D02*
X259427Y227384D01*
G01X259416Y226524D02*
X259422Y226913D01*
G01X259410Y226230D02*
X259416Y226524D01*
G01X259403Y226037D02*
X259410Y226230D01*
G01X259338Y224988D02*
X259352Y225050D01*
G01X259330Y225118D02*
X259338Y224988D01*
G01X259324Y225353D02*
X259330Y225118D01*
G01X261058Y224988D02*
X261072Y225353D01*
G01X261051Y224965D02*
X261058Y224988D01*
G01X261044Y225050D02*
X261051Y224965D01*
G01X260980Y226524D02*
X260993Y226037D01*
G01X260974Y226913D02*
X260980Y226524D01*
G01X260969Y227384D02*
X260974Y226913D01*
G01X260964Y227925D02*
X260969Y227384D01*
G01X260961Y228520D02*
X260964Y227925D01*
G01X260959Y229153D02*
X260961Y228520D01*
G01X260959Y229807D02*
Y229153D01*
G01X260985Y227364D02*
X260995Y226999D01*
G01X260981Y227656D02*
X260985Y227364D01*
G01X260977Y228009D02*
X260981Y227656D01*
G01X260974Y228414D02*
X260977Y228009D01*
G01X260972Y228861D02*
X260974Y228414D01*
G01X260970Y229336D02*
X260972Y228861D01*
G01X260969Y229826D02*
X260970Y229336D01*
G01X261057Y225965D02*
X261067Y226239D01*
G01X261051Y225948D02*
X261057Y225965D01*
G01X261046Y226012D02*
X261051Y225948D01*
G01X261057Y220412D02*
X261046Y220365D01*
G01X261062Y220314D02*
X261057Y220412D01*
G01X261067Y220138D02*
X261062Y220314D01*
G01X260972Y217516D02*
X260969Y216551D01*
G01X260974Y217963D02*
X260972Y217516D01*
G01X260977Y218368D02*
X260974Y217963D01*
G01X260981Y218722D02*
X260977Y218368D01*
G01X260985Y219013D02*
X260981Y218722D01*
G01X260990Y219234D02*
X260985Y219013D01*
G01X260995Y219379D02*
X260990Y219234D01*
G01X260961Y217857D02*
X260959Y216570D01*
G01X260964Y218453D02*
X260961Y217857D01*
G01X260969Y218993D02*
X260964Y218453D01*
G01X260974Y219464D02*
X260969Y218993D01*
G01X260980Y219853D02*
X260974Y219464D01*
G01X260986Y220148D02*
X260980Y219853D01*
G01X260993Y220340D02*
X260986Y220148D01*
G01X261058Y221390D02*
X261044Y221327D01*
G01X261065Y221259D02*
X261058Y221390D01*
G01X261072Y221024D02*
X261065Y221259D01*
G01X259338Y221390D02*
X259324Y221024D01*
G01X259345Y221412D02*
X259338Y221390D01*
G01X259352Y221327D02*
X259345Y221412D01*
G01X259416Y219853D02*
X259403Y220340D01*
G01X259422Y219464D02*
X259416Y219853D01*
G01X259427Y218993D02*
X259422Y219464D01*
G01X259431Y218453D02*
X259427Y218993D01*
G01X259434Y217857D02*
X259431Y218453D01*
G01X259436Y217224D02*
X259434Y217857D01*
G01X259437Y216570D02*
X259436Y217224D01*
G01X259410Y219013D02*
X259400Y219379D01*
G01X259415Y218722D02*
X259410Y219013D01*
G01X259419Y218368D02*
X259415Y218722D01*
G01X259422Y217963D02*
X259419Y218368D01*
G01X259424Y217516D02*
X259422Y217963D01*
G01X259426Y217041D02*
X259424Y217516D01*
G01X259426Y216551D02*
Y217041D01*
G01X259339Y220412D02*
X259328Y220138D01*
G01X259344Y220429D02*
X259339Y220412D01*
G01X259350Y220365D02*
X259344Y220429D01*
G01X255407Y225965D02*
X255417Y226012D01*
G01X255401Y226063D02*
X255407Y225965D01*
G01X255396Y226239D02*
X255401Y226063D01*
G01X255492Y228861D02*
X255494Y229826D01*
G01X255489Y228414D02*
X255492Y228861D01*
G01X255486Y228009D02*
X255489Y228414D01*
G01X255482Y227656D02*
X255486Y228009D01*
G01X255478Y227364D02*
X255482Y227656D01*
G01X255473Y227143D02*
X255478Y227364D01*
G01X255468Y226999D02*
X255473Y227143D01*
G01X255495Y230521D02*
X255494Y229826D01*
G01X255497Y230838D02*
X255495Y230521D01*
G01X255500Y231120D02*
X255497Y230838D01*
G01X255503Y231359D02*
X255500Y231120D01*
G01X255506Y231547D02*
X255503Y231359D01*
G01X255510Y231677D02*
X255506Y231547D01*
G01X255513Y231746D02*
X255510Y231677D01*
G01X255517Y231750D02*
X255513Y231746D01*
G01X255502Y228520D02*
X255505Y229807D01*
G01X255499Y227925D02*
X255502Y228520D01*
G01X255495Y227384D02*
X255499Y227925D01*
G01X255490Y226913D02*
X255495Y227384D01*
G01X255484Y226524D02*
X255490Y226913D01*
G01X255477Y226230D02*
X255484Y226524D01*
G01X255470Y226037D02*
X255477Y226230D01*
G01X255405Y224988D02*
X255420Y225050D01*
G01X255398Y225118D02*
X255405Y224988D01*
G01X255391Y225353D02*
X255398Y225118D01*
G01X257126Y224988D02*
X257140Y225353D01*
G01X257118Y224965D02*
X257126Y224988D01*
G01X257111Y225050D02*
X257118Y224965D01*
G01X257047Y226524D02*
X257061Y226037D01*
G01X257041Y226913D02*
X257047Y226524D01*
G01X257036Y227384D02*
X257041Y226913D01*
G01X257032Y227925D02*
X257036Y227384D01*
G01X257029Y228520D02*
X257032Y227925D01*
G01X257027Y229153D02*
X257029Y228520D01*
G01X257026Y229807D02*
X257027Y229153D01*
G01X257021Y231677D02*
X257014Y231750D01*
G01X257025Y231547D02*
X257021Y231677D01*
G01X257028Y231359D02*
X257025Y231547D01*
G01X257031Y231120D02*
X257028Y231359D01*
G01X257034Y230838D02*
X257031Y231120D01*
G01X257036Y230521D02*
X257034Y230838D01*
G01X257037Y230180D02*
X257036Y230521D01*
G01X257037Y229826D02*
Y230180D01*
G01X257053Y227364D02*
X257063Y226999D01*
G01X257048Y227656D02*
X257053Y227364D01*
G01X257045Y228009D02*
X257048Y227656D01*
G01X257042Y228414D02*
X257045Y228009D01*
G01X257039Y228861D02*
X257042Y228414D01*
G01X257038Y229336D02*
X257039Y228861D01*
G01X257037Y229826D02*
X257038Y229336D01*
G01X257124Y225965D02*
X257135Y226239D01*
G01X257119Y225948D02*
X257124Y225965D01*
G01X257114Y226012D02*
X257119Y225948D01*
G01X257115Y220412D02*
X257104Y220365D01*
G01X257120Y220314D02*
X257115Y220412D01*
G01X257126Y220138D02*
X257120Y220314D01*
G01X257030Y217516D02*
X257028Y216551D01*
G01X257032Y217963D02*
X257030Y217516D01*
G01X257035Y218368D02*
X257032Y217963D01*
G01X257039Y218722D02*
X257035Y218368D01*
G01X257044Y219013D02*
X257039Y218722D01*
G01X257048Y219234D02*
X257044Y219013D01*
G01X257054Y219379D02*
X257048Y219234D01*
G01X257026Y215857D02*
X257028Y216551D01*
G01X257024Y215540D02*
X257026Y215857D01*
G01X257022Y215257D02*
X257024Y215540D01*
G01X257019Y215018D02*
X257022Y215257D01*
G01X257016Y214830D02*
X257019Y215018D01*
G01X257012Y214700D02*
X257016Y214830D01*
G01X257008Y214632D02*
X257012Y214700D01*
G01X257004Y214627D02*
X257008Y214632D01*
G01X257020Y217857D02*
X257017Y216570D01*
G01X257023Y218453D02*
X257020Y217857D01*
G01X257027Y218993D02*
X257023Y218453D01*
G01X257032Y219464D02*
X257027Y218993D01*
G01X257038Y219853D02*
X257032Y219464D01*
G01X257044Y220148D02*
X257038Y219853D01*
G01X257051Y220340D02*
X257044Y220148D01*
G01X257116Y221390D02*
X257102Y221327D01*
G01X257124Y221259D02*
X257116Y221390D01*
G01X257130Y221024D02*
X257124Y221259D01*
G01X255396Y221390D02*
X255382Y221024D01*
G01X255403Y221412D02*
X255396Y221390D01*
G01X255410Y221327D02*
X255403Y221412D01*
G01X255474Y219853D02*
X255461Y220340D01*
G01X255480Y219464D02*
X255474Y219853D01*
G01X255485Y218993D02*
X255480Y219464D01*
G01X255490Y218453D02*
X255485Y218993D01*
G01X255493Y217857D02*
X255490Y218453D01*
G01X255495Y217224D02*
X255493Y217857D01*
G01X255495Y216570D02*
Y217224D01*
G01X255500Y214700D02*
X255508Y214627D01*
G01X255497Y214830D02*
X255500Y214700D01*
G01X255493Y215018D02*
X255497Y214830D01*
G01X255490Y215257D02*
X255493Y215018D01*
G01X255488Y215540D02*
X255490Y215257D01*
G01X255486Y215857D02*
X255488Y215540D01*
G01X255485Y216198D02*
X255486Y215857D01*
G01X255484Y216551D02*
X255485Y216198D01*
G01X255469Y219013D02*
X255459Y219379D01*
G01X255473Y218722D02*
X255469Y219013D01*
G01X255477Y218368D02*
X255473Y218722D01*
G01X255480Y217963D02*
X255477Y218368D01*
G01X255482Y217516D02*
X255480Y217963D01*
G01X255484Y217041D02*
X255482Y217516D01*
G01X255484Y216551D02*
Y217041D01*
G01X255397Y220412D02*
X255387Y220138D01*
G01X255403Y220429D02*
X255397Y220412D01*
G01X255408Y220365D02*
X255403Y220429D01*
G01X251465Y225965D02*
X251476Y226012D01*
G01X251459Y226063D02*
X251465Y225965D01*
G01X251454Y226239D02*
X251459Y226063D01*
G01X251550Y228861D02*
X251552Y229826D01*
G01X251548Y228414D02*
X251550Y228861D01*
G01X251545Y228009D02*
X251548Y228414D01*
G01X251541Y227656D02*
X251545Y228009D01*
G01X251536Y227364D02*
X251541Y227656D01*
G01X251531Y227143D02*
X251536Y227364D01*
G01X251526Y226999D02*
X251531Y227143D01*
G01X251560Y228520D02*
X251563Y229807D01*
G01X251557Y227925D02*
X251560Y228520D01*
G01X251553Y227384D02*
X251557Y227925D01*
G01X251548Y226913D02*
X251553Y227384D01*
G01X251542Y226524D02*
X251548Y226913D01*
G01X251536Y226230D02*
X251542Y226524D01*
G01X251529Y226037D02*
X251536Y226230D01*
G01X251464Y224988D02*
X251478Y225050D01*
G01X251456Y225118D02*
X251464Y224988D01*
G01X251450Y225353D02*
X251456Y225118D01*
G01X253184Y224988D02*
X253198Y225353D01*
G01X253177Y224965D02*
X253184Y224988D01*
G01X253170Y225050D02*
X253177Y224965D01*
G01X253105Y226524D02*
X253119Y226037D01*
G01X253100Y226913D02*
X253105Y226524D01*
G01X253094Y227384D02*
X253100Y226913D01*
G01X253090Y227925D02*
X253094Y227384D01*
G01X253087Y228520D02*
X253090Y227925D01*
G01X253085Y229153D02*
X253087Y228520D01*
G01X253085Y229807D02*
Y229153D01*
G01X253111Y227364D02*
X253121Y226999D01*
G01X253107Y227656D02*
X253111Y227364D01*
G01X253103Y228009D02*
X253107Y227656D01*
G01X253100Y228414D02*
X253103Y228009D01*
G01X253098Y228861D02*
X253100Y228414D01*
G01X253096Y229336D02*
X253098Y228861D01*
G01X253095Y229826D02*
X253096Y229336D01*
G01X253183Y225965D02*
X253193Y226239D01*
G01X253177Y225948D02*
X253183Y225965D01*
G01X253172Y226012D02*
X253177Y225948D01*
G01X253183Y220412D02*
X253172Y220365D01*
G01X253188Y220314D02*
X253183Y220412D01*
G01X253193Y220138D02*
X253188Y220314D01*
G01X253098Y217516D02*
X253095Y216551D01*
G01X253100Y217963D02*
X253098Y217516D01*
G01X253103Y218368D02*
X253100Y217963D01*
G01X253107Y218722D02*
X253103Y218368D01*
G01X253111Y219013D02*
X253107Y218722D01*
G01X253116Y219234D02*
X253111Y219013D01*
G01X253121Y219379D02*
X253116Y219234D01*
G01X253087Y217857D02*
X253085Y216570D01*
G01X253090Y218453D02*
X253087Y217857D01*
G01X253094Y218993D02*
X253090Y218453D01*
G01X253100Y219464D02*
X253094Y218993D01*
G01X253105Y219853D02*
X253100Y219464D01*
G01X253112Y220148D02*
X253105Y219853D01*
G01X253119Y220340D02*
X253112Y220148D01*
G01X253184Y221390D02*
X253170Y221327D01*
G01X253191Y221259D02*
X253184Y221390D01*
G01X253198Y221024D02*
X253191Y221259D01*
G01X251464Y221390D02*
X251450Y221024D01*
G01X251471Y221412D02*
X251464Y221390D01*
G01X251478Y221327D02*
X251471Y221412D01*
G01X251542Y219853D02*
X251529Y220340D01*
G01X251548Y219464D02*
X251542Y219853D01*
G01X251553Y218993D02*
X251548Y219464D01*
G01X251557Y218453D02*
X251553Y218993D01*
G01X251560Y217857D02*
X251557Y218453D01*
G01X251562Y217224D02*
X251560Y217857D01*
G01X251563Y216570D02*
X251562Y217224D01*
G01X251536Y219013D02*
X251526Y219379D01*
G01X251541Y218722D02*
X251536Y219013D01*
G01X251545Y218368D02*
X251541Y218722D01*
G01X251548Y217963D02*
X251545Y218368D01*
G01X251550Y217516D02*
X251548Y217963D01*
G01X251552Y217041D02*
X251550Y217516D01*
G01X251552Y216551D02*
Y217041D01*
G01X251465Y220412D02*
X251454Y220138D01*
G01X251470Y220429D02*
X251465Y220412D01*
G01X251476Y220365D02*
X251470Y220429D01*
G01X247533Y225965D02*
X247543Y226012D01*
G01X247527Y226063D02*
X247533Y225965D01*
G01X247522Y226239D02*
X247527Y226063D01*
G01X247618Y228861D02*
X247620Y229826D01*
G01X247615Y228414D02*
X247618Y228861D01*
G01X247612Y228009D02*
X247615Y228414D01*
G01X247608Y227656D02*
X247612Y228009D01*
G01X247604Y227364D02*
X247608Y227656D01*
G01X247599Y227143D02*
X247604Y227364D01*
G01X247594Y226999D02*
X247599Y227143D01*
G01X247621Y230521D02*
X247620Y229826D01*
G01X247623Y230838D02*
X247621Y230521D01*
G01X247626Y231120D02*
X247623Y230838D01*
G01X247629Y231359D02*
X247626Y231120D01*
G01X247632Y231547D02*
X247629Y231359D01*
G01X247636Y231677D02*
X247632Y231547D01*
G01X247639Y231746D02*
X247636Y231677D01*
G01X247643Y231750D02*
X247639Y231746D01*
G01X247628Y228520D02*
X247631Y229807D01*
G01X247625Y227925D02*
X247628Y228520D01*
G01X247621Y227384D02*
X247625Y227925D01*
G01X247616Y226913D02*
X247621Y227384D01*
G01X247610Y226524D02*
X247616Y226913D01*
G01X247603Y226230D02*
X247610Y226524D01*
G01X247596Y226037D02*
X247603Y226230D01*
G01X247531Y224988D02*
X247546Y225050D01*
G01X247524Y225118D02*
X247531Y224988D01*
G01X247517Y225353D02*
X247524Y225118D01*
G01X249252Y224988D02*
X249266Y225353D01*
G01X249244Y224965D02*
X249252Y224988D01*
G01X249237Y225050D02*
X249244Y224965D01*
G01X249173Y226524D02*
X249187Y226037D01*
G01X249167Y226913D02*
X249173Y226524D01*
G01X249162Y227384D02*
X249167Y226913D01*
G01X249158Y227925D02*
X249162Y227384D01*
G01X249155Y228520D02*
X249158Y227925D01*
G01X249153Y229153D02*
X249155Y228520D01*
G01X249152Y229807D02*
X249153Y229153D01*
G01X249147Y231677D02*
X249139Y231750D01*
G01X249151Y231547D02*
X249147Y231677D01*
G01X249154Y231359D02*
X249151Y231547D01*
G01X249157Y231120D02*
X249154Y231359D01*
G01X249160Y230838D02*
X249157Y231120D01*
G01X249162Y230521D02*
X249160Y230838D01*
G01X249163Y230180D02*
X249162Y230521D01*
G01X249163Y229826D02*
Y230180D01*
G01X249179Y227364D02*
X249189Y226999D01*
G01X249174Y227656D02*
X249179Y227364D01*
G01X249171Y228009D02*
X249174Y227656D01*
G01X249167Y228414D02*
X249171Y228009D01*
G01X249165Y228861D02*
X249167Y228414D01*
G01X249164Y229336D02*
X249165Y228861D01*
G01X249163Y229826D02*
X249164Y229336D01*
G01X249250Y225965D02*
X249261Y226239D01*
G01X249245Y225948D02*
X249250Y225965D01*
G01X249240Y226012D02*
X249245Y225948D01*
G01X249241Y220412D02*
X249230Y220365D01*
G01X249246Y220314D02*
X249241Y220412D01*
G01X249252Y220138D02*
X249246Y220314D01*
G01X249156Y217516D02*
X249154Y216551D01*
G01X249158Y217963D02*
X249156Y217516D01*
G01X249161Y218368D02*
X249158Y217963D01*
G01X249165Y218722D02*
X249161Y218368D01*
G01X249170Y219013D02*
X249165Y218722D01*
G01X249174Y219234D02*
X249170Y219013D01*
G01X249180Y219379D02*
X249174Y219234D01*
G01X249152Y215857D02*
X249154Y216551D01*
G01X249150Y215540D02*
X249152Y215857D01*
G01X249148Y215257D02*
X249150Y215540D01*
G01X249145Y215018D02*
X249148Y215257D01*
G01X249142Y214830D02*
X249145Y215018D01*
G01X249138Y214700D02*
X249142Y214830D01*
G01X249134Y214632D02*
X249138Y214700D01*
G01X249130Y214627D02*
X249134Y214632D01*
G01X249146Y217857D02*
X249143Y216570D01*
G01X249149Y218453D02*
X249146Y217857D01*
G01X249153Y218993D02*
X249149Y218453D01*
G01X249158Y219464D02*
X249153Y218993D01*
G01X249164Y219853D02*
X249158Y219464D01*
G01X249170Y220148D02*
X249164Y219853D01*
G01X249177Y220340D02*
X249170Y220148D01*
G01X249242Y221390D02*
X249228Y221327D01*
G01X249249Y221259D02*
X249242Y221390D01*
G01X249256Y221024D02*
X249249Y221259D01*
G01X247522Y221390D02*
X247508Y221024D01*
G01X247529Y221412D02*
X247522Y221390D01*
G01X247536Y221327D02*
X247529Y221412D01*
G01X247600Y219853D02*
X247587Y220340D01*
G01X247606Y219464D02*
X247600Y219853D01*
G01X247611Y218993D02*
X247606Y219464D01*
G01X247616Y218453D02*
X247611Y218993D01*
G01X247619Y217857D02*
X247616Y218453D01*
G01X247621Y217224D02*
X247619Y217857D01*
G01X247621Y216570D02*
Y217224D01*
G01X247626Y214700D02*
X247634Y214627D01*
G01X247623Y214830D02*
X247626Y214700D01*
G01X247619Y215018D02*
X247623Y214830D01*
G01X247616Y215257D02*
X247619Y215018D01*
G01X247614Y215540D02*
X247616Y215257D01*
G01X247612Y215857D02*
X247614Y215540D01*
G01X247611Y216198D02*
X247612Y215857D01*
G01X247610Y216551D02*
X247611Y216198D01*
G01X247595Y219013D02*
X247585Y219379D01*
G01X247599Y218722D02*
X247595Y219013D01*
G01X247603Y218368D02*
X247599Y218722D01*
G01X247606Y217963D02*
X247603Y218368D01*
G01X247608Y217516D02*
X247606Y217963D01*
G01X247610Y217041D02*
X247608Y217516D01*
G01X247610Y216551D02*
Y217041D01*
G01X247523Y220412D02*
X247513Y220138D01*
G01X247529Y220429D02*
X247523Y220412D01*
G01X247534Y220365D02*
X247529Y220429D01*
G01X243591Y225965D02*
X243602Y226012D01*
G01X243585Y226063D02*
X243591Y225965D01*
G01X243580Y226239D02*
X243585Y226063D01*
G01X243676Y228861D02*
X243678Y229826D01*
G01X243674Y228414D02*
X243676Y228861D01*
G01X243671Y228009D02*
X243674Y228414D01*
G01X243667Y227656D02*
X243671Y228009D01*
G01X243662Y227364D02*
X243667Y227656D01*
G01X243657Y227143D02*
X243662Y227364D01*
G01X243652Y226999D02*
X243657Y227143D01*
G01X243686Y228520D02*
X243689Y229807D01*
G01X243683Y227925D02*
X243686Y228520D01*
G01X243679Y227384D02*
X243683Y227925D01*
G01X243674Y226913D02*
X243679Y227384D01*
G01X243668Y226524D02*
X243674Y226913D01*
G01X243662Y226230D02*
X243668Y226524D01*
G01X243655Y226037D02*
X243662Y226230D01*
G01X243590Y224988D02*
X243604Y225050D01*
G01X243582Y225118D02*
X243590Y224988D01*
G01X243576Y225353D02*
X243582Y225118D01*
G01X245309Y225965D02*
X245319Y226239D01*
G01X245303Y225948D02*
X245309Y225965D01*
G01X245298Y226012D02*
X245303Y225948D01*
G01X245310Y224988D02*
X245324Y225353D01*
G01X245303Y224965D02*
X245310Y224988D01*
G01X245296Y225050D02*
X245303Y224965D01*
G01X245231Y226524D02*
X245245Y226037D01*
G01X245226Y226913D02*
X245231Y226524D01*
G01X245220Y227384D02*
X245226Y226913D01*
G01X245216Y227925D02*
X245220Y227384D01*
G01X245213Y228520D02*
X245216Y227925D01*
G01X245211Y229153D02*
X245213Y228520D01*
G01X245210Y229807D02*
X245211Y229153D01*
G01X245237Y227364D02*
X245247Y226999D01*
G01X245233Y227656D02*
X245237Y227364D01*
G01X245229Y228009D02*
X245233Y227656D01*
G01X245226Y228414D02*
X245229Y228009D01*
G01X245223Y228861D02*
X245226Y228414D01*
G01X245222Y229336D02*
X245223Y228861D01*
G01X245221Y229826D02*
X245222Y229336D01*
G01X245309Y220412D02*
X245298Y220365D01*
G01X245314Y220314D02*
X245309Y220412D01*
G01X245319Y220138D02*
X245314Y220314D01*
G01X245223Y217516D02*
X245221Y216551D01*
G01X245226Y217963D02*
X245223Y217516D01*
G01X245229Y218368D02*
X245226Y217963D01*
G01X245233Y218722D02*
X245229Y218368D01*
G01X245237Y219013D02*
X245233Y218722D01*
G01X245242Y219234D02*
X245237Y219013D01*
G01X245247Y219379D02*
X245242Y219234D01*
G01X245213Y217857D02*
X245210Y216570D01*
G01X245216Y218453D02*
X245213Y217857D01*
G01X245220Y218993D02*
X245216Y218453D01*
G01X245226Y219464D02*
X245220Y218993D01*
G01X245231Y219853D02*
X245226Y219464D01*
G01X245238Y220148D02*
X245231Y219853D01*
G01X245245Y220340D02*
X245238Y220148D01*
G01X245310Y221390D02*
X245296Y221327D01*
G01X245317Y221259D02*
X245310Y221390D01*
G01X245324Y221024D02*
X245317Y221259D01*
G01X243591Y220412D02*
X243580Y220138D01*
G01X243596Y220429D02*
X243591Y220412D01*
G01X243602Y220365D02*
X243596Y220429D01*
G01X243590Y221390D02*
X243576Y221024D01*
G01X243597Y221412D02*
X243590Y221390D01*
G01X243604Y221327D02*
X243597Y221412D01*
G01X243668Y219853D02*
X243655Y220340D01*
G01X243674Y219464D02*
X243668Y219853D01*
G01X243679Y218993D02*
X243674Y219464D01*
G01X243683Y218453D02*
X243679Y218993D01*
G01X243686Y217857D02*
X243683Y218453D01*
G01X243688Y217224D02*
X243686Y217857D01*
G01X243689Y216570D02*
X243688Y217224D01*
G01X243662Y219013D02*
X243652Y219379D01*
G01X243667Y218722D02*
X243662Y219013D01*
G01X243671Y218368D02*
X243667Y218722D01*
G01X243674Y217963D02*
X243671Y218368D01*
G01X243676Y217516D02*
X243674Y217963D01*
G01X243678Y217041D02*
X243676Y217516D01*
G01X243678Y216551D02*
Y217041D01*
G01X241376Y225965D02*
X241387Y226239D01*
G01X241371Y225948D02*
X241376Y225965D01*
G01X241366Y226012D02*
X241371Y225948D01*
G01X241378Y224988D02*
X241392Y225353D01*
G01X241370Y224965D02*
X241378Y224988D01*
G01X241363Y225050D02*
X241370Y224965D01*
G01X241299Y226524D02*
X241313Y226037D01*
G01X241293Y226913D02*
X241299Y226524D01*
G01X241288Y227384D02*
X241293Y226913D01*
G01X241284Y227925D02*
X241288Y227384D01*
G01X241281Y228520D02*
X241284Y227925D01*
G01X241279Y229153D02*
X241281Y228520D01*
G01X241278Y229807D02*
X241279Y229153D01*
G01X241273Y231677D02*
X241265Y231750D01*
G01X241277Y231547D02*
X241273Y231677D01*
G01X241280Y231359D02*
X241277Y231547D01*
G01X241283Y231120D02*
X241280Y231359D01*
G01X241286Y230838D02*
X241283Y231120D01*
G01X241288Y230521D02*
X241286Y230838D01*
G01X241289Y230180D02*
X241288Y230521D01*
G01X241289Y229826D02*
Y230180D01*
G01X241305Y227364D02*
X241315Y226999D01*
G01X241300Y227656D02*
X241305Y227364D01*
G01X241297Y228009D02*
X241300Y227656D01*
G01X241293Y228414D02*
X241297Y228009D01*
G01X241291Y228861D02*
X241293Y228414D01*
G01X241290Y229336D02*
X241291Y228861D01*
G01X241289Y229826D02*
X241290Y229336D01*
G01X239658Y225965D02*
X239669Y226012D01*
G01X239653Y226063D02*
X239658Y225965D01*
G01X239648Y226239D02*
X239653Y226063D01*
G01X239744Y228861D02*
X239746Y229826D01*
G01X239741Y228414D02*
X239744Y228861D01*
G01X239738Y228009D02*
X239741Y228414D01*
G01X239734Y227656D02*
X239738Y228009D01*
G01X239730Y227364D02*
X239734Y227656D01*
G01X239725Y227143D02*
X239730Y227364D01*
G01X239720Y226999D02*
X239725Y227143D01*
G01X239747Y230521D02*
X239746Y229826D01*
G01X239749Y230838D02*
X239747Y230521D01*
G01X239752Y231120D02*
X239749Y230838D01*
G01X239754Y231359D02*
X239752Y231120D01*
G01X239758Y231547D02*
X239754Y231359D01*
G01X239762Y231677D02*
X239758Y231547D01*
G01X239765Y231746D02*
X239762Y231677D01*
G01X239769Y231750D02*
X239765Y231746D01*
G01X239754Y228520D02*
X239757Y229807D01*
G01X239751Y227925D02*
X239754Y228520D01*
G01X239747Y227384D02*
X239751Y227925D01*
G01X239742Y226913D02*
X239747Y227384D01*
G01X239736Y226524D02*
X239742Y226913D01*
G01X239729Y226230D02*
X239736Y226524D01*
G01X239722Y226037D02*
X239729Y226230D01*
G01X239657Y224988D02*
X239672Y225050D01*
G01X239650Y225118D02*
X239657Y224988D01*
G01X239643Y225353D02*
X239650Y225118D01*
G01X239649Y220412D02*
X239639Y220138D01*
G01X239655Y220429D02*
X239649Y220412D01*
G01X239660Y220365D02*
X239655Y220429D01*
G01X239648Y221390D02*
X239634Y221024D01*
G01X239655Y221412D02*
X239648Y221390D01*
G01X239662Y221327D02*
X239655Y221412D01*
G01X239726Y219853D02*
X239713Y220340D01*
G01X239732Y219464D02*
X239726Y219853D01*
G01X239737Y218993D02*
X239732Y219464D01*
G01X239742Y218453D02*
X239737Y218993D01*
G01X239745Y217857D02*
X239742Y218453D01*
G01X239747Y217224D02*
X239745Y217857D01*
G01X239747Y216570D02*
Y217224D01*
G01X239752Y214700D02*
X239760Y214627D01*
G01X239749Y214830D02*
X239752Y214700D01*
G01X239745Y215018D02*
X239749Y214830D01*
G01X239742Y215257D02*
X239745Y215018D01*
G01X239740Y215540D02*
X239742Y215257D01*
G01X239738Y215857D02*
X239740Y215540D01*
G01X239737Y216198D02*
X239738Y215857D01*
G01X239736Y216551D02*
X239737Y216198D01*
G01X239721Y219013D02*
X239711Y219379D01*
G01X239725Y218722D02*
X239721Y219013D01*
G01X239729Y218368D02*
X239725Y218722D01*
G01X239732Y217963D02*
X239729Y218368D01*
G01X239734Y217516D02*
X239732Y217963D01*
G01X239736Y217041D02*
X239734Y217516D01*
G01X239736Y216551D02*
Y217041D01*
G01X241367Y220412D02*
X241356Y220365D01*
G01X241372Y220314D02*
X241367Y220412D01*
G01X241378Y220138D02*
X241372Y220314D01*
G01X241282Y217516D02*
X241280Y216551D01*
G01X241284Y217963D02*
X241282Y217516D01*
G01X241287Y218368D02*
X241284Y217963D01*
G01X241291Y218722D02*
X241287Y218368D01*
G01X241296Y219013D02*
X241291Y218722D01*
G01X241300Y219234D02*
X241296Y219013D01*
G01X241306Y219379D02*
X241300Y219234D01*
G01X241278Y215857D02*
X241280Y216551D01*
G01X241276Y215540D02*
X241278Y215857D01*
G01X241274Y215257D02*
X241276Y215540D01*
G01X241271Y215018D02*
X241274Y215257D01*
G01X241268Y214830D02*
X241271Y215018D01*
G01X241264Y214700D02*
X241268Y214830D01*
G01X241260Y214632D02*
X241264Y214700D01*
G01X241256Y214627D02*
X241260Y214632D01*
G01X241272Y217857D02*
X241269Y216570D01*
G01X241275Y218453D02*
X241272Y217857D01*
G01X241279Y218993D02*
X241275Y218453D01*
G01X241284Y219464D02*
X241279Y218993D01*
G01X241290Y219853D02*
X241284Y219464D01*
G01X241296Y220148D02*
X241290Y219853D01*
G01X241303Y220340D02*
X241296Y220148D01*
G01X241368Y221390D02*
X241354Y221327D01*
G01X241375Y221259D02*
X241368Y221390D01*
G01X241382Y221024D02*
X241375Y221259D01*
G01X235717Y225965D02*
X235728Y226012D01*
G01X235711Y226063D02*
X235717Y225965D01*
G01X235706Y226239D02*
X235711Y226063D01*
G01X235802Y228861D02*
X235804Y229826D01*
G01X235800Y228414D02*
X235802Y228861D01*
G01X235797Y228009D02*
X235800Y228414D01*
G01X235793Y227656D02*
X235797Y228009D01*
G01X235788Y227364D02*
X235793Y227656D01*
G01X235783Y227143D02*
X235788Y227364D01*
G01X235778Y226999D02*
X235783Y227143D01*
G01X235812Y228520D02*
X235815Y229807D01*
G01X235809Y227925D02*
X235812Y228520D01*
G01X235805Y227384D02*
X235809Y227925D01*
G01X235800Y226913D02*
X235805Y227384D01*
G01X235794Y226524D02*
X235800Y226913D01*
G01X235788Y226230D02*
X235794Y226524D01*
G01X235781Y226037D02*
X235788Y226230D01*
G01X235716Y224988D02*
X235730Y225050D01*
G01X235708Y225118D02*
X235716Y224988D01*
G01X235702Y225353D02*
X235708Y225118D01*
G01X237435Y225965D02*
X237445Y226239D01*
G01X237429Y225948D02*
X237435Y225965D01*
G01X237424Y226012D02*
X237429Y225948D01*
G01X237436Y224988D02*
X237450Y225353D01*
G01X237429Y224965D02*
X237436Y224988D01*
G01X237421Y225050D02*
X237429Y224965D01*
G01X237357Y226524D02*
X237371Y226037D01*
G01X237352Y226913D02*
X237357Y226524D01*
G01X237346Y227384D02*
X237352Y226913D01*
G01X237342Y227925D02*
X237346Y227384D01*
G01X237339Y228520D02*
X237342Y227925D01*
G01X237337Y229153D02*
X237339Y228520D01*
G01X237336Y229807D02*
X237337Y229153D01*
G01X237363Y227364D02*
X237373Y226999D01*
G01X237359Y227656D02*
X237363Y227364D01*
G01X237355Y228009D02*
X237359Y227656D01*
G01X237352Y228414D02*
X237355Y228009D01*
G01X237349Y228861D02*
X237352Y228414D01*
G01X237348Y229336D02*
X237349Y228861D01*
G01X237347Y229826D02*
X237348Y229336D01*
G01X237435Y220412D02*
X237424Y220365D01*
G01X237440Y220314D02*
X237435Y220412D01*
G01X237445Y220138D02*
X237440Y220314D01*
G01X237349Y217516D02*
X237347Y216551D01*
G01X237352Y217963D02*
X237349Y217516D01*
G01X237355Y218368D02*
X237352Y217963D01*
G01X237359Y218722D02*
X237355Y218368D01*
G01X237363Y219013D02*
X237359Y218722D01*
G01X237368Y219234D02*
X237363Y219013D01*
G01X237373Y219379D02*
X237368Y219234D01*
G01X237339Y217857D02*
X237336Y216570D01*
G01X237342Y218453D02*
X237339Y217857D01*
G01X237346Y218993D02*
X237342Y218453D01*
G01X237352Y219464D02*
X237346Y218993D01*
G01X237357Y219853D02*
X237352Y219464D01*
G01X237364Y220148D02*
X237357Y219853D01*
G01X237371Y220340D02*
X237364Y220148D01*
G01X237436Y221390D02*
X237421Y221327D01*
G01X237443Y221259D02*
X237436Y221390D01*
G01X237450Y221024D02*
X237443Y221259D01*
G01X235717Y220412D02*
X235706Y220138D01*
G01X235722Y220429D02*
X235717Y220412D01*
G01X235728Y220365D02*
X235722Y220429D01*
G01X235716Y221390D02*
X235702Y221024D01*
G01X235723Y221412D02*
X235716Y221390D01*
G01X235730Y221327D02*
X235723Y221412D01*
G01X235794Y219853D02*
X235781Y220340D01*
G01X235800Y219464D02*
X235794Y219853D01*
G01X235805Y218993D02*
X235800Y219464D01*
G01X235809Y218453D02*
X235805Y218993D01*
G01X235812Y217857D02*
X235809Y218453D01*
G01X235814Y217224D02*
X235812Y217857D01*
G01X235815Y216570D02*
X235814Y217224D01*
G01X235788Y219013D02*
X235778Y219379D01*
G01X235793Y218722D02*
X235788Y219013D01*
G01X235797Y218368D02*
X235793Y218722D01*
G01X235800Y217963D02*
X235797Y218368D01*
G01X235802Y217516D02*
X235800Y217963D01*
G01X235804Y217041D02*
X235802Y217516D01*
G01X235804Y216551D02*
Y217041D01*
G01X233502Y225965D02*
X233513Y226239D01*
G01X233497Y225948D02*
X233502Y225965D01*
G01X233491Y226012D02*
X233497Y225948D01*
G01X233504Y224988D02*
X233518Y225353D01*
G01X233496Y224965D02*
X233504Y224988D01*
G01X233489Y225050D02*
X233496Y224965D01*
G01X233425Y226524D02*
X233439Y226037D01*
G01X233419Y226913D02*
X233425Y226524D01*
G01X233414Y227384D02*
X233419Y226913D01*
G01X233410Y227925D02*
X233414Y227384D01*
G01X233407Y228520D02*
X233410Y227925D01*
G01X233405Y229153D02*
X233407Y228520D01*
G01X233404Y229807D02*
X233405Y229153D01*
G01X233399Y231677D02*
X233391Y231750D01*
G01X233403Y231547D02*
X233399Y231677D01*
G01X233406Y231359D02*
X233403Y231547D01*
G01X233409Y231120D02*
X233406Y231359D01*
G01X233412Y230838D02*
X233409Y231120D01*
G01X233414Y230521D02*
X233412Y230838D01*
G01X233415Y230180D02*
X233414Y230521D01*
G01X233415Y229826D02*
Y230180D01*
G01X233431Y227364D02*
X233441Y226999D01*
G01X233426Y227656D02*
X233431Y227364D01*
G01X233423Y228009D02*
X233426Y227656D01*
G01X233419Y228414D02*
X233423Y228009D01*
G01X233417Y228861D02*
X233419Y228414D01*
G01X233416Y229336D02*
X233417Y228861D01*
G01X233415Y229826D02*
X233416Y229336D01*
G01X231784Y225965D02*
X231795Y226012D01*
G01X231779Y226063D02*
X231784Y225965D01*
G01X231774Y226239D02*
X231779Y226063D01*
G01X231870Y228861D02*
X231872Y229826D01*
G01X231867Y228414D02*
X231870Y228861D01*
G01X231864Y228009D02*
X231867Y228414D01*
G01X231860Y227656D02*
X231864Y228009D01*
G01X231856Y227364D02*
X231860Y227656D01*
G01X231851Y227143D02*
X231856Y227364D01*
G01X231846Y226999D02*
X231851Y227143D01*
G01X231873Y230521D02*
X231872Y229826D01*
G01X231875Y230838D02*
X231873Y230521D01*
G01X231878Y231120D02*
X231875Y230838D01*
G01X231880Y231359D02*
X231878Y231120D01*
G01X231884Y231547D02*
X231880Y231359D01*
G01X231888Y231677D02*
X231884Y231547D01*
G01X231891Y231746D02*
X231888Y231677D01*
G01X231895Y231750D02*
X231891Y231746D01*
G01X231880Y228520D02*
X231883Y229807D01*
G01X231877Y227925D02*
X231880Y228520D01*
G01X231873Y227384D02*
X231877Y227925D01*
G01X231868Y226913D02*
X231873Y227384D01*
G01X231862Y226524D02*
X231868Y226913D01*
G01X231855Y226230D02*
X231862Y226524D01*
G01X231848Y226037D02*
X231855Y226230D01*
G01X231783Y224988D02*
X231798Y225050D01*
G01X231776Y225118D02*
X231783Y224988D01*
G01X231769Y225353D02*
X231776Y225118D01*
G01X231775Y220412D02*
X231765Y220138D01*
G01X231781Y220429D02*
X231775Y220412D01*
G01X231786Y220365D02*
X231781Y220429D01*
G01X231774Y221390D02*
X231760Y221024D01*
G01X231781Y221412D02*
X231774Y221390D01*
G01X231788Y221327D02*
X231781Y221412D01*
G01X231852Y219853D02*
X231839Y220340D01*
G01X231858Y219464D02*
X231852Y219853D01*
G01X231863Y218993D02*
X231858Y219464D01*
G01X231868Y218453D02*
X231863Y218993D01*
G01X231871Y217857D02*
X231868Y218453D01*
G01X231873Y217224D02*
X231871Y217857D01*
G01X231873Y216570D02*
Y217224D01*
G01X231878Y214700D02*
X231886Y214627D01*
G01X231875Y214830D02*
X231878Y214700D01*
G01X231871Y215018D02*
X231875Y214830D01*
G01X231868Y215257D02*
X231871Y215018D01*
G01X231866Y215540D02*
X231868Y215257D01*
G01X231864Y215857D02*
X231866Y215540D01*
G01X231863Y216198D02*
X231864Y215857D01*
G01X231862Y216551D02*
X231863Y216198D01*
G01X231847Y219013D02*
X231837Y219379D01*
G01X231851Y218722D02*
X231847Y219013D01*
G01X231855Y218368D02*
X231851Y218722D01*
G01X231858Y217963D02*
X231855Y218368D01*
G01X231860Y217516D02*
X231858Y217963D01*
G01X231862Y217041D02*
X231860Y217516D01*
G01X231862Y216551D02*
Y217041D01*
G01X233493Y220412D02*
X233482Y220365D01*
G01X233498Y220314D02*
X233493Y220412D01*
G01X233503Y220138D02*
X233498Y220314D01*
G01X233408Y217516D02*
X233406Y216551D01*
G01X233410Y217963D02*
X233408Y217516D01*
G01X233413Y218368D02*
X233410Y217963D01*
G01X233417Y218722D02*
X233413Y218368D01*
G01X233422Y219013D02*
X233417Y218722D01*
G01X233426Y219234D02*
X233422Y219013D01*
G01X233432Y219379D02*
X233426Y219234D01*
G01X233404Y215857D02*
X233406Y216551D01*
G01X233402Y215540D02*
X233404Y215857D01*
G01X233400Y215257D02*
X233402Y215540D01*
G01X233397Y215018D02*
X233400Y215257D01*
G01X233394Y214830D02*
X233397Y215018D01*
G01X233390Y214700D02*
X233394Y214830D01*
G01X233386Y214632D02*
X233390Y214700D01*
G01X233382Y214627D02*
X233386Y214632D01*
G01X233398Y217857D02*
X233395Y216570D01*
G01X233401Y218453D02*
X233398Y217857D01*
G01X233405Y218993D02*
X233401Y218453D01*
G01X233410Y219464D02*
X233405Y218993D01*
G01X233416Y219853D02*
X233410Y219464D01*
G01X233422Y220148D02*
X233416Y219853D01*
G01X233429Y220340D02*
X233422Y220148D01*
G01X233494Y221390D02*
X233480Y221327D01*
G01X233501Y221259D02*
X233494Y221390D01*
G01X233508Y221024D02*
X233501Y221259D01*
G01X227843Y225965D02*
X227854Y226012D01*
G01X227837Y226063D02*
X227843Y225965D01*
G01X227832Y226239D02*
X227837Y226063D01*
G01X227928Y228861D02*
X227930Y229826D01*
G01X227926Y228414D02*
X227928Y228861D01*
G01X227923Y228009D02*
X227926Y228414D01*
G01X227919Y227656D02*
X227923Y228009D01*
G01X227914Y227364D02*
X227919Y227656D01*
G01X227909Y227143D02*
X227914Y227364D01*
G01X227904Y226999D02*
X227909Y227143D01*
G01X227938Y228520D02*
X227941Y229807D01*
G01X227935Y227925D02*
X227938Y228520D01*
G01X227931Y227384D02*
X227935Y227925D01*
G01X227926Y226913D02*
X227931Y227384D01*
G01X227920Y226524D02*
X227926Y226913D01*
G01X227913Y226230D02*
X227920Y226524D01*
G01X227907Y226037D02*
X227913Y226230D01*
G01X227842Y224988D02*
X227856Y225050D01*
G01X227834Y225118D02*
X227842Y224988D01*
G01X227828Y225353D02*
X227834Y225118D01*
G01X229561Y225965D02*
X229571Y226239D01*
G01X229555Y225948D02*
X229561Y225965D01*
G01X229550Y226012D02*
X229555Y225948D01*
G01X229562Y224988D02*
X229576Y225353D01*
G01X229555Y224965D02*
X229562Y224988D01*
G01X229547Y225050D02*
X229555Y224965D01*
G01X229483Y226524D02*
X229497Y226037D01*
G01X229478Y226913D02*
X229483Y226524D01*
G01X229472Y227384D02*
X229478Y226913D01*
G01X229468Y227925D02*
X229472Y227384D01*
G01X229465Y228520D02*
X229468Y227925D01*
G01X229463Y229153D02*
X229465Y228520D01*
G01X229462Y229807D02*
X229463Y229153D01*
G01X229489Y227364D02*
X229499Y226999D01*
G01X229485Y227656D02*
X229489Y227364D01*
G01X229481Y228009D02*
X229485Y227656D01*
G01X229478Y228414D02*
X229481Y228009D01*
G01X229475Y228861D02*
X229478Y228414D01*
G01X229474Y229336D02*
X229475Y228861D01*
G01X229473Y229826D02*
X229474Y229336D01*
G01X229561Y220412D02*
X229550Y220365D01*
G01X229566Y220314D02*
X229561Y220412D01*
G01X229571Y220138D02*
X229566Y220314D01*
G01X229475Y217516D02*
X229473Y216551D01*
G01X229478Y217963D02*
X229475Y217516D01*
G01X229481Y218368D02*
X229478Y217963D01*
G01X229485Y218722D02*
X229481Y218368D01*
G01X229489Y219013D02*
X229485Y218722D01*
G01X229494Y219234D02*
X229489Y219013D01*
G01X229499Y219379D02*
X229494Y219234D01*
G01X229465Y217857D02*
X229462Y216570D01*
G01X229468Y218453D02*
X229465Y217857D01*
G01X229472Y218993D02*
X229468Y218453D01*
G01X229478Y219464D02*
X229472Y218993D01*
G01X229483Y219853D02*
X229478Y219464D01*
G01X229490Y220148D02*
X229483Y219853D01*
G01X229497Y220340D02*
X229490Y220148D01*
G01X229562Y221390D02*
X229547Y221327D01*
G01X229569Y221259D02*
X229562Y221390D01*
G01X229576Y221024D02*
X229569Y221259D01*
G01X227843Y220412D02*
X227832Y220138D01*
G01X227848Y220429D02*
X227843Y220412D01*
G01X227854Y220365D02*
X227848Y220429D01*
G01X227842Y221390D02*
X227828Y221024D01*
G01X227849Y221412D02*
X227842Y221390D01*
G01X227856Y221327D02*
X227849Y221412D01*
G01X227920Y219853D02*
X227907Y220340D01*
G01X227926Y219464D02*
X227920Y219853D01*
G01X227931Y218993D02*
X227926Y219464D01*
G01X227935Y218453D02*
X227931Y218993D01*
G01X227938Y217857D02*
X227935Y218453D01*
G01X227940Y217224D02*
X227938Y217857D01*
G01X227941Y216570D02*
X227940Y217224D01*
G01X227914Y219013D02*
X227904Y219379D01*
G01X227919Y218722D02*
X227914Y219013D01*
G01X227923Y218368D02*
X227919Y218722D01*
G01X227926Y217963D02*
X227923Y218368D01*
G01X227928Y217516D02*
X227926Y217963D01*
G01X227929Y217041D02*
X227928Y217516D01*
G01X227930Y216551D02*
X227929Y217041D01*
G01X225628Y225965D02*
X225639Y226239D01*
G01X225623Y225948D02*
X225628Y225965D01*
G01X225617Y226012D02*
X225623Y225948D01*
G01X225630Y224988D02*
X225644Y225353D01*
G01X225622Y224965D02*
X225630Y224988D01*
G01X225615Y225050D02*
X225622Y224965D01*
G01X225551Y226524D02*
X225565Y226037D01*
G01X225545Y226913D02*
X225551Y226524D01*
G01X225540Y227384D02*
X225545Y226913D01*
G01X225536Y227925D02*
X225540Y227384D01*
G01X225533Y228520D02*
X225536Y227925D01*
G01X225531Y229153D02*
X225533Y228520D01*
G01X225530Y229807D02*
X225531Y229153D01*
G01X225525Y231677D02*
X225517Y231750D01*
G01X225529Y231547D02*
X225525Y231677D01*
G01X225532Y231359D02*
X225529Y231547D01*
G01X225535Y231120D02*
X225532Y231359D01*
G01X225538Y230838D02*
X225535Y231120D01*
G01X225540Y230521D02*
X225538Y230838D01*
G01X225541Y230180D02*
X225540Y230521D01*
G01X225541Y229826D02*
Y230180D01*
G01X225557Y227364D02*
X225567Y226999D01*
G01X225552Y227656D02*
X225557Y227364D01*
G01X225549Y228009D02*
X225552Y227656D01*
G01X225545Y228414D02*
X225549Y228009D01*
G01X225543Y228861D02*
X225545Y228414D01*
G01X225542Y229336D02*
X225543Y228861D01*
G01X225541Y229826D02*
X225542Y229336D01*
G01X223910Y225965D02*
X223921Y226012D01*
G01X223905Y226063D02*
X223910Y225965D01*
G01X223900Y226239D02*
X223905Y226063D01*
G01X223996Y228861D02*
X223998Y229826D01*
G01X223993Y228414D02*
X223996Y228861D01*
G01X223990Y228009D02*
X223993Y228414D01*
G01X223986Y227656D02*
X223990Y228009D01*
G01X223982Y227364D02*
X223986Y227656D01*
G01X223977Y227143D02*
X223982Y227364D01*
G01X223972Y226999D02*
X223977Y227143D01*
G01X223999Y230521D02*
X223998Y229826D01*
G01X224001Y230838D02*
X223999Y230521D01*
G01X224004Y231120D02*
X224001Y230838D01*
G01X224006Y231359D02*
X224004Y231120D01*
G01X224010Y231547D02*
X224006Y231359D01*
G01X224014Y231677D02*
X224010Y231547D01*
G01X224017Y231746D02*
X224014Y231677D01*
G01X224021Y231750D02*
X224017Y231746D01*
G01X224006Y228520D02*
X224009Y229807D01*
G01X224003Y227925D02*
X224006Y228520D01*
G01X223999Y227384D02*
X224003Y227925D01*
G01X223994Y226913D02*
X223999Y227384D01*
G01X223988Y226524D02*
X223994Y226913D01*
G01X223981Y226230D02*
X223988Y226524D01*
G01X223974Y226037D02*
X223981Y226230D01*
G01X223909Y224988D02*
X223924Y225050D01*
G01X223902Y225118D02*
X223909Y224988D01*
G01X223895Y225353D02*
X223902Y225118D01*
G01X223901Y220412D02*
X223891Y220138D01*
G01X223907Y220429D02*
X223901Y220412D01*
G01X223912Y220365D02*
X223907Y220429D01*
G01X223900Y221390D02*
X223886Y221024D01*
G01X223907Y221412D02*
X223900Y221390D01*
G01X223914Y221327D02*
X223907Y221412D01*
G01X223978Y219853D02*
X223965Y220340D01*
G01X223984Y219464D02*
X223978Y219853D01*
G01X223989Y218993D02*
X223984Y219464D01*
G01X223994Y218453D02*
X223989Y218993D01*
G01X223997Y217857D02*
X223994Y218453D01*
G01X223999Y217224D02*
X223997Y217857D01*
G01X223999Y216570D02*
Y217224D01*
G01X224004Y214700D02*
X224012Y214627D01*
G01X224000Y214830D02*
X224004Y214700D01*
G01X223997Y215018D02*
X224000Y214830D01*
G01X223994Y215257D02*
X223997Y215018D01*
G01X223992Y215540D02*
X223994Y215257D01*
G01X223990Y215857D02*
X223992Y215540D01*
G01X223989Y216198D02*
X223990Y215857D01*
G01X223988Y216551D02*
X223989Y216198D01*
G01X223973Y219013D02*
X223962Y219379D01*
G01X223977Y218722D02*
X223973Y219013D01*
G01X223981Y218368D02*
X223977Y218722D01*
G01X223984Y217963D02*
X223981Y218368D01*
G01X223986Y217516D02*
X223984Y217963D01*
G01X223988Y217041D02*
X223986Y217516D01*
G01X223988Y216551D02*
Y217041D01*
G01X225619Y220412D02*
X225608Y220365D01*
G01X225624Y220314D02*
X225619Y220412D01*
G01X225629Y220138D02*
X225624Y220314D01*
G01X225534Y217516D02*
X225532Y216551D01*
G01X225536Y217963D02*
X225534Y217516D01*
G01X225539Y218368D02*
X225536Y217963D01*
G01X225543Y218722D02*
X225539Y218368D01*
G01X225547Y219013D02*
X225543Y218722D01*
G01X225552Y219234D02*
X225547Y219013D01*
G01X225558Y219379D02*
X225552Y219234D01*
G01X225530Y215857D02*
X225532Y216551D01*
G01X225528Y215540D02*
X225530Y215857D01*
G01X225526Y215257D02*
X225528Y215540D01*
G01X225523Y215018D02*
X225526Y215257D01*
G01X225520Y214830D02*
X225523Y215018D01*
G01X225516Y214700D02*
X225520Y214830D01*
G01X225512Y214632D02*
X225516Y214700D01*
G01X225508Y214627D02*
X225512Y214632D01*
G01X225523Y217857D02*
X225521Y216570D01*
G01X225527Y218453D02*
X225523Y217857D01*
G01X225531Y218993D02*
X225527Y218453D01*
G01X225536Y219464D02*
X225531Y218993D01*
G01X225542Y219853D02*
X225536Y219464D01*
G01X225548Y220148D02*
X225542Y219853D01*
G01X225555Y220340D02*
X225548Y220148D01*
G01X225620Y221390D02*
X225606Y221327D01*
G01X225627Y221259D02*
X225620Y221390D01*
G01X225634Y221024D02*
X225627Y221259D01*
G01X219969Y225965D02*
X219980Y226012D01*
G01X219963Y226063D02*
X219969Y225965D01*
G01X219958Y226239D02*
X219963Y226063D01*
G01X220054Y228861D02*
X220056Y229826D01*
G01X220052Y228414D02*
X220054Y228861D01*
G01X220049Y228009D02*
X220052Y228414D01*
G01X220045Y227656D02*
X220049Y228009D01*
G01X220040Y227364D02*
X220045Y227656D01*
G01X220035Y227143D02*
X220040Y227364D01*
G01X220030Y226999D02*
X220035Y227143D01*
G01X220064Y228520D02*
X220067Y229807D01*
G01X220061Y227925D02*
X220064Y228520D01*
G01X220057Y227384D02*
X220061Y227925D01*
G01X220052Y226913D02*
X220057Y227384D01*
G01X220046Y226524D02*
X220052Y226913D01*
G01X220039Y226230D02*
X220046Y226524D01*
G01X220032Y226037D02*
X220039Y226230D01*
G01X219967Y224988D02*
X219982Y225050D01*
G01X219960Y225118D02*
X219967Y224988D01*
G01X219954Y225353D02*
X219960Y225118D01*
G01X221687Y225965D02*
X221697Y226239D01*
G01X221681Y225948D02*
X221687Y225965D01*
G01X221676Y226012D02*
X221681Y225948D01*
G01X221688Y224988D02*
X221702Y225353D01*
G01X221681Y224965D02*
X221688Y224988D01*
G01X221673Y225050D02*
X221681Y224965D01*
G01X221609Y226524D02*
X221623Y226037D01*
G01X221604Y226913D02*
X221609Y226524D01*
G01X221598Y227384D02*
X221604Y226913D01*
G01X221594Y227925D02*
X221598Y227384D01*
G01X221591Y228520D02*
X221594Y227925D01*
G01X221589Y229153D02*
X221591Y228520D01*
G01X221588Y229807D02*
X221589Y229153D01*
G01X221615Y227364D02*
X221625Y226999D01*
G01X221611Y227656D02*
X221615Y227364D01*
G01X221607Y228009D02*
X221611Y227656D01*
G01X221604Y228414D02*
X221607Y228009D01*
G01X221601Y228861D02*
X221604Y228414D01*
G01X221600Y229336D02*
X221601Y228861D01*
G01X221599Y229826D02*
X221600Y229336D01*
G01X221687Y220412D02*
X221676Y220365D01*
G01X221692Y220314D02*
X221687Y220412D01*
G01X221697Y220138D02*
X221692Y220314D01*
G01X221601Y217516D02*
X221599Y216551D01*
G01X221604Y217963D02*
X221601Y217516D01*
G01X221607Y218368D02*
X221604Y217963D01*
G01X221611Y218722D02*
X221607Y218368D01*
G01X221615Y219013D02*
X221611Y218722D01*
G01X221620Y219234D02*
X221615Y219013D01*
G01X221625Y219379D02*
X221620Y219234D01*
G01X221591Y217857D02*
X221588Y216570D01*
G01X221594Y218453D02*
X221591Y217857D01*
G01X221598Y218993D02*
X221594Y218453D01*
G01X221604Y219464D02*
X221598Y218993D01*
G01X221609Y219853D02*
X221604Y219464D01*
G01X221616Y220148D02*
X221609Y219853D01*
G01X221623Y220340D02*
X221616Y220148D01*
G01X221688Y221390D02*
X221673Y221327D01*
G01X221695Y221259D02*
X221688Y221390D01*
G01X221702Y221024D02*
X221695Y221259D01*
G01X219969Y220412D02*
X219958Y220138D01*
G01X219974Y220429D02*
X219969Y220412D01*
G01X219980Y220365D02*
X219974Y220429D01*
G01X219967Y221390D02*
X219954Y221024D01*
G01X219975Y221412D02*
X219967Y221390D01*
G01X219982Y221327D02*
X219975Y221412D01*
G01X220046Y219853D02*
X220032Y220340D01*
G01X220052Y219464D02*
X220046Y219853D01*
G01X220057Y218993D02*
X220052Y219464D01*
G01X220061Y218453D02*
X220057Y218993D01*
G01X220064Y217857D02*
X220061Y218453D01*
G01X220066Y217224D02*
X220064Y217857D01*
G01X220067Y216570D02*
X220066Y217224D01*
G01X220040Y219013D02*
X220030Y219379D01*
G01X220045Y218722D02*
X220040Y219013D01*
G01X220049Y218368D02*
X220045Y218722D01*
G01X220052Y217963D02*
X220049Y218368D01*
G01X220054Y217516D02*
X220052Y217963D01*
G01X220055Y217041D02*
X220054Y217516D01*
G01X220056Y216551D02*
X220055Y217041D01*
G01X217754Y225965D02*
X217765Y226239D01*
G01X217749Y225948D02*
X217754Y225965D01*
G01X217743Y226012D02*
X217749Y225948D01*
G01X217756Y224988D02*
X217770Y225353D01*
G01X217748Y224965D02*
X217756Y224988D01*
G01X217741Y225050D02*
X217748Y224965D01*
G01X217677Y226524D02*
X217691Y226037D01*
G01X217671Y226913D02*
X217677Y226524D01*
G01X217666Y227384D02*
X217671Y226913D01*
G01X217662Y227925D02*
X217666Y227384D01*
G01X217659Y228520D02*
X217662Y227925D01*
G01X217657Y229153D02*
X217659Y228520D01*
G01X217656Y229807D02*
X217657Y229153D01*
G01X217651Y231677D02*
X217643Y231750D01*
G01X217655Y231547D02*
X217651Y231677D01*
G01X217658Y231359D02*
X217655Y231547D01*
G01X217661Y231120D02*
X217658Y231359D01*
G01X217664Y230838D02*
X217661Y231120D01*
G01X217665Y230521D02*
X217664Y230838D01*
G01X217667Y230180D02*
X217665Y230521D01*
G01X217667Y229826D02*
Y230180D01*
G01X217683Y227364D02*
X217693Y226999D01*
G01X217678Y227656D02*
X217683Y227364D01*
G01X217675Y228009D02*
X217678Y227656D01*
G01X217671Y228414D02*
X217675Y228009D01*
G01X217669Y228861D02*
X217671Y228414D01*
G01X217668Y229336D02*
X217669Y228861D01*
G01X217667Y229826D02*
X217668Y229336D01*
G01X216036Y225965D02*
X216047Y226012D01*
G01X216031Y226063D02*
X216036Y225965D01*
G01X216026Y226239D02*
X216031Y226063D01*
G01X216122Y228861D02*
X216124Y229826D01*
G01X216119Y228414D02*
X216122Y228861D01*
G01X216116Y228009D02*
X216119Y228414D01*
G01X216112Y227656D02*
X216116Y228009D01*
G01X216108Y227364D02*
X216112Y227656D01*
G01X216103Y227143D02*
X216108Y227364D01*
G01X216098Y226999D02*
X216103Y227143D01*
G01X216125Y230521D02*
X216124Y229826D01*
G01X216127Y230838D02*
X216125Y230521D01*
G01X216130Y231120D02*
X216127Y230838D01*
G01X216132Y231359D02*
X216130Y231120D01*
G01X216136Y231547D02*
X216132Y231359D01*
G01X216140Y231677D02*
X216136Y231547D01*
G01X216143Y231746D02*
X216140Y231677D01*
G01X216147Y231750D02*
X216143Y231746D01*
G01X216132Y228520D02*
X216135Y229807D01*
G01X216129Y227925D02*
X216132Y228520D01*
G01X216125Y227384D02*
X216129Y227925D01*
G01X216120Y226913D02*
X216125Y227384D01*
G01X216114Y226524D02*
X216120Y226913D01*
G01X216107Y226230D02*
X216114Y226524D01*
G01X216100Y226037D02*
X216107Y226230D01*
G01X216035Y224988D02*
X216050Y225050D01*
G01X216028Y225118D02*
X216035Y224988D01*
G01X216021Y225353D02*
X216028Y225118D01*
G01X216027Y220412D02*
X216017Y220138D01*
G01X216033Y220429D02*
X216027Y220412D01*
G01X216038Y220365D02*
X216033Y220429D01*
G01X216026Y221390D02*
X216012Y221024D01*
G01X216033Y221412D02*
X216026Y221390D01*
G01X216040Y221327D02*
X216033Y221412D01*
G01X216104Y219853D02*
X216091Y220340D01*
G01X216110Y219464D02*
X216104Y219853D01*
G01X216115Y218993D02*
X216110Y219464D01*
G01X216120Y218453D02*
X216115Y218993D01*
G01X216123Y217857D02*
X216120Y218453D01*
G01X216125Y217224D02*
X216123Y217857D01*
G01X216125Y216570D02*
Y217224D01*
G01X216130Y214700D02*
X216138Y214627D01*
G01X216126Y214830D02*
X216130Y214700D01*
G01X216123Y215018D02*
X216126Y214830D01*
G01X216120Y215257D02*
X216123Y215018D01*
G01X216118Y215540D02*
X216120Y215257D01*
G01X216116Y215857D02*
X216118Y215540D01*
G01X216115Y216198D02*
X216116Y215857D01*
G01X216114Y216551D02*
X216115Y216198D01*
G01X216099Y219013D02*
X216088Y219379D01*
G01X216103Y218722D02*
X216099Y219013D01*
G01X216107Y218368D02*
X216103Y218722D01*
G01X216110Y217963D02*
X216107Y218368D01*
G01X216112Y217516D02*
X216110Y217963D01*
G01X216114Y217041D02*
X216112Y217516D01*
G01X216114Y216551D02*
Y217041D01*
G01X217745Y220412D02*
X217734Y220365D01*
G01X217750Y220314D02*
X217745Y220412D01*
G01X217755Y220138D02*
X217750Y220314D01*
G01X217660Y217516D02*
X217658Y216551D01*
G01X217662Y217963D02*
X217660Y217516D01*
G01X217665Y218368D02*
X217662Y217963D01*
G01X217669Y218722D02*
X217665Y218368D01*
G01X217673Y219013D02*
X217669Y218722D01*
G01X217678Y219234D02*
X217673Y219013D01*
G01X217684Y219379D02*
X217678Y219234D01*
G01X217656Y215857D02*
X217658Y216551D01*
G01X217654Y215540D02*
X217656Y215857D01*
G01X217652Y215257D02*
X217654Y215540D01*
G01X217649Y215018D02*
X217652Y215257D01*
G01X217646Y214830D02*
X217649Y215018D01*
G01X217642Y214700D02*
X217646Y214830D01*
G01X217638Y214632D02*
X217642Y214700D01*
G01X217634Y214627D02*
X217638Y214632D01*
G01X217649Y217857D02*
X217647Y216570D01*
G01X217653Y218453D02*
X217649Y217857D01*
G01X217657Y218993D02*
X217653Y218453D01*
G01X217662Y219464D02*
X217657Y218993D01*
G01X217668Y219853D02*
X217662Y219464D01*
G01X217674Y220148D02*
X217668Y219853D01*
G01X217681Y220340D02*
X217674Y220148D01*
G01X217746Y221390D02*
X217732Y221327D01*
G01X217753Y221259D02*
X217746Y221390D01*
G01X217760Y221024D02*
X217753Y221259D01*
G01X212095Y225965D02*
X212106Y226012D01*
G01X212089Y226063D02*
X212095Y225965D01*
G01X212084Y226239D02*
X212089Y226063D01*
G01X212180Y228861D02*
X212182Y229826D01*
G01X212178Y228414D02*
X212180Y228861D01*
G01X212175Y228009D02*
X212178Y228414D01*
G01X212171Y227656D02*
X212175Y228009D01*
G01X212166Y227364D02*
X212171Y227656D01*
G01X212161Y227143D02*
X212166Y227364D01*
G01X212156Y226999D02*
X212161Y227143D01*
G01X212190Y228520D02*
X212193Y229807D01*
G01X212187Y227925D02*
X212190Y228520D01*
G01X212183Y227384D02*
X212187Y227925D01*
G01X212178Y226913D02*
X212183Y227384D01*
G01X212172Y226524D02*
X212178Y226913D01*
G01X212165Y226230D02*
X212172Y226524D01*
G01X212158Y226037D02*
X212165Y226230D01*
G01X212093Y224988D02*
X212108Y225050D01*
G01X212086Y225118D02*
X212093Y224988D01*
G01X212080Y225353D02*
X212086Y225118D01*
G01X213813Y225965D02*
X213823Y226239D01*
G01X213807Y225948D02*
X213813Y225965D01*
G01X213802Y226012D02*
X213807Y225948D01*
G01X213814Y224988D02*
X213828Y225353D01*
G01X213807Y224965D02*
X213814Y224988D01*
G01X213799Y225050D02*
X213807Y224965D01*
G01X213735Y226524D02*
X213749Y226037D01*
G01X213730Y226913D02*
X213735Y226524D01*
G01X213724Y227384D02*
X213730Y226913D01*
G01X213720Y227925D02*
X213724Y227384D01*
G01X213717Y228520D02*
X213720Y227925D01*
G01X213715Y229153D02*
X213717Y228520D01*
G01X213714Y229807D02*
X213715Y229153D01*
G01X213741Y227364D02*
X213751Y226999D01*
G01X213737Y227656D02*
X213741Y227364D01*
G01X213733Y228009D02*
X213737Y227656D01*
G01X213730Y228414D02*
X213733Y228009D01*
G01X213727Y228861D02*
X213730Y228414D01*
G01X213726Y229336D02*
X213727Y228861D01*
G01X213725Y229826D02*
X213726Y229336D01*
G01X213813Y220412D02*
X213802Y220365D01*
G01X213818Y220314D02*
X213813Y220412D01*
G01X213823Y220138D02*
X213818Y220314D01*
G01X213727Y217516D02*
X213725Y216551D01*
G01X213730Y217963D02*
X213727Y217516D01*
G01X213733Y218368D02*
X213730Y217963D01*
G01X213737Y218722D02*
X213733Y218368D01*
G01X213741Y219013D02*
X213737Y218722D01*
G01X213746Y219234D02*
X213741Y219013D01*
G01X213751Y219379D02*
X213746Y219234D01*
G01X213717Y217857D02*
X213714Y216570D01*
G01X213720Y218453D02*
X213717Y217857D01*
G01X213724Y218993D02*
X213720Y218453D01*
G01X213730Y219464D02*
X213724Y218993D01*
G01X213735Y219853D02*
X213730Y219464D01*
G01X213742Y220148D02*
X213735Y219853D01*
G01X213749Y220340D02*
X213742Y220148D01*
G01X213814Y221390D02*
X213799Y221327D01*
G01X213821Y221259D02*
X213814Y221390D01*
G01X213828Y221024D02*
X213821Y221259D01*
G01X212095Y220412D02*
X212084Y220138D01*
G01X212100Y220429D02*
X212095Y220412D01*
G01X212106Y220365D02*
X212100Y220429D01*
G01X212093Y221390D02*
X212080Y221024D01*
G01X212101Y221412D02*
X212093Y221390D01*
G01X212108Y221327D02*
X212101Y221412D01*
G01X212172Y219853D02*
X212158Y220340D01*
G01X212178Y219464D02*
X212172Y219853D01*
G01X212183Y218993D02*
X212178Y219464D01*
G01X212187Y218453D02*
X212183Y218993D01*
G01X212190Y217857D02*
X212187Y218453D01*
G01X212192Y217224D02*
X212190Y217857D01*
G01X212193Y216570D02*
X212192Y217224D01*
G01X212166Y219013D02*
X212156Y219379D01*
G01X212171Y218722D02*
X212166Y219013D01*
G01X212175Y218368D02*
X212171Y218722D01*
G01X212178Y217963D02*
X212175Y218368D01*
G01X212180Y217516D02*
X212178Y217963D01*
G01X212181Y217041D02*
X212180Y217516D01*
G01X212182Y216551D02*
X212181Y217041D01*
G01X209880Y225965D02*
X209891Y226239D01*
G01X209875Y225948D02*
X209880Y225965D01*
G01X209869Y226012D02*
X209875Y225948D01*
G01X209882Y224988D02*
X209896Y225353D01*
G01X209874Y224965D02*
X209882Y224988D01*
G01X209867Y225050D02*
X209874Y224965D01*
G01X209803Y226524D02*
X209817Y226037D01*
G01X209797Y226913D02*
X209803Y226524D01*
G01X209792Y227384D02*
X209797Y226913D01*
G01X209788Y227925D02*
X209792Y227384D01*
G01X209785Y228520D02*
X209788Y227925D01*
G01X209783Y229153D02*
X209785Y228520D01*
G01X209782Y229807D02*
X209783Y229153D01*
G01X209777Y231677D02*
X209769Y231750D01*
G01X209781Y231547D02*
X209777Y231677D01*
G01X209784Y231359D02*
X209781Y231547D01*
G01X209787Y231120D02*
X209784Y231359D01*
G01X209790Y230838D02*
X209787Y231120D01*
G01X209791Y230521D02*
X209790Y230838D01*
G01X209793Y230180D02*
X209791Y230521D01*
G01X209793Y229826D02*
Y230180D01*
G01X209809Y227364D02*
X209819Y226999D01*
G01X209804Y227656D02*
X209809Y227364D01*
G01X209801Y228009D02*
X209804Y227656D01*
G01X209797Y228414D02*
X209801Y228009D01*
G01X209795Y228861D02*
X209797Y228414D01*
G01X209794Y229336D02*
X209795Y228861D01*
G01X209793Y229826D02*
X209794Y229336D01*
G01X208162Y225965D02*
X208173Y226012D01*
G01X208157Y226063D02*
X208162Y225965D01*
G01X208152Y226239D02*
X208157Y226063D01*
G01X208248Y228861D02*
X208250Y229826D01*
G01X208245Y228414D02*
X208248Y228861D01*
G01X208242Y228009D02*
X208245Y228414D01*
G01X208238Y227656D02*
X208242Y228009D01*
G01X208234Y227364D02*
X208238Y227656D01*
G01X208229Y227143D02*
X208234Y227364D01*
G01X208224Y226999D02*
X208229Y227143D01*
G01X208251Y230521D02*
X208250Y229826D01*
G01X208253Y230838D02*
X208251Y230521D01*
G01X208255Y231120D02*
X208253Y230838D01*
G01X208258Y231359D02*
X208255Y231120D01*
G01X208262Y231547D02*
X208258Y231359D01*
G01X208265Y231677D02*
X208262Y231547D01*
G01X208269Y231746D02*
X208265Y231677D01*
G01X208273Y231750D02*
X208269Y231746D01*
G01X208258Y228520D02*
X208261Y229807D01*
G01X208255Y227925D02*
X208258Y228520D01*
G01X208251Y227384D02*
X208255Y227925D01*
G01X208246Y226913D02*
X208251Y227384D01*
G01X208240Y226524D02*
X208246Y226913D01*
G01X208233Y226230D02*
X208240Y226524D01*
G01X208226Y226037D02*
X208233Y226230D01*
G01X208161Y224988D02*
X208176Y225050D01*
G01X208154Y225118D02*
X208161Y224988D01*
G01X208147Y225353D02*
X208154Y225118D01*
G01X208153Y220412D02*
X208143Y220138D01*
G01X208159Y220429D02*
X208153Y220412D01*
G01X208164Y220365D02*
X208159Y220429D01*
G01X208152Y221390D02*
X208138Y221024D01*
G01X208159Y221412D02*
X208152Y221390D01*
G01X208166Y221327D02*
X208159Y221412D01*
G01X208230Y219853D02*
X208217Y220340D01*
G01X208236Y219464D02*
X208230Y219853D01*
G01X208241Y218993D02*
X208236Y219464D01*
G01X208246Y218453D02*
X208241Y218993D01*
G01X208249Y217857D02*
X208246Y218453D01*
G01X208251Y217224D02*
X208249Y217857D01*
G01X208251Y216570D02*
Y217224D01*
G01X208256Y214700D02*
X208264Y214627D01*
G01X208252Y214830D02*
X208256Y214700D01*
G01X208249Y215018D02*
X208252Y214830D01*
G01X208246Y215257D02*
X208249Y215018D01*
G01X208244Y215540D02*
X208246Y215257D01*
G01X208242Y215857D02*
X208244Y215540D01*
G01X208241Y216198D02*
X208242Y215857D01*
G01X208240Y216551D02*
X208241Y216198D01*
G01X208225Y219013D02*
X208214Y219379D01*
G01X208229Y218722D02*
X208225Y219013D01*
G01X208233Y218368D02*
X208229Y218722D01*
G01X208236Y217963D02*
X208233Y218368D01*
G01X208238Y217516D02*
X208236Y217963D01*
G01X208240Y217041D02*
X208238Y217516D01*
G01X208240Y216551D02*
Y217041D01*
G01X209871Y220412D02*
X209860Y220365D01*
G01X209876Y220314D02*
X209871Y220412D01*
G01X209881Y220138D02*
X209876Y220314D01*
G01X209786Y217516D02*
X209784Y216551D01*
G01X209788Y217963D02*
X209786Y217516D01*
G01X209791Y218368D02*
X209788Y217963D01*
G01X209795Y218722D02*
X209791Y218368D01*
G01X209799Y219013D02*
X209795Y218722D01*
G01X209804Y219234D02*
X209799Y219013D01*
G01X209810Y219379D02*
X209804Y219234D01*
G01X209782Y215857D02*
X209784Y216551D01*
G01X209780Y215540D02*
X209782Y215857D01*
G01X209778Y215257D02*
X209780Y215540D01*
G01X209775Y215018D02*
X209778Y215257D01*
G01X209772Y214830D02*
X209775Y215018D01*
G01X209768Y214700D02*
X209772Y214830D01*
G01X209764Y214632D02*
X209768Y214700D01*
G01X209760Y214627D02*
X209764Y214632D01*
G01X209775Y217857D02*
X209773Y216570D01*
G01X209779Y218453D02*
X209775Y217857D01*
G01X209783Y218993D02*
X209779Y218453D01*
G01X209788Y219464D02*
X209783Y218993D01*
G01X209794Y219853D02*
X209788Y219464D01*
G01X209800Y220148D02*
X209794Y219853D01*
G01X209807Y220340D02*
X209800Y220148D01*
G01X209872Y221390D02*
X209858Y221327D01*
G01X209879Y221259D02*
X209872Y221390D01*
G01X209886Y221024D02*
X209879Y221259D01*
G01X204221Y225965D02*
X204232Y226012D01*
G01X204215Y226063D02*
X204221Y225965D01*
G01X204210Y226239D02*
X204215Y226063D01*
G01X204306Y228861D02*
X204308Y229826D01*
G01X204304Y228414D02*
X204306Y228861D01*
G01X204301Y228009D02*
X204304Y228414D01*
G01X204297Y227656D02*
X204301Y228009D01*
G01X204292Y227364D02*
X204297Y227656D01*
G01X204287Y227143D02*
X204292Y227364D01*
G01X204282Y226999D02*
X204287Y227143D01*
G01X204316Y228520D02*
X204319Y229807D01*
G01X204313Y227925D02*
X204316Y228520D01*
G01X204309Y227384D02*
X204313Y227925D01*
G01X204304Y226913D02*
X204309Y227384D01*
G01X204298Y226524D02*
X204304Y226913D01*
G01X204291Y226230D02*
X204298Y226524D01*
G01X204284Y226037D02*
X204291Y226230D01*
G01X204219Y224988D02*
X204234Y225050D01*
G01X204212Y225118D02*
X204219Y224988D01*
G01X204206Y225353D02*
X204212Y225118D01*
G01X205939Y225965D02*
X205949Y226239D01*
G01X205933Y225948D02*
X205939Y225965D01*
G01X205928Y226012D02*
X205933Y225948D01*
G01X205940Y224988D02*
X205954Y225353D01*
G01X205933Y224965D02*
X205940Y224988D01*
G01X205925Y225050D02*
X205933Y224965D01*
G01X205861Y226524D02*
X205875Y226037D01*
G01X205855Y226913D02*
X205861Y226524D01*
G01X205850Y227384D02*
X205855Y226913D01*
G01X205846Y227925D02*
X205850Y227384D01*
G01X205843Y228520D02*
X205846Y227925D01*
G01X205841Y229153D02*
X205843Y228520D01*
G01X205840Y229807D02*
X205841Y229153D01*
G01X205867Y227364D02*
X205877Y226999D01*
G01X205863Y227656D02*
X205867Y227364D01*
G01X205859Y228009D02*
X205863Y227656D01*
G01X205856Y228414D02*
X205859Y228009D01*
G01X205853Y228861D02*
X205856Y228414D01*
G01X205852Y229336D02*
X205853Y228861D01*
G01X205851Y229826D02*
X205852Y229336D01*
G01X205939Y220412D02*
X205928Y220365D01*
G01X205944Y220314D02*
X205939Y220412D01*
G01X205949Y220138D02*
X205944Y220314D01*
G01X205853Y217516D02*
X205851Y216551D01*
G01X205856Y217963D02*
X205853Y217516D01*
G01X205859Y218368D02*
X205856Y217963D01*
G01X205863Y218722D02*
X205859Y218368D01*
G01X205867Y219013D02*
X205863Y218722D01*
G01X205872Y219234D02*
X205867Y219013D01*
G01X205877Y219379D02*
X205872Y219234D01*
G01X205843Y217857D02*
X205840Y216570D01*
G01X205846Y218453D02*
X205843Y217857D01*
G01X205850Y218993D02*
X205846Y218453D01*
G01X205855Y219464D02*
X205850Y218993D01*
G01X205861Y219853D02*
X205855Y219464D01*
G01X205868Y220148D02*
X205861Y219853D01*
G01X205875Y220340D02*
X205868Y220148D01*
G01X205940Y221390D02*
X205925Y221327D01*
G01X205947Y221259D02*
X205940Y221390D01*
G01X205954Y221024D02*
X205947Y221259D01*
G01X204221Y220412D02*
X204210Y220138D01*
G01X204226Y220429D02*
X204221Y220412D01*
G01X204232Y220365D02*
X204226Y220429D01*
G01X204219Y221390D02*
X204206Y221024D01*
G01X204227Y221412D02*
X204219Y221390D01*
G01X204234Y221327D02*
X204227Y221412D01*
G01X204298Y219853D02*
X204284Y220340D01*
G01X204304Y219464D02*
X204298Y219853D01*
G01X204309Y218993D02*
X204304Y219464D01*
G01X204313Y218453D02*
X204309Y218993D01*
G01X204316Y217857D02*
X204313Y218453D01*
G01X204318Y217224D02*
X204316Y217857D01*
G01X204319Y216570D02*
X204318Y217224D01*
G01X204292Y219013D02*
X204282Y219379D01*
G01X204297Y218722D02*
X204292Y219013D01*
G01X204301Y218368D02*
X204297Y218722D01*
G01X204304Y217963D02*
X204301Y218368D01*
G01X204306Y217516D02*
X204304Y217963D01*
G01X204307Y217041D02*
X204306Y217516D01*
G01X204308Y216551D02*
X204307Y217041D01*
G01X202006Y225965D02*
X202017Y226239D01*
G01X202001Y225948D02*
X202006Y225965D01*
G01X201995Y226012D02*
X202001Y225948D01*
G01X202008Y224988D02*
X202022Y225353D01*
G01X202000Y224965D02*
X202008Y224988D01*
G01X201993Y225050D02*
X202000Y224965D01*
G01X201929Y226524D02*
X201943Y226037D01*
G01X201923Y226913D02*
X201929Y226524D01*
G01X201918Y227384D02*
X201923Y226913D01*
G01X201914Y227925D02*
X201918Y227384D01*
G01X201911Y228520D02*
X201914Y227925D01*
G01X201909Y229153D02*
X201911Y228520D01*
G01X201908Y229807D02*
X201909Y229153D01*
G01X201903Y231677D02*
X201895Y231750D01*
G01X201907Y231547D02*
X201903Y231677D01*
G01X201910Y231359D02*
X201907Y231547D01*
G01X201913Y231120D02*
X201910Y231359D01*
G01X201916Y230838D02*
X201913Y231120D01*
G01X201917Y230521D02*
X201916Y230838D01*
G01X201919Y230180D02*
X201917Y230521D01*
G01X201919Y229826D02*
Y230180D01*
G01X201935Y227364D02*
X201945Y226999D01*
G01X201930Y227656D02*
X201935Y227364D01*
G01X201927Y228009D02*
X201930Y227656D01*
G01X201923Y228414D02*
X201927Y228009D01*
G01X201921Y228861D02*
X201923Y228414D01*
G01X201920Y229336D02*
X201921Y228861D01*
G01X201919Y229826D02*
X201920Y229336D01*
G01X200288Y225965D02*
X200299Y226012D01*
G01X200283Y226063D02*
X200288Y225965D01*
G01X200278Y226239D02*
X200283Y226063D01*
G01X200374Y228861D02*
X200376Y229826D01*
G01X200371Y228414D02*
X200374Y228861D01*
G01X200368Y228009D02*
X200371Y228414D01*
G01X200364Y227656D02*
X200368Y228009D01*
G01X200360Y227364D02*
X200364Y227656D01*
G01X200355Y227143D02*
X200360Y227364D01*
G01X200350Y226999D02*
X200355Y227143D01*
G01X200377Y230521D02*
X200376Y229826D01*
G01X200379Y230838D02*
X200377Y230521D01*
G01X200381Y231120D02*
X200379Y230838D01*
G01X200384Y231359D02*
X200381Y231120D01*
G01X200388Y231547D02*
X200384Y231359D01*
G01X200391Y231677D02*
X200388Y231547D01*
G01X200395Y231746D02*
X200391Y231677D01*
G01X200399Y231750D02*
X200395Y231746D01*
G01X200384Y228520D02*
X200387Y229807D01*
G01X200381Y227925D02*
X200384Y228520D01*
G01X200377Y227384D02*
X200381Y227925D01*
G01X200372Y226913D02*
X200377Y227384D01*
G01X200366Y226524D02*
X200372Y226913D01*
G01X200359Y226230D02*
X200366Y226524D01*
G01X200352Y226037D02*
X200359Y226230D01*
G01X200287Y224988D02*
X200302Y225050D01*
G01X200280Y225118D02*
X200287Y224988D01*
G01X200273Y225353D02*
X200280Y225118D01*
G01X200279Y220412D02*
X200269Y220138D01*
G01X200285Y220429D02*
X200279Y220412D01*
G01X200290Y220365D02*
X200285Y220429D01*
G01X200278Y221390D02*
X200264Y221024D01*
G01X200285Y221412D02*
X200278Y221390D01*
G01X200292Y221327D02*
X200285Y221412D01*
G01X200356Y219853D02*
X200343Y220340D01*
G01X200362Y219464D02*
X200356Y219853D01*
G01X200367Y218993D02*
X200362Y219464D01*
G01X200371Y218453D02*
X200367Y218993D01*
G01X200375Y217857D02*
X200371Y218453D01*
G01X200377Y217224D02*
X200375Y217857D01*
G01X200377Y216570D02*
Y217224D01*
G01X200382Y214700D02*
X200390Y214627D01*
G01X200378Y214830D02*
X200382Y214700D01*
G01X200375Y215018D02*
X200378Y214830D01*
G01X200372Y215257D02*
X200375Y215018D01*
G01X200370Y215540D02*
X200372Y215257D01*
G01X200368Y215857D02*
X200370Y215540D01*
G01X200367Y216198D02*
X200368Y215857D01*
G01X200366Y216551D02*
X200367Y216198D01*
G01X200351Y219013D02*
X200340Y219379D01*
G01X200355Y218722D02*
X200351Y219013D01*
G01X200359Y218368D02*
X200355Y218722D01*
G01X200362Y217963D02*
X200359Y218368D01*
G01X200364Y217516D02*
X200362Y217963D01*
G01X200366Y217041D02*
X200364Y217516D01*
G01X200366Y216551D02*
Y217041D01*
G01X201997Y220412D02*
X201986Y220365D01*
G01X202002Y220314D02*
X201997Y220412D01*
G01X202007Y220138D02*
X202002Y220314D01*
G01X201912Y217516D02*
X201910Y216551D01*
G01X201914Y217963D02*
X201912Y217516D01*
G01X201917Y218368D02*
X201914Y217963D01*
G01X201921Y218722D02*
X201917Y218368D01*
G01X201925Y219013D02*
X201921Y218722D01*
G01X201930Y219234D02*
X201925Y219013D01*
G01X201936Y219379D02*
X201930Y219234D01*
G01X201908Y215857D02*
X201910Y216551D01*
G01X201906Y215540D02*
X201908Y215857D01*
G01X201904Y215257D02*
X201906Y215540D01*
G01X201901Y215018D02*
X201904Y215257D01*
G01X201898Y214830D02*
X201901Y215018D01*
G01X201894Y214700D02*
X201898Y214830D01*
G01X201890Y214632D02*
X201894Y214700D01*
G01X201886Y214627D02*
X201890Y214632D01*
G01X201901Y217857D02*
X201899Y216570D01*
G01X201905Y218453D02*
X201901Y217857D01*
G01X201909Y218993D02*
X201905Y218453D01*
G01X201914Y219464D02*
X201909Y218993D01*
G01X201920Y219853D02*
X201914Y219464D01*
G01X201926Y220148D02*
X201920Y219853D01*
G01X201933Y220340D02*
X201926Y220148D01*
G01X201998Y221390D02*
X201984Y221327D01*
G01X202005Y221259D02*
X201998Y221390D01*
G01X202012Y221024D02*
X202005Y221259D01*
G01X196347Y225965D02*
X196358Y226012D01*
G01X196341Y226063D02*
X196347Y225965D01*
G01X196336Y226239D02*
X196341Y226063D01*
G01X196432Y228861D02*
X196434Y229826D01*
G01X196430Y228414D02*
X196432Y228861D01*
G01X196427Y228009D02*
X196430Y228414D01*
G01X196423Y227656D02*
X196427Y228009D01*
G01X196418Y227364D02*
X196423Y227656D01*
G01X196413Y227143D02*
X196418Y227364D01*
G01X196408Y226999D02*
X196413Y227143D01*
G01X196442Y228520D02*
X196445Y229807D01*
G01X196439Y227925D02*
X196442Y228520D01*
G01X196435Y227384D02*
X196439Y227925D01*
G01X196430Y226913D02*
X196435Y227384D01*
G01X196424Y226524D02*
X196430Y226913D01*
G01X196417Y226230D02*
X196424Y226524D01*
G01X196410Y226037D02*
X196417Y226230D01*
G01X196345Y224988D02*
X196360Y225050D01*
G01X196338Y225118D02*
X196345Y224988D01*
G01X196331Y225353D02*
X196338Y225118D01*
G01X198065Y225965D02*
X198075Y226239D01*
G01X198059Y225948D02*
X198065Y225965D01*
G01X198054Y226012D02*
X198059Y225948D01*
G01X198066Y224988D02*
X198080Y225353D01*
G01X198059Y224965D02*
X198066Y224988D01*
G01X198051Y225050D02*
X198059Y224965D01*
G01X197987Y226524D02*
X198001Y226037D01*
G01X197981Y226913D02*
X197987Y226524D01*
G01X197976Y227384D02*
X197981Y226913D01*
G01X197972Y227925D02*
X197976Y227384D01*
G01X197969Y228520D02*
X197972Y227925D01*
G01X197967Y229153D02*
X197969Y228520D01*
G01X197966Y229807D02*
X197967Y229153D01*
G01X197993Y227364D02*
X198003Y226999D01*
G01X197989Y227656D02*
X197993Y227364D01*
G01X197985Y228009D02*
X197989Y227656D01*
G01X197982Y228414D02*
X197985Y228009D01*
G01X197979Y228861D02*
X197982Y228414D01*
G01X197978Y229336D02*
X197979Y228861D01*
G01X197977Y229826D02*
X197978Y229336D01*
G01X198065Y220412D02*
X198054Y220365D01*
G01X198070Y220314D02*
X198065Y220412D01*
G01X198075Y220138D02*
X198070Y220314D01*
G01X197979Y217516D02*
X197977Y216551D01*
G01X197982Y217963D02*
X197979Y217516D01*
G01X197985Y218368D02*
X197982Y217963D01*
G01X197989Y218722D02*
X197985Y218368D01*
G01X197993Y219013D02*
X197989Y218722D01*
G01X197998Y219234D02*
X197993Y219013D01*
G01X198003Y219379D02*
X197998Y219234D01*
G01X197969Y217857D02*
X197966Y216570D01*
G01X197972Y218453D02*
X197969Y217857D01*
G01X197976Y218993D02*
X197972Y218453D01*
G01X197981Y219464D02*
X197976Y218993D01*
G01X197987Y219853D02*
X197981Y219464D01*
G01X197994Y220148D02*
X197987Y219853D01*
G01X198001Y220340D02*
X197994Y220148D01*
G01X198066Y221390D02*
X198051Y221327D01*
G01X198073Y221259D02*
X198066Y221390D01*
G01X198080Y221024D02*
X198073Y221259D01*
G01X196347Y220412D02*
X196336Y220138D01*
G01X196352Y220429D02*
X196347Y220412D01*
G01X196358Y220365D02*
X196352Y220429D01*
G01X196345Y221390D02*
X196331Y221024D01*
G01X196353Y221412D02*
X196345Y221390D01*
G01X196360Y221327D02*
X196353Y221412D01*
G01X196424Y219853D02*
X196410Y220340D01*
G01X196430Y219464D02*
X196424Y219853D01*
G01X196435Y218993D02*
X196430Y219464D01*
G01X196439Y218453D02*
X196435Y218993D01*
G01X196442Y217857D02*
X196439Y218453D01*
G01X196444Y217224D02*
X196442Y217857D01*
G01X196445Y216570D02*
X196444Y217224D01*
G01X196418Y219013D02*
X196408Y219379D01*
G01X196423Y218722D02*
X196418Y219013D01*
G01X196427Y218368D02*
X196423Y218722D01*
G01X196430Y217963D02*
X196427Y218368D01*
G01X196432Y217516D02*
X196430Y217963D01*
G01X196433Y217041D02*
X196432Y217516D01*
G01X196434Y216551D02*
X196433Y217041D01*
G01X194132Y225965D02*
X194143Y226239D01*
G01X194127Y225948D02*
X194132Y225965D01*
G01X194121Y226012D02*
X194127Y225948D01*
G01X194134Y224988D02*
X194148Y225353D01*
G01X194126Y224965D02*
X194134Y224988D01*
G01X194119Y225050D02*
X194126Y224965D01*
G01X194055Y226524D02*
X194069Y226037D01*
G01X194049Y226913D02*
X194055Y226524D01*
G01X194044Y227384D02*
X194049Y226913D01*
G01X194040Y227925D02*
X194044Y227384D01*
G01X194037Y228520D02*
X194040Y227925D01*
G01X194035Y229153D02*
X194037Y228520D01*
G01X194034Y229807D02*
X194035Y229153D01*
G01X194029Y231677D02*
X194021Y231750D01*
G01X194033Y231547D02*
X194029Y231677D01*
G01X194036Y231359D02*
X194033Y231547D01*
G01X194039Y231120D02*
X194036Y231359D01*
G01X194042Y230838D02*
X194039Y231120D01*
G01X194043Y230521D02*
X194042Y230838D01*
G01X194045Y230180D02*
X194043Y230521D01*
G01X194045Y229826D02*
Y230180D01*
G01X194061Y227364D02*
X194071Y226999D01*
G01X194056Y227656D02*
X194061Y227364D01*
G01X194053Y228009D02*
X194056Y227656D01*
G01X194049Y228414D02*
X194053Y228009D01*
G01X194047Y228861D02*
X194049Y228414D01*
G01X194046Y229336D02*
X194047Y228861D01*
G01X194045Y229826D02*
X194046Y229336D01*
G01X192414Y225965D02*
X192425Y226012D01*
G01X192409Y226063D02*
X192414Y225965D01*
G01X192404Y226239D02*
X192409Y226063D01*
G01X192500Y228861D02*
X192502Y229826D01*
G01X192497Y228414D02*
X192500Y228861D01*
G01X192494Y228009D02*
X192497Y228414D01*
G01X192490Y227656D02*
X192494Y228009D01*
G01X192486Y227364D02*
X192490Y227656D01*
G01X192481Y227143D02*
X192486Y227364D01*
G01X192476Y226999D02*
X192481Y227143D01*
G01X192503Y230521D02*
X192502Y229826D01*
G01X192505Y230838D02*
X192503Y230521D01*
G01X192507Y231120D02*
X192505Y230838D01*
G01X192510Y231359D02*
X192507Y231120D01*
G01X192514Y231547D02*
X192510Y231359D01*
G01X192517Y231677D02*
X192514Y231547D01*
G01X192521Y231746D02*
X192517Y231677D01*
G01X192525Y231750D02*
X192521Y231746D01*
G01X192510Y228520D02*
X192513Y229807D01*
G01X192507Y227925D02*
X192510Y228520D01*
G01X192503Y227384D02*
X192507Y227925D01*
G01X192498Y226913D02*
X192503Y227384D01*
G01X192492Y226524D02*
X192498Y226913D01*
G01X192485Y226230D02*
X192492Y226524D01*
G01X192478Y226037D02*
X192485Y226230D01*
G01X192413Y224988D02*
X192428Y225050D01*
G01X192406Y225118D02*
X192413Y224988D01*
G01X192399Y225353D02*
X192406Y225118D01*
G01X192405Y220412D02*
X192395Y220138D01*
G01X192411Y220429D02*
X192405Y220412D01*
G01X192416Y220365D02*
X192411Y220429D01*
G01X192404Y221390D02*
X192390Y221024D01*
G01X192411Y221412D02*
X192404Y221390D01*
G01X192418Y221327D02*
X192411Y221412D01*
G01X192482Y219853D02*
X192469Y220340D01*
G01X192488Y219464D02*
X192482Y219853D01*
G01X192493Y218993D02*
X192488Y219464D01*
G01X192497Y218453D02*
X192493Y218993D01*
G01X192501Y217857D02*
X192497Y218453D01*
G01X192503Y217224D02*
X192501Y217857D01*
G01X192503Y216570D02*
Y217224D01*
G01X192508Y214700D02*
X192516Y214627D01*
G01X192504Y214830D02*
X192508Y214700D01*
G01X192501Y215018D02*
X192504Y214830D01*
G01X192498Y215257D02*
X192501Y215018D01*
G01X192496Y215540D02*
X192498Y215257D01*
G01X192494Y215857D02*
X192496Y215540D01*
G01X192493Y216198D02*
X192494Y215857D01*
G01X192492Y216551D02*
X192493Y216198D01*
G01X192477Y219013D02*
X192466Y219379D01*
G01X192481Y218722D02*
X192477Y219013D01*
G01X192485Y218368D02*
X192481Y218722D01*
G01X192488Y217963D02*
X192485Y218368D01*
G01X192490Y217516D02*
X192488Y217963D01*
G01X192492Y217041D02*
X192490Y217516D01*
G01X192492Y216551D02*
Y217041D01*
G01X194123Y220412D02*
X194112Y220365D01*
G01X194128Y220314D02*
X194123Y220412D01*
G01X194133Y220138D02*
X194128Y220314D01*
G01X194038Y217516D02*
X194036Y216551D01*
G01X194040Y217963D02*
X194038Y217516D01*
G01X194043Y218368D02*
X194040Y217963D01*
G01X194047Y218722D02*
X194043Y218368D01*
G01X194051Y219013D02*
X194047Y218722D01*
G01X194056Y219234D02*
X194051Y219013D01*
G01X194062Y219379D02*
X194056Y219234D01*
G01X194034Y215857D02*
X194036Y216551D01*
G01X194032Y215540D02*
X194034Y215857D01*
G01X194030Y215257D02*
X194032Y215540D01*
G01X194027Y215018D02*
X194030Y215257D01*
G01X194024Y214830D02*
X194027Y215018D01*
G01X194020Y214700D02*
X194024Y214830D01*
G01X194016Y214632D02*
X194020Y214700D01*
G01X194012Y214627D02*
X194016Y214632D01*
G01X194027Y217857D02*
X194025Y216570D01*
G01X194031Y218453D02*
X194027Y217857D01*
G01X194035Y218993D02*
X194031Y218453D01*
G01X194040Y219464D02*
X194035Y218993D01*
G01X194046Y219853D02*
X194040Y219464D01*
G01X194052Y220148D02*
X194046Y219853D01*
G01X194059Y220340D02*
X194052Y220148D01*
G01X194124Y221390D02*
X194110Y221327D01*
G01X194131Y221259D02*
X194124Y221390D01*
G01X194138Y221024D02*
X194131Y221259D01*
G01X188473Y225965D02*
X188484Y226012D01*
G01X188467Y226063D02*
X188473Y225965D01*
G01X188462Y226239D02*
X188467Y226063D01*
G01X188558Y228861D02*
X188560Y229826D01*
G01X188556Y228414D02*
X188558Y228861D01*
G01X188553Y228009D02*
X188556Y228414D01*
G01X188549Y227656D02*
X188553Y228009D01*
G01X188544Y227364D02*
X188549Y227656D01*
G01X188539Y227143D02*
X188544Y227364D01*
G01X188534Y226999D02*
X188539Y227143D01*
G01X188568Y228520D02*
X188571Y229807D01*
G01X188565Y227925D02*
X188568Y228520D01*
G01X188561Y227384D02*
X188565Y227925D01*
G01X188556Y226913D02*
X188561Y227384D01*
G01X188550Y226524D02*
X188556Y226913D01*
G01X188543Y226230D02*
X188550Y226524D01*
G01X188536Y226037D02*
X188543Y226230D01*
G01X188471Y224988D02*
X188486Y225050D01*
G01X188464Y225118D02*
X188471Y224988D01*
G01X188457Y225353D02*
X188464Y225118D01*
G01X190192Y224988D02*
X190206Y225353D01*
G01X190185Y224965D02*
X190192Y224988D01*
G01X190177Y225050D02*
X190185Y224965D01*
G01X190113Y226524D02*
X190127Y226037D01*
G01X190107Y226913D02*
X190113Y226524D01*
G01X190102Y227384D02*
X190107Y226913D01*
G01X190098Y227925D02*
X190102Y227384D01*
G01X190095Y228520D02*
X190098Y227925D01*
G01X190093Y229153D02*
X190095Y228520D01*
G01X190092Y229807D02*
X190093Y229153D01*
G01X190119Y227364D02*
X190129Y226999D01*
G01X190115Y227656D02*
X190119Y227364D01*
G01X190111Y228009D02*
X190115Y227656D01*
G01X190108Y228414D02*
X190111Y228009D01*
G01X190105Y228861D02*
X190108Y228414D01*
G01X190104Y229336D02*
X190105Y228861D01*
G01X190103Y229826D02*
X190104Y229336D01*
G01X190191Y225965D02*
X190201Y226239D01*
G01X190185Y225948D02*
X190191Y225965D01*
G01X190180Y226012D02*
X190185Y225948D01*
G01X190191Y220412D02*
X190180Y220365D01*
G01X190196Y220314D02*
X190191Y220412D01*
G01X190201Y220138D02*
X190196Y220314D01*
G01X190105Y217516D02*
X190103Y216551D01*
G01X190108Y217963D02*
X190105Y217516D01*
G01X190111Y218368D02*
X190108Y217963D01*
G01X190115Y218722D02*
X190111Y218368D01*
G01X190119Y219013D02*
X190115Y218722D01*
G01X190124Y219234D02*
X190119Y219013D01*
G01X190129Y219379D02*
X190124Y219234D01*
G01X190095Y217857D02*
X190092Y216570D01*
G01X190098Y218453D02*
X190095Y217857D01*
G01X190102Y218993D02*
X190098Y218453D01*
G01X190107Y219464D02*
X190102Y218993D01*
G01X190113Y219853D02*
X190107Y219464D01*
G01X190120Y220148D02*
X190113Y219853D01*
G01X190127Y220340D02*
X190120Y220148D01*
G01X190192Y221390D02*
X190177Y221327D01*
G01X190199Y221259D02*
X190192Y221390D01*
G01X190206Y221024D02*
X190199Y221259D01*
G01X188471Y221390D02*
X188457Y221024D01*
G01X188479Y221412D02*
X188471Y221390D01*
G01X188486Y221327D02*
X188479Y221412D01*
G01X188550Y219853D02*
X188536Y220340D01*
G01X188556Y219464D02*
X188550Y219853D01*
G01X188561Y218993D02*
X188556Y219464D01*
G01X188565Y218453D02*
X188561Y218993D01*
G01X188568Y217857D02*
X188565Y218453D01*
G01X188570Y217224D02*
X188568Y217857D01*
G01X188571Y216570D02*
X188570Y217224D01*
G01X188544Y219013D02*
X188534Y219379D01*
G01X188549Y218722D02*
X188544Y219013D01*
G01X188553Y218368D02*
X188549Y218722D01*
G01X188556Y217963D02*
X188553Y218368D01*
G01X188558Y217516D02*
X188556Y217963D01*
G01X188559Y217041D02*
X188558Y217516D01*
G01X188560Y216551D02*
X188559Y217041D01*
G01X188473Y220412D02*
X188462Y220138D01*
G01X188478Y220429D02*
X188473Y220412D01*
G01X188484Y220365D02*
X188478Y220429D01*
G01X190080Y231754D02*
Y231750D01*
G01X190081Y231756D02*
X190080Y231754D01*
G01X197954D02*
Y231750D01*
G01X197955Y231756D02*
X197954Y231754D01*
G01Y230768D02*
Y230762D01*
G01X197955Y230771D02*
X197954Y230768D01*
G01X197955Y230772D02*
Y230771D01*
G01X196457Y215610D02*
Y215615D01*
G01X196456Y215606D02*
X196457Y215610D01*
G01X196456Y215605D02*
Y215606D01*
G01X205828Y230768D02*
Y230762D01*
G01X205829Y230771D02*
X205828Y230768D01*
G01X205829Y230772D02*
Y230771D01*
G01X188583Y214624D02*
X188584Y214627D01*
G01X188583Y214622D02*
Y214624D01*
G01X188582Y214621D02*
X188583Y214622D01*
G01X205828Y231754D02*
Y231750D01*
G01X205829Y231756D02*
X205828Y231754D01*
G01X196457Y214624D02*
X196458Y214627D01*
G01X196457Y214622D02*
Y214624D01*
G01X196456Y214621D02*
X196457Y214622D01*
G01X213702Y231754D02*
Y231750D01*
G01X213703Y231756D02*
X213702Y231754D01*
G01X204331Y214624D02*
X204332Y214627D01*
G01X204331Y214622D02*
Y214624D01*
G01X204330Y214621D02*
X204331Y214622D01*
G01X221576Y231754D02*
Y231750D01*
G01X221577Y231756D02*
X221576Y231754D01*
G01X212205Y214624D02*
X212206Y214627D01*
G01X212205Y214622D02*
Y214624D01*
G01X212204Y214621D02*
X212205Y214622D01*
G01X229450Y231754D02*
Y231750D01*
G01X229451Y231756D02*
X229450Y231754D01*
G01X188562Y230573D02*
X188560Y229826D01*
G01X188567Y231193D02*
X188562Y230573D01*
G01X188574Y231608D02*
X188567Y231193D01*
G01X188582Y231756D02*
X188574Y231608D01*
G01X190102Y215804D02*
X190103Y216551D01*
G01X190097Y215184D02*
X190102Y215804D01*
G01X190090Y214770D02*
X190097Y215184D01*
G01X190081Y214621D02*
X190090Y214770D01*
G01X188582Y215606D02*
Y215605D01*
G01X188583Y215610D02*
X188582Y215606D01*
G01X188584Y215617D02*
X188583Y215610D01*
G01X190081Y230771D02*
Y230772D01*
G01X190080Y230768D02*
X190081Y230771D01*
G01X190080Y230760D02*
Y230768D01*
G01X188317Y214965D02*
X188321Y215117D01*
G01X188313Y214866D02*
X188317Y214965D01*
G01X188308Y214824D02*
X188313Y214866D01*
G01X190346Y231413D02*
X190342Y231260D01*
G01X190351Y231511D02*
X190346Y231413D01*
G01X190355Y231553D02*
X190351Y231511D01*
G01X192249Y214965D02*
X192254Y215117D01*
G01X192245Y214866D02*
X192249Y214965D01*
G01X192240Y214824D02*
X192245Y214866D01*
G01X194288Y231413D02*
X194284Y231260D01*
G01X194292Y231511D02*
X194288Y231413D01*
G01X194297Y231553D02*
X194292Y231511D01*
G01X196191Y214965D02*
X196195Y215117D01*
G01X196187Y214866D02*
X196191Y214965D01*
G01X196182Y214824D02*
X196187Y214866D01*
G01X198220Y231413D02*
X198216Y231260D01*
G01X198225Y231511D02*
X198220Y231413D01*
G01X198229Y231553D02*
X198225Y231511D01*
G01X190343Y232353D02*
X190337Y232147D01*
G01X190349Y232484D02*
X190343Y232353D01*
G01X190355Y232538D02*
X190349Y232484D01*
G01X188320Y214024D02*
X188326Y214231D01*
G01X188314Y213893D02*
X188320Y214024D01*
G01X188308Y213840D02*
X188314Y213893D01*
G01X194285Y232353D02*
X194279Y232147D01*
G01X194291Y232484D02*
X194285Y232353D01*
G01X194297Y232538D02*
X194291Y232484D01*
G01X192253Y214024D02*
X192258Y214231D01*
G01X192247Y213893D02*
X192253Y214024D01*
G01X192240Y213840D02*
X192247Y213893D01*
G01X198217Y232353D02*
X198211Y232147D01*
G01X198223Y232484D02*
X198217Y232353D01*
G01X198229Y232538D02*
X198223Y232484D01*
G01X196194Y214024D02*
X196200Y214231D01*
G01X196188Y213893D02*
X196194Y214024D01*
G01X196182Y213840D02*
X196188Y213893D01*
G01X192514Y230209D02*
X192513Y229807D01*
G01X192516Y230537D02*
X192514Y230209D01*
G01X192521Y230733D02*
X192516Y230537D01*
G01X192525Y230762D02*
X192521Y230733D01*
G01X194024Y216168D02*
X194025Y216570D01*
G01X194021Y215841D02*
X194024Y216168D01*
G01X194017Y215645D02*
X194021Y215841D01*
G01X194012Y215615D02*
X194017Y215645D01*
G01X200388Y230209D02*
X200387Y229807D01*
G01X200391Y230537D02*
X200388Y230209D01*
G01X200395Y230733D02*
X200391Y230537D01*
G01X200399Y230762D02*
X200395Y230733D01*
G01X201898Y216168D02*
X201899Y216570D01*
G01X201895Y215841D02*
X201898Y216168D01*
G01X201891Y215645D02*
X201895Y215841D01*
G01X201886Y215615D02*
X201891Y215645D01*
G01X204331Y215610D02*
Y215615D01*
G01X204330Y215606D02*
X204331Y215610D01*
G01X204330Y215605D02*
Y215606D01*
G01X213702Y230768D02*
Y230762D01*
G01X213703Y230771D02*
X213702Y230768D01*
G01X213703Y230772D02*
Y230771D01*
G01X212205Y215610D02*
Y215615D01*
G01X212204Y215606D02*
X212205Y215610D01*
G01X212204Y215605D02*
Y215606D01*
G01X221576Y230768D02*
Y230762D01*
G01X221577Y230771D02*
X221576Y230768D01*
G01X221577Y230772D02*
Y230771D01*
G01X220079Y215610D02*
X220080Y215615D01*
G01X220079Y215606D02*
Y215610D01*
G01X220078Y215605D02*
X220079Y215606D01*
G01X229450Y230768D02*
Y230762D01*
G01X229451Y230771D02*
X229450Y230768D01*
G01X229451Y230772D02*
Y230771D01*
G01X227953Y215610D02*
X227954Y215615D01*
G01X227953Y215606D02*
Y215610D01*
G01X227952Y215605D02*
X227953Y215606D01*
G01X237324Y230768D02*
Y230762D01*
G01X237325Y230771D02*
X237324Y230768D01*
G01X237325Y230772D02*
Y230771D01*
G01X220079Y214624D02*
X220080Y214627D01*
G01X220079Y214622D02*
Y214624D01*
G01X220078Y214621D02*
X220079Y214622D01*
G01X237324Y231754D02*
Y231750D01*
G01X237325Y231756D02*
X237324Y231754D01*
G01X227953Y214624D02*
X227954Y214627D01*
G01X227953Y214622D02*
Y214624D01*
G01X227952Y214621D02*
X227953Y214622D01*
G01X245198Y231754D02*
Y231750D01*
G01X245199Y231756D02*
X245198Y231754D01*
G01X245200Y231756D02*
X245199D01*
G01X235827Y214624D02*
X235828Y214627D01*
G01X235827Y214622D02*
Y214624D01*
G01X235826Y214621D02*
X235827Y214622D01*
G01X253072Y231754D02*
Y231750D01*
G01X253073Y231756D02*
X253072Y231754D01*
G01X253074Y231756D02*
X253073D01*
G01X243701Y214624D02*
X243702Y214627D01*
G01X243701Y214622D02*
Y214624D01*
G01X243700Y214621D02*
X243701Y214622D01*
G01X260946Y231754D02*
Y231750D01*
G01X260947Y231756D02*
X260946Y231754D01*
G01X260948Y231756D02*
X260947D01*
G01X188572Y216197D02*
X188571Y216570D01*
G01X188574Y215887D02*
X188572Y216197D01*
G01X188578Y215680D02*
X188574Y215887D01*
G01X188582Y215605D02*
X188578Y215680D01*
G01X190091Y230180D02*
X190092Y229807D01*
G01X190089Y230490D02*
X190091Y230180D01*
G01X190086Y230698D02*
X190089Y230490D01*
G01X190081Y230772D02*
X190086Y230698D01*
G01X188314Y232484D02*
X188308Y232538D01*
G01X188320Y232353D02*
X188314Y232484D01*
G01X188326Y232147D02*
X188320Y232353D01*
G01X190349Y213893D02*
X190355Y213840D01*
G01X190343Y214024D02*
X190349Y213893D01*
G01X190337Y214231D02*
X190343Y214024D01*
G01X192256Y232484D02*
X192250Y232538D01*
G01X192262Y232353D02*
X192256Y232484D01*
G01X192268Y232147D02*
X192262Y232353D01*
G01X194281Y213893D02*
X194288Y213840D01*
G01X194275Y214024D02*
X194281Y213893D01*
G01X194270Y214231D02*
X194275Y214024D01*
G01X196188Y232484D02*
X196182Y232538D01*
G01X196194Y232353D02*
X196188Y232484D01*
G01X196200Y232147D02*
X196194Y232353D01*
G01X198223Y213893D02*
X198229Y213840D01*
G01X198217Y214024D02*
X198223Y213893D01*
G01X198211Y214231D02*
X198217Y214024D01*
G01X200130Y232484D02*
X200124Y232538D01*
G01X200136Y232353D02*
X200130Y232484D01*
G01X200142Y232147D02*
X200136Y232353D01*
G01X202155Y213893D02*
X202162Y213840D01*
G01X202149Y214024D02*
X202155Y213893D01*
G01X202144Y214231D02*
X202149Y214024D01*
G01X204062Y232484D02*
X204056Y232538D01*
G01X204068Y232353D02*
X204062Y232484D01*
G01X204074Y232147D02*
X204068Y232353D01*
G01X188313Y231511D02*
X188308Y231553D01*
G01X188317Y231413D02*
X188313Y231511D01*
G01X188321Y231260D02*
X188317Y231413D01*
G01X190351Y214866D02*
X190355Y214824D01*
G01X190346Y214965D02*
X190351Y214866D01*
G01X190342Y215117D02*
X190346Y214965D01*
G01X192254Y231511D02*
X192250Y231553D01*
G01X192259Y231413D02*
X192254Y231511D01*
G01X192263Y231260D02*
X192259Y231413D01*
G01X194283Y214866D02*
X194288Y214824D01*
G01X194279Y214965D02*
X194283Y214866D01*
G01X194274Y215117D02*
X194279Y214965D01*
G01X196187Y231511D02*
X196182Y231553D01*
G01X196191Y231413D02*
X196187Y231511D01*
G01X196195Y231260D02*
X196191Y231413D01*
G01X198225Y214866D02*
X198229Y214824D01*
G01X198220Y214965D02*
X198225Y214866D01*
G01X198216Y215117D02*
X198220Y214965D01*
G01X200128Y231511D02*
X200124Y231553D01*
G01X200133Y231413D02*
X200128Y231511D01*
G01X200137Y231260D02*
X200133Y231413D01*
G01X202157Y214866D02*
X202162Y214824D01*
G01X202153Y214965D02*
X202157Y214866D01*
G01X202148Y215117D02*
X202153Y214965D01*
G01X204061Y231511D02*
X204056Y231553D01*
G01X204065Y231413D02*
X204061Y231511D01*
G01X204069Y231260D02*
X204065Y231413D01*
G01X192511Y215645D02*
X192516Y215615D01*
G01X192507Y215841D02*
X192511Y215645D01*
G01X192504Y216168D02*
X192507Y215841D01*
G01X192503Y216570D02*
X192504Y216168D01*
G01X194026Y230733D02*
X194022Y230762D01*
G01X194030Y230537D02*
X194026Y230733D01*
G01X194033Y230209D02*
X194030Y230537D01*
G01X194034Y229807D02*
X194033Y230209D01*
G01X200385Y215645D02*
X200390Y215615D01*
G01X200381Y215841D02*
X200385Y215645D01*
G01X200378Y216168D02*
X200381Y215841D01*
G01X200377Y216570D02*
X200378Y216168D01*
G01X201900Y230733D02*
X201896Y230762D01*
G01X201904Y230537D02*
X201900Y230733D01*
G01X201907Y230209D02*
X201904Y230537D01*
G01X201908Y229807D02*
X201907Y230209D01*
G01X188574Y214770D02*
X188582Y214621D01*
G01X188567Y215184D02*
X188574Y214770D01*
G01X188562Y215804D02*
X188567Y215184D01*
G01X188560Y216551D02*
X188562Y215804D01*
G01X190090Y231608D02*
X190081Y231756D01*
G01X190097Y231193D02*
X190090Y231608D01*
G01X190102Y230573D02*
X190097Y231193D01*
G01X190103Y229826D02*
X190102Y230573D01*
G01X196448Y214770D02*
X196456Y214621D01*
G01X196441Y215184D02*
X196448Y214770D01*
G01X196436Y215804D02*
X196441Y215184D01*
G01X196434Y216551D02*
X196436Y215804D01*
G01X196452Y215678D02*
X196456Y215605D01*
G01X196448Y215887D02*
X196452Y215678D01*
G01X196446Y216200D02*
X196448Y215887D01*
G01X196445Y216570D02*
X196446Y216200D01*
G01X197960Y230699D02*
X197955Y230772D01*
G01X197963Y230490D02*
X197960Y230699D01*
G01X197965Y230178D02*
X197963Y230490D01*
G01X197966Y229807D02*
X197965Y230178D01*
G01X197964Y231608D02*
X197955Y231756D01*
G01X197971Y231193D02*
X197964Y231608D01*
G01X197976Y230573D02*
X197971Y231193D01*
G01X197977Y229826D02*
X197976Y230573D01*
G01X204322Y214770D02*
X204330Y214621D01*
G01X204315Y215184D02*
X204322Y214770D01*
G01X204310Y215804D02*
X204315Y215184D01*
G01X204308Y216551D02*
X204310Y215804D01*
G01X204326Y215678D02*
X204330Y215605D01*
G01X204322Y215887D02*
X204326Y215678D01*
G01X204320Y216200D02*
X204322Y215887D01*
G01X204319Y216570D02*
X204320Y216200D01*
G01X205834Y230699D02*
X205829Y230772D01*
G01X205837Y230490D02*
X205834Y230699D01*
G01X205840Y230178D02*
X205837Y230490D01*
G01X205840Y229807D02*
Y230178D01*
G01X205838Y231608D02*
X205829Y231756D01*
G01X205845Y231193D02*
X205838Y231608D01*
G01X205850Y230573D02*
X205845Y231193D01*
G01X205851Y229826D02*
X205850Y230573D01*
G01X188578Y230698D02*
X188582Y230772D01*
G01X188574Y230490D02*
X188578Y230698D01*
G01X188572Y230180D02*
X188574Y230490D01*
G01X188571Y229807D02*
X188572Y230180D01*
G01X190086Y215680D02*
X190081Y215605D01*
G01X190089Y215887D02*
X190086Y215680D01*
G01X190091Y216197D02*
X190089Y215887D01*
G01X190092Y216570D02*
X190091Y216197D01*
G01X196436Y230573D02*
X196434Y229826D01*
G01X196441Y231193D02*
X196436Y230573D01*
G01X196448Y231608D02*
X196441Y231193D01*
G01X196456Y231756D02*
X196448Y231608D01*
G01X197976Y215804D02*
X197977Y216551D01*
G01X197971Y215184D02*
X197976Y215804D01*
G01X197964Y214770D02*
X197971Y215184D01*
G01X197955Y214621D02*
X197964Y214770D01*
G01X204310Y230573D02*
X204308Y229826D01*
G01X204315Y231193D02*
X204310Y230573D01*
G01X204322Y231608D02*
X204315Y231193D01*
G01X204330Y231756D02*
X204322Y231608D01*
G01X205850Y215804D02*
X205851Y216551D01*
G01X205845Y215184D02*
X205850Y215804D01*
G01X205838Y214770D02*
X205845Y215184D01*
G01X205829Y214621D02*
X205838Y214770D01*
G01X212184Y230573D02*
X212182Y229826D01*
G01X212189Y231193D02*
X212184Y230573D01*
G01X212196Y231608D02*
X212189Y231193D01*
G01X212204Y231756D02*
X212196Y231608D01*
G01X213724Y215804D02*
X213725Y216551D01*
G01X213719Y215184D02*
X213724Y215804D01*
G01X213712Y214770D02*
X213719Y215184D01*
G01X213703Y214621D02*
X213712Y214770D01*
G01X196446Y230178D02*
X196445Y229807D01*
G01X196448Y230490D02*
X196446Y230178D01*
G01X196452Y230699D02*
X196448Y230490D01*
G01X196456Y230772D02*
X196452Y230699D01*
G01X197965Y216200D02*
X197966Y216570D01*
G01X197963Y215887D02*
X197965Y216200D01*
G01X197960Y215678D02*
X197963Y215887D01*
G01X197955Y215605D02*
X197960Y215678D01*
G01X204320Y230178D02*
X204319Y229807D01*
G01X204322Y230490D02*
X204320Y230178D01*
G01X204326Y230699D02*
X204322Y230490D01*
G01X204330Y230772D02*
X204326Y230699D01*
G01X205840Y216200D02*
Y216570D01*
G01X205837Y215887D02*
X205840Y216200D01*
G01X205834Y215678D02*
X205837Y215887D01*
G01X205829Y215605D02*
X205834Y215678D01*
G01X212194Y230178D02*
X212193Y229807D01*
G01X212196Y230490D02*
X212194Y230178D01*
G01X212200Y230699D02*
X212196Y230490D01*
G01X212204Y230772D02*
X212200Y230699D01*
G01X213714Y216200D02*
Y216570D01*
G01X213711Y215887D02*
X213714Y216200D01*
G01X213708Y215678D02*
X213711Y215887D01*
G01X213703Y215605D02*
X213708Y215678D01*
G01X200123Y214965D02*
X200128Y215117D01*
G01X200119Y214866D02*
X200123Y214965D01*
G01X200114Y214824D02*
X200119Y214866D01*
G01X202162Y231413D02*
X202158Y231260D01*
G01X202166Y231511D02*
X202162Y231413D01*
G01X202171Y231553D02*
X202166Y231511D01*
G01X204065Y214965D02*
X204069Y215117D01*
G01X204061Y214866D02*
X204065Y214965D01*
G01X204056Y214824D02*
X204061Y214866D01*
G01X206094Y231413D02*
X206090Y231260D01*
G01X206099Y231511D02*
X206094Y231413D01*
G01X206103Y231553D02*
X206099Y231511D01*
G01X207997Y214965D02*
X208002Y215117D01*
G01X207993Y214866D02*
X207997Y214965D01*
G01X207988Y214824D02*
X207993Y214866D01*
G01X210036Y231413D02*
X210032Y231260D01*
G01X210040Y231511D02*
X210036Y231413D01*
G01X210045Y231553D02*
X210040Y231511D01*
G01X211939Y214965D02*
X211943Y215117D01*
G01X211935Y214866D02*
X211939Y214965D01*
G01X211930Y214824D02*
X211935Y214866D01*
G01X213968Y231413D02*
X213964Y231260D01*
G01X213973Y231511D02*
X213968Y231413D01*
G01X213977Y231553D02*
X213973Y231511D01*
G01X215871Y214965D02*
X215876Y215117D01*
G01X215867Y214866D02*
X215871Y214965D01*
G01X215862Y214824D02*
X215867Y214866D01*
G01X217910Y231413D02*
X217906Y231260D01*
G01X217914Y231511D02*
X217910Y231413D01*
G01X217919Y231553D02*
X217914Y231511D01*
G01X219813Y214965D02*
X219817Y215117D01*
G01X219809Y214866D02*
X219813Y214965D01*
G01X219804Y214824D02*
X219809Y214866D01*
G01X221842Y231413D02*
X221838Y231260D01*
G01X221847Y231511D02*
X221842Y231413D01*
G01X221851Y231553D02*
X221847Y231511D01*
G01X202159Y232353D02*
X202153Y232147D01*
G01X202165Y232484D02*
X202159Y232353D01*
G01X202171Y232538D02*
X202165Y232484D01*
G01X200127Y214024D02*
X200132Y214231D01*
G01X200121Y213893D02*
X200127Y214024D01*
G01X200114Y213840D02*
X200121Y213893D01*
G01X206091Y232353D02*
X206085Y232147D01*
G01X206097Y232484D02*
X206091Y232353D01*
G01X206103Y232538D02*
X206097Y232484D01*
G01X204068Y214024D02*
X204074Y214231D01*
G01X204062Y213893D02*
X204068Y214024D01*
G01X204056Y213840D02*
X204062Y213893D01*
G01X210033Y232353D02*
X210027Y232147D01*
G01X210039Y232484D02*
X210033Y232353D01*
G01X210045Y232538D02*
X210039Y232484D01*
G01X208001Y214024D02*
X208006Y214231D01*
G01X207995Y213893D02*
X208001Y214024D01*
G01X207988Y213840D02*
X207995Y213893D01*
G01X213965Y232353D02*
X213959Y232147D01*
G01X213971Y232484D02*
X213965Y232353D01*
G01X213977Y232538D02*
X213971Y232484D01*
G01X211942Y214024D02*
X211948Y214231D01*
G01X211936Y213893D02*
X211942Y214024D01*
G01X211930Y213840D02*
X211936Y213893D01*
G01X217907Y232353D02*
X217901Y232147D01*
G01X217913Y232484D02*
X217907Y232353D01*
G01X217919Y232538D02*
X217913Y232484D01*
G01X215875Y214024D02*
X215880Y214231D01*
G01X215869Y213893D02*
X215875Y214024D01*
G01X215862Y213840D02*
X215869Y213893D01*
G01X221839Y232353D02*
X221833Y232147D01*
G01X221845Y232484D02*
X221839Y232353D01*
G01X221851Y232538D02*
X221845Y232484D01*
G01X219816Y214024D02*
X219822Y214231D01*
G01X219810Y213893D02*
X219816Y214024D01*
G01X219804Y213840D02*
X219810Y213893D01*
G01X208262Y230209D02*
X208261Y229807D01*
G01X208265Y230537D02*
X208262Y230209D01*
G01X208269Y230733D02*
X208265Y230537D01*
G01X208273Y230762D02*
X208269Y230733D01*
G01X209772Y216168D02*
X209773Y216570D01*
G01X209769Y215841D02*
X209772Y216168D01*
G01X209765Y215645D02*
X209769Y215841D01*
G01X209760Y215615D02*
X209765Y215645D01*
G01X216136Y230209D02*
X216135Y229807D01*
G01X216139Y230537D02*
X216136Y230209D01*
G01X216143Y230733D02*
X216139Y230537D01*
G01X216147Y230762D02*
X216143Y230733D01*
G01X217646Y216168D02*
X217647Y216570D01*
G01X217643Y215841D02*
X217646Y216168D01*
G01X217639Y215645D02*
X217643Y215841D01*
G01X217634Y215615D02*
X217639Y215645D01*
G01X224010Y230209D02*
X224009Y229807D01*
G01X224013Y230537D02*
X224010Y230209D01*
G01X224017Y230733D02*
X224013Y230537D01*
G01X224021Y230762D02*
X224017Y230733D01*
G01X225520Y216168D02*
X225521Y216570D01*
G01X225517Y215841D02*
X225520Y216168D01*
G01X225513Y215645D02*
X225517Y215841D01*
G01X225508Y215615D02*
X225513Y215645D01*
G01X235827Y215610D02*
X235828Y215615D01*
G01X235827Y215606D02*
Y215610D01*
G01X235826Y215605D02*
X235827Y215606D01*
G01X245199Y230768D02*
X245198Y230762D01*
G01X245199Y230771D02*
Y230768D01*
G01X245200Y230772D02*
X245199Y230771D01*
G01X243701Y215610D02*
X243702Y215615D01*
G01X243701Y215606D02*
Y215610D01*
G01X243700Y215605D02*
X243701Y215606D01*
G01X251575Y214624D02*
X251576Y214627D01*
G01X251575Y214622D02*
Y214624D01*
G01X251574Y214621D02*
X251575Y214622D01*
G01X259449Y214624D02*
X259450Y214627D01*
G01X259449Y214622D02*
Y214624D01*
G01X259448Y214621D02*
X259449Y214622D01*
G01X196456Y230771D02*
Y230772D01*
G01X196457Y230768D02*
X196456Y230771D01*
G01X196457Y230762D02*
Y230768D01*
G01X197955Y215606D02*
Y215605D01*
G01X197954Y215610D02*
X197955Y215606D01*
G01X197954Y215615D02*
Y215610D01*
G01X204330Y230771D02*
Y230772D01*
G01X204331Y230768D02*
X204330Y230771D01*
G01X204331Y230762D02*
Y230768D01*
G01X205829Y215606D02*
Y215605D01*
G01X205828Y215610D02*
X205829Y215606D01*
G01X205828Y215615D02*
Y215610D01*
G01X212204Y230771D02*
Y230772D01*
G01X212205Y230768D02*
X212204Y230771D01*
G01X212205Y230762D02*
Y230768D01*
G01X213703Y215606D02*
Y215605D01*
G01X213702Y215610D02*
X213703Y215606D01*
G01X213702Y215615D02*
Y215610D01*
G01X206097Y213893D02*
X206103Y213840D01*
G01X206091Y214024D02*
X206097Y213893D01*
G01X206085Y214231D02*
X206091Y214024D01*
G01X208004Y232484D02*
X207998Y232538D01*
G01X208010Y232353D02*
X208004Y232484D01*
G01X208016Y232147D02*
X208010Y232353D01*
G01X210029Y213893D02*
X210036Y213840D01*
G01X210023Y214024D02*
X210029Y213893D01*
G01X210018Y214231D02*
X210023Y214024D01*
G01X211936Y232484D02*
X211930Y232538D01*
G01X211942Y232353D02*
X211936Y232484D01*
G01X211948Y232147D02*
X211942Y232353D01*
G01X213971Y213893D02*
X213977Y213840D01*
G01X213965Y214024D02*
X213971Y213893D01*
G01X213959Y214231D02*
X213965Y214024D01*
G01X215878Y232484D02*
X215872Y232538D01*
G01X215884Y232353D02*
X215878Y232484D01*
G01X215890Y232147D02*
X215884Y232353D01*
G01X217903Y213893D02*
X217910Y213840D01*
G01X217897Y214024D02*
X217903Y213893D01*
G01X217892Y214231D02*
X217897Y214024D01*
G01X219810Y232484D02*
X219804Y232538D01*
G01X219816Y232353D02*
X219810Y232484D01*
G01X219822Y232147D02*
X219816Y232353D01*
G01X221845Y213893D02*
X221851Y213840D01*
G01X221839Y214024D02*
X221845Y213893D01*
G01X221833Y214231D02*
X221839Y214024D01*
G01X223752Y232484D02*
X223746Y232538D01*
G01X223758Y232353D02*
X223752Y232484D01*
G01X223764Y232147D02*
X223758Y232353D01*
G01X225778Y213893D02*
X225784Y213840D01*
G01X225771Y214024D02*
X225778Y213893D01*
G01X225766Y214231D02*
X225771Y214024D01*
G01X227684Y232484D02*
X227678Y232538D01*
G01X227690Y232353D02*
X227684Y232484D01*
G01X227696Y232147D02*
X227690Y232353D01*
G01X206099Y214866D02*
X206103Y214824D01*
G01X206094Y214965D02*
X206099Y214866D01*
G01X206090Y215117D02*
X206094Y214965D01*
G01X208002Y231511D02*
X207998Y231553D01*
G01X208007Y231413D02*
X208002Y231511D01*
G01X208011Y231260D02*
X208007Y231413D01*
G01X210031Y214866D02*
X210036Y214824D01*
G01X210027Y214965D02*
X210031Y214866D01*
G01X210022Y215117D02*
X210027Y214965D01*
G01X211935Y231511D02*
X211930Y231553D01*
G01X211939Y231413D02*
X211935Y231511D01*
G01X211943Y231260D02*
X211939Y231413D01*
G01X213973Y214866D02*
X213977Y214824D01*
G01X213968Y214965D02*
X213973Y214866D01*
G01X213964Y215117D02*
X213968Y214965D01*
G01X215876Y231511D02*
X215872Y231553D01*
G01X215881Y231413D02*
X215876Y231511D01*
G01X215885Y231260D02*
X215881Y231413D01*
G01X217905Y214866D02*
X217910Y214824D01*
G01X217901Y214965D02*
X217905Y214866D01*
G01X217896Y215117D02*
X217901Y214965D01*
G01X219809Y231511D02*
X219804Y231553D01*
G01X219813Y231413D02*
X219809Y231511D01*
G01X219817Y231260D02*
X219813Y231413D01*
G01X221847Y214866D02*
X221851Y214824D01*
G01X221842Y214965D02*
X221847Y214866D01*
G01X221838Y215117D02*
X221842Y214965D01*
G01X223750Y231511D02*
X223746Y231553D01*
G01X223755Y231413D02*
X223750Y231511D01*
G01X223759Y231260D02*
X223755Y231413D01*
G01X225779Y214866D02*
X225784Y214824D01*
G01X225775Y214965D02*
X225779Y214866D01*
G01X225770Y215117D02*
X225775Y214965D01*
G01X227683Y231511D02*
X227678Y231553D01*
G01X227687Y231413D02*
X227683Y231511D01*
G01X227691Y231260D02*
X227687Y231413D01*
G01X208259Y215645D02*
X208264Y215615D01*
G01X208255Y215841D02*
X208259Y215645D01*
G01X208252Y216168D02*
X208255Y215841D01*
G01X208251Y216570D02*
X208252Y216168D01*
G01X209774Y230733D02*
X209770Y230762D01*
G01X209778Y230537D02*
X209774Y230733D01*
G01X209781Y230209D02*
X209778Y230537D01*
G01X209782Y229807D02*
X209781Y230209D01*
G01X216133Y215645D02*
X216138Y215615D01*
G01X216129Y215841D02*
X216133Y215645D01*
G01X216126Y216168D02*
X216129Y215841D01*
G01X216125Y216570D02*
X216126Y216168D01*
G01X217648Y230733D02*
X217644Y230762D01*
G01X217652Y230537D02*
X217648Y230733D01*
G01X217655Y230209D02*
X217652Y230537D01*
G01X217656Y229807D02*
X217655Y230209D01*
G01X224007Y215645D02*
X224012Y215615D01*
G01X224003Y215841D02*
X224007Y215645D01*
G01X224000Y216168D02*
X224003Y215841D01*
G01X223999Y216570D02*
X224000Y216168D01*
G01X225522Y230733D02*
X225518Y230762D01*
G01X225526Y230537D02*
X225522Y230733D01*
G01X225529Y230209D02*
X225526Y230537D01*
G01X225530Y229807D02*
X225529Y230209D01*
G01X231881Y215645D02*
X231886Y215615D01*
G01X231877Y215841D02*
X231881Y215645D01*
G01X231874Y216168D02*
X231877Y215841D01*
G01X231873Y216570D02*
X231874Y216168D01*
G01X212196Y214770D02*
X212204Y214621D01*
G01X212189Y215184D02*
X212196Y214770D01*
G01X212184Y215804D02*
X212189Y215184D01*
G01X212182Y216551D02*
X212184Y215804D01*
G01X212200Y215678D02*
X212204Y215605D01*
G01X212196Y215887D02*
X212200Y215678D01*
G01X212194Y216200D02*
X212196Y215887D01*
G01X212193Y216570D02*
X212194Y216200D01*
G01X213708Y230699D02*
X213703Y230772D01*
G01X213711Y230490D02*
X213708Y230699D01*
G01X213714Y230178D02*
X213711Y230490D01*
G01X213714Y229807D02*
Y230178D01*
G01X213712Y231608D02*
X213703Y231756D01*
G01X213719Y231193D02*
X213712Y231608D01*
G01X213724Y230573D02*
X213719Y231193D01*
G01X213725Y229826D02*
X213724Y230573D01*
G01X220070Y214770D02*
X220078Y214621D01*
G01X220063Y215184D02*
X220070Y214770D01*
G01X220058Y215804D02*
X220063Y215184D01*
G01X220056Y216551D02*
X220058Y215804D01*
G01X220074Y215678D02*
X220078Y215605D01*
G01X220070Y215887D02*
X220074Y215678D01*
G01X220068Y216200D02*
X220070Y215887D01*
G01X220067Y216570D02*
X220068Y216200D01*
G01X221582Y230699D02*
X221577Y230772D01*
G01X221585Y230490D02*
X221582Y230699D01*
G01X221588Y230178D02*
X221585Y230490D01*
G01X221588Y229807D02*
Y230178D01*
G01X221586Y231608D02*
X221577Y231756D01*
G01X221593Y231193D02*
X221586Y231608D01*
G01X221598Y230573D02*
X221593Y231193D01*
G01X221599Y229826D02*
X221598Y230573D01*
G01X227944Y214770D02*
X227952Y214621D01*
G01X227937Y215184D02*
X227944Y214770D01*
G01X227932Y215804D02*
X227937Y215184D01*
G01X227930Y216551D02*
X227932Y215804D01*
G01X227948Y215678D02*
X227952Y215605D01*
G01X227944Y215887D02*
X227948Y215678D01*
G01X227942Y216200D02*
X227944Y215887D01*
G01X227941Y216570D02*
X227942Y216200D01*
G01X229456Y230699D02*
X229451Y230772D01*
G01X229459Y230490D02*
X229456Y230699D01*
G01X229462Y230178D02*
X229459Y230490D01*
G01X229462Y229807D02*
Y230178D01*
G01X229460Y231608D02*
X229451Y231756D01*
G01X229467Y231193D02*
X229460Y231608D01*
G01X229472Y230573D02*
X229467Y231193D01*
G01X229473Y229826D02*
X229472Y230573D01*
G01X220058D02*
X220056Y229826D01*
G01X220063Y231193D02*
X220058Y230573D01*
G01X220070Y231608D02*
X220063Y231193D01*
G01X220078Y231756D02*
X220070Y231608D01*
G01X221598Y215804D02*
X221599Y216551D01*
G01X221593Y215184D02*
X221598Y215804D01*
G01X221586Y214770D02*
X221593Y215184D01*
G01X221577Y214621D02*
X221586Y214770D01*
G01X227932Y230573D02*
X227930Y229826D01*
G01X227937Y231193D02*
X227932Y230573D01*
G01X227944Y231608D02*
X227937Y231193D01*
G01X227952Y231756D02*
X227944Y231608D01*
G01X229472Y215804D02*
X229473Y216551D01*
G01X229467Y215184D02*
X229472Y215804D01*
G01X229460Y214770D02*
X229467Y215184D01*
G01X229451Y214621D02*
X229460Y214770D01*
G01X235806Y230573D02*
X235804Y229826D01*
G01X235811Y231193D02*
X235806Y230573D01*
G01X235818Y231608D02*
X235811Y231193D01*
G01X235826Y231756D02*
X235818Y231608D01*
G01X237346Y215804D02*
X237347Y216551D01*
G01X237341Y215184D02*
X237346Y215804D01*
G01X237334Y214770D02*
X237341Y215184D01*
G01X237325Y214621D02*
X237334Y214770D01*
G01X220068Y230178D02*
X220067Y229807D01*
G01X220070Y230490D02*
X220068Y230178D01*
G01X220074Y230699D02*
X220070Y230490D01*
G01X220078Y230772D02*
X220074Y230699D01*
G01X221588Y216200D02*
Y216570D01*
G01X221585Y215887D02*
X221588Y216200D01*
G01X221582Y215678D02*
X221585Y215887D01*
G01X221577Y215605D02*
X221582Y215678D01*
G01X227942Y230178D02*
X227941Y229807D01*
G01X227944Y230490D02*
X227942Y230178D01*
G01X227948Y230699D02*
X227944Y230490D01*
G01X227952Y230772D02*
X227948Y230699D01*
G01X229462Y216200D02*
Y216570D01*
G01X229459Y215887D02*
X229462Y216200D01*
G01X229456Y215678D02*
X229459Y215887D01*
G01X229451Y215605D02*
X229456Y215678D01*
G01X235816Y230178D02*
X235815Y229807D01*
G01X235818Y230490D02*
X235816Y230178D01*
G01X235822Y230699D02*
X235818Y230490D01*
G01X235826Y230772D02*
X235822Y230699D01*
G01X237336Y216200D02*
Y216570D01*
G01X237333Y215887D02*
X237336Y216200D01*
G01X237330Y215678D02*
X237333Y215887D01*
G01X237325Y215605D02*
X237330Y215678D01*
G01X223745Y214965D02*
X223750Y215117D01*
G01X223741Y214866D02*
X223745Y214965D01*
G01X223736Y214824D02*
X223741Y214866D01*
G01X225784Y231413D02*
X225780Y231260D01*
G01X225788Y231511D02*
X225784Y231413D01*
G01X225793Y231553D02*
X225788Y231511D01*
G01X227687Y214965D02*
X227691Y215117D01*
G01X227683Y214866D02*
X227687Y214965D01*
G01X227678Y214824D02*
X227683Y214866D01*
G01X229716Y231413D02*
X229712Y231260D01*
G01X229721Y231511D02*
X229716Y231413D01*
G01X229725Y231553D02*
X229721Y231511D01*
G01X231619Y214965D02*
X231624Y215117D01*
G01X231615Y214866D02*
X231619Y214965D01*
G01X231610Y214824D02*
X231615Y214866D01*
G01X233658Y231413D02*
X233654Y231260D01*
G01X233663Y231511D02*
X233658Y231413D01*
G01X233667Y231553D02*
X233663Y231511D01*
G01X235561Y214965D02*
X235565Y215117D01*
G01X235557Y214866D02*
X235561Y214965D01*
G01X235552Y214824D02*
X235557Y214866D01*
G01X237590Y231413D02*
X237586Y231260D01*
G01X237595Y231511D02*
X237590Y231413D01*
G01X237599Y231553D02*
X237595Y231511D01*
G01X239493Y214965D02*
X239498Y215117D01*
G01X239489Y214866D02*
X239493Y214965D01*
G01X239484Y214824D02*
X239489Y214866D01*
G01X241532Y231413D02*
X241528Y231260D01*
G01X241537Y231511D02*
X241532Y231413D01*
G01X241541Y231553D02*
X241537Y231511D01*
G01X243435Y214965D02*
X243439Y215117D01*
G01X243431Y214866D02*
X243435Y214965D01*
G01X243426Y214824D02*
X243431Y214866D01*
G01X245464Y231413D02*
X245460Y231260D01*
G01X245469Y231511D02*
X245464Y231413D01*
G01X245473Y231553D02*
X245469Y231511D01*
G01X225781Y232353D02*
X225775Y232147D01*
G01X225787Y232484D02*
X225781Y232353D01*
G01X225793Y232538D02*
X225787Y232484D01*
G01X223749Y214024D02*
X223754Y214231D01*
G01X223743Y213893D02*
X223749Y214024D01*
G01X223736Y213840D02*
X223743Y213893D01*
G01X229713Y232353D02*
X229707Y232147D01*
G01X229719Y232484D02*
X229713Y232353D01*
G01X229725Y232538D02*
X229719Y232484D01*
G01X227690Y214024D02*
X227696Y214231D01*
G01X227684Y213893D02*
X227690Y214024D01*
G01X227678Y213840D02*
X227684Y213893D01*
G01X233655Y232353D02*
X233649Y232147D01*
G01X233661Y232484D02*
X233655Y232353D01*
G01X233667Y232538D02*
X233661Y232484D01*
G01X231623Y214024D02*
X231628Y214231D01*
G01X231617Y213893D02*
X231623Y214024D01*
G01X231610Y213840D02*
X231617Y213893D01*
G01X237587Y232353D02*
X237581Y232147D01*
G01X237593Y232484D02*
X237587Y232353D01*
G01X237599Y232538D02*
X237593Y232484D01*
G01X235564Y214024D02*
X235570Y214231D01*
G01X235558Y213893D02*
X235564Y214024D01*
G01X235552Y213840D02*
X235558Y213893D01*
G01X241529Y232353D02*
X241523Y232147D01*
G01X241535Y232484D02*
X241529Y232353D01*
G01X241541Y232538D02*
X241535Y232484D01*
G01X239497Y214024D02*
X239502Y214231D01*
G01X239491Y213893D02*
X239497Y214024D01*
G01X239484Y213840D02*
X239491Y213893D01*
G01X245461Y232353D02*
X245455Y232147D01*
G01X245467Y232484D02*
X245461Y232353D01*
G01X245473Y232538D02*
X245467Y232484D01*
G01X243438Y214024D02*
X243444Y214231D01*
G01X243432Y213893D02*
X243438Y214024D01*
G01X243426Y213840D02*
X243432Y213893D01*
G01X231884Y230209D02*
X231883Y229807D01*
G01X231887Y230537D02*
X231884Y230209D01*
G01X231891Y230733D02*
X231887Y230537D01*
G01X231895Y230762D02*
X231891Y230733D01*
G01X233394Y216168D02*
X233395Y216570D01*
G01X233391Y215841D02*
X233394Y216168D01*
G01X233387Y215645D02*
X233391Y215841D01*
G01X233382Y215615D02*
X233387Y215645D01*
G01X239758Y230209D02*
X239757Y229807D01*
G01X239761Y230537D02*
X239758Y230209D01*
G01X239765Y230733D02*
X239761Y230537D01*
G01X239769Y230762D02*
X239765Y230733D01*
G01X241268Y216168D02*
X241269Y216570D01*
G01X241265Y215841D02*
X241268Y216168D01*
G01X241261Y215645D02*
X241265Y215841D01*
G01X241256Y215615D02*
X241261Y215645D01*
G01X247632Y230209D02*
X247631Y229807D01*
G01X247635Y230537D02*
X247632Y230209D01*
G01X247639Y230733D02*
X247635Y230537D01*
G01X247643Y230762D02*
X247639Y230733D01*
G01X249142Y216168D02*
X249143Y216570D01*
G01X249139Y215841D02*
X249142Y216168D01*
G01X249135Y215645D02*
X249139Y215841D01*
G01X249130Y215615D02*
X249135Y215645D01*
G01X190081Y214622D02*
Y214621D01*
G01X190080Y214624D02*
X190081Y214622D01*
G01X190080Y214627D02*
Y214624D01*
G01X188583Y231756D02*
X188582D01*
G01X188583Y231754D02*
Y231756D01*
G01X188584Y231750D02*
X188583Y231754D01*
G01X197955Y214622D02*
Y214621D01*
G01X197954Y214624D02*
X197955Y214622D01*
G01X197954Y214627D02*
Y214624D01*
G01X196457Y231756D02*
X196456D01*
G01X196457Y231754D02*
Y231756D01*
G01X196458Y231750D02*
X196457Y231754D01*
G01X205829Y214622D02*
Y214621D01*
G01X205828Y214624D02*
X205829Y214622D01*
G01X205828Y214627D02*
Y214624D01*
G01X204331Y231756D02*
X204330D01*
G01X204331Y231754D02*
Y231756D01*
G01X204332Y231750D02*
X204331Y231754D01*
G01X220079Y230771D02*
X220078Y230772D01*
G01X220079Y230768D02*
Y230771D01*
G01X220080Y230762D02*
X220079Y230768D01*
G01X221577Y215606D02*
Y215605D01*
G01X221576Y215610D02*
X221577Y215606D01*
G01X221576Y215615D02*
Y215610D01*
G01X227953Y230771D02*
X227952Y230772D01*
G01X227953Y230768D02*
Y230771D01*
G01X227954Y230762D02*
X227953Y230768D01*
G01X229451Y215606D02*
Y215605D01*
G01X229450Y215610D02*
X229451Y215606D01*
G01X229450Y215615D02*
Y215610D01*
G01X235827Y230771D02*
X235826Y230772D01*
G01X235827Y230768D02*
Y230771D01*
G01X235828Y230762D02*
X235827Y230768D01*
G01X237325Y215606D02*
Y215605D01*
G01X237324Y215610D02*
X237325Y215606D01*
G01X237324Y215615D02*
Y215610D01*
G01X229719Y213893D02*
X229725Y213840D01*
G01X229713Y214024D02*
X229719Y213893D01*
G01X229707Y214231D02*
X229713Y214024D01*
G01X231626Y232484D02*
X231620Y232538D01*
G01X231632Y232353D02*
X231626Y232484D01*
G01X231638Y232147D02*
X231632Y232353D01*
G01X233652Y213893D02*
X233658Y213840D01*
G01X233645Y214024D02*
X233652Y213893D01*
G01X233640Y214231D02*
X233645Y214024D01*
G01X235558Y232484D02*
X235552Y232538D01*
G01X235564Y232353D02*
X235558Y232484D01*
G01X235570Y232147D02*
X235564Y232353D01*
G01X237593Y213893D02*
X237599Y213840D01*
G01X237587Y214024D02*
X237593Y213893D01*
G01X237581Y214231D02*
X237587Y214024D01*
G01X239500Y232484D02*
X239494Y232538D01*
G01X239506Y232353D02*
X239500Y232484D01*
G01X239512Y232147D02*
X239506Y232353D01*
G01X241526Y213893D02*
X241532Y213840D01*
G01X241520Y214024D02*
X241526Y213893D01*
G01X241514Y214231D02*
X241520Y214024D01*
G01X243432Y232484D02*
X243426Y232538D01*
G01X243438Y232353D02*
X243432Y232484D01*
G01X243444Y232147D02*
X243438Y232353D01*
G01X245467Y213893D02*
X245473Y213840D01*
G01X245461Y214024D02*
X245467Y213893D01*
G01X245455Y214231D02*
X245461Y214024D01*
G01X247374Y232484D02*
X247368Y232538D01*
G01X247380Y232353D02*
X247374Y232484D01*
G01X247386Y232147D02*
X247380Y232353D01*
G01X249400Y213893D02*
X249406Y213840D01*
G01X249394Y214024D02*
X249400Y213893D01*
G01X249388Y214231D02*
X249394Y214024D01*
G01X251306Y232484D02*
X251300Y232538D01*
G01X251312Y232353D02*
X251306Y232484D01*
G01X251318Y232147D02*
X251312Y232353D01*
G01X253341Y213893D02*
X253347Y213840D01*
G01X253335Y214024D02*
X253341Y213893D01*
G01X253329Y214231D02*
X253335Y214024D01*
G01X229721Y214866D02*
X229725Y214824D01*
G01X229716Y214965D02*
X229721Y214866D01*
G01X229712Y215117D02*
X229716Y214965D01*
G01X231624Y231511D02*
X231620Y231553D01*
G01X231629Y231413D02*
X231624Y231511D01*
G01X231633Y231260D02*
X231629Y231413D01*
G01X233653Y214866D02*
X233658Y214824D01*
G01X233649Y214965D02*
X233653Y214866D01*
G01X233645Y215117D02*
X233649Y214965D01*
G01X235557Y231511D02*
X235552Y231553D01*
G01X235561Y231413D02*
X235557Y231511D01*
G01X235565Y231260D02*
X235561Y231413D01*
G01X237595Y214866D02*
X237599Y214824D01*
G01X237590Y214965D02*
X237595Y214866D01*
G01X237586Y215117D02*
X237590Y214965D01*
G01X239498Y231511D02*
X239494Y231553D01*
G01X239503Y231413D02*
X239498Y231511D01*
G01X239507Y231260D02*
X239503Y231413D01*
G01X241527Y214866D02*
X241532Y214824D01*
G01X241523Y214965D02*
X241527Y214866D01*
G01X241519Y215117D02*
X241523Y214965D01*
G01X243431Y231511D02*
X243426Y231553D01*
G01X243435Y231413D02*
X243431Y231511D01*
G01X243439Y231260D02*
X243435Y231413D01*
G01X245469Y214866D02*
X245473Y214824D01*
G01X245464Y214965D02*
X245469Y214866D01*
G01X245460Y215117D02*
X245464Y214965D01*
G01X247372Y231511D02*
X247368Y231553D01*
G01X247377Y231413D02*
X247372Y231511D01*
G01X247381Y231260D02*
X247377Y231413D01*
G01X249401Y214866D02*
X249406Y214824D01*
G01X249397Y214965D02*
X249401Y214866D01*
G01X249393Y215117D02*
X249397Y214965D01*
G01X251305Y231511D02*
X251300Y231553D01*
G01X251309Y231413D02*
X251305Y231511D01*
G01X251313Y231260D02*
X251309Y231413D01*
G01X253343Y214866D02*
X253347Y214824D01*
G01X253338Y214965D02*
X253343Y214866D01*
G01X253334Y215117D02*
X253338Y214965D01*
G01X233396Y230733D02*
X233392Y230762D01*
G01X233400Y230537D02*
X233396Y230733D01*
G01X233403Y230209D02*
X233400Y230537D01*
G01X233404Y229807D02*
X233403Y230209D01*
G01X239755Y215645D02*
X239760Y215615D01*
G01X239751Y215841D02*
X239755Y215645D01*
G01X239748Y216168D02*
X239751Y215841D01*
G01X239747Y216570D02*
X239748Y216168D01*
G01X241270Y230733D02*
X241266Y230762D01*
G01X241274Y230537D02*
X241270Y230733D01*
G01X241277Y230209D02*
X241274Y230537D01*
G01X241278Y229807D02*
X241277Y230209D01*
G01X247629Y215645D02*
X247634Y215615D01*
G01X247625Y215841D02*
X247629Y215645D01*
G01X247622Y216168D02*
X247625Y215841D01*
G01X247621Y216570D02*
X247622Y216168D01*
G01X249144Y230733D02*
X249140Y230762D01*
G01X249148Y230537D02*
X249144Y230733D01*
G01X249151Y230209D02*
X249148Y230537D01*
G01X249152Y229807D02*
X249151Y230209D01*
G01X255503Y215645D02*
X255508Y215615D01*
G01X255499Y215841D02*
X255503Y215645D01*
G01X255496Y216168D02*
X255499Y215841D01*
G01X255495Y216570D02*
X255496Y216168D01*
G01X235818Y214770D02*
X235826Y214621D01*
G01X235811Y215184D02*
X235818Y214770D01*
G01X235806Y215804D02*
X235811Y215184D01*
G01X235804Y216551D02*
X235806Y215804D01*
G01X235822Y215678D02*
X235826Y215605D01*
G01X235818Y215887D02*
X235822Y215678D01*
G01X235816Y216200D02*
X235818Y215887D01*
G01X235815Y216570D02*
X235816Y216200D01*
G01X237330Y230699D02*
X237325Y230772D01*
G01X237333Y230490D02*
X237330Y230699D01*
G01X237336Y230178D02*
X237333Y230490D01*
G01X237336Y229807D02*
Y230178D01*
G01X237334Y231608D02*
X237325Y231756D01*
G01X237341Y231193D02*
X237334Y231608D01*
G01X237346Y230573D02*
X237341Y231193D01*
G01X237347Y229826D02*
X237346Y230573D01*
G01X243692Y214770D02*
X243700Y214621D01*
G01X243685Y215184D02*
X243692Y214770D01*
G01X243680Y215804D02*
X243685Y215184D01*
G01X243678Y216551D02*
X243680Y215804D01*
G01X243696Y215678D02*
X243700Y215605D01*
G01X243692Y215887D02*
X243696Y215678D01*
G01X243690Y216200D02*
X243692Y215887D01*
G01X243689Y216570D02*
X243690Y216200D01*
G01X245204Y230699D02*
X245200Y230772D01*
G01X245207Y230490D02*
X245204Y230699D01*
G01X245210Y230178D02*
X245207Y230490D01*
G01X245210Y229807D02*
Y230178D01*
G01X245208Y231608D02*
X245200Y231756D01*
G01X245215Y231193D02*
X245208Y231608D01*
G01X245220Y230573D02*
X245215Y231193D01*
G01X245221Y229826D02*
X245220Y230573D01*
G01X251566Y214770D02*
X251574Y214621D01*
G01X251559Y215184D02*
X251566Y214770D01*
G01X251554Y215804D02*
X251559Y215184D01*
G01X251552Y216551D02*
X251554Y215804D01*
G01X253082Y231608D02*
X253074Y231756D01*
G01X253089Y231193D02*
X253082Y231608D01*
G01X253094Y230573D02*
X253089Y231193D01*
G01X253095Y229826D02*
X253094Y230573D01*
G01X251570Y230698D02*
X251574Y230772D01*
G01X251566Y230490D02*
X251570Y230698D01*
G01X251564Y230180D02*
X251566Y230490D01*
G01X251563Y229807D02*
X251564Y230180D01*
G01X253078Y215680D02*
X253074Y215605D01*
G01X253081Y215887D02*
X253078Y215680D01*
G01X253084Y216197D02*
X253081Y215887D01*
G01X253085Y216570D02*
X253084Y216197D01*
G01X243680Y230573D02*
X243678Y229826D01*
G01X243685Y231193D02*
X243680Y230573D01*
G01X243692Y231608D02*
X243685Y231193D01*
G01X243700Y231756D02*
X243692Y231608D01*
G01X245220Y215804D02*
X245221Y216551D01*
G01X245215Y215184D02*
X245220Y215804D01*
G01X245208Y214770D02*
X245215Y215184D01*
G01X245200Y214621D02*
X245208Y214770D01*
G01X251554Y230573D02*
X251552Y229826D01*
G01X251559Y231193D02*
X251554Y230573D01*
G01X251566Y231608D02*
X251559Y231193D01*
G01X251574Y231756D02*
X251566Y231608D01*
G01X253094Y215804D02*
X253095Y216551D01*
G01X253089Y215184D02*
X253094Y215804D01*
G01X253082Y214770D02*
X253089Y215184D01*
G01X253074Y214621D02*
X253082Y214770D01*
G01X259428Y230573D02*
X259426Y229826D01*
G01X259433Y231193D02*
X259428Y230573D01*
G01X259440Y231608D02*
X259433Y231193D01*
G01X259448Y231756D02*
X259440Y231608D01*
G01X260968Y215804D02*
X260969Y216551D01*
G01X260963Y215184D02*
X260968Y215804D01*
G01X260956Y214770D02*
X260963Y215184D01*
G01X260948Y214621D02*
X260956Y214770D01*
G01X243690Y230178D02*
X243689Y229807D01*
G01X243692Y230490D02*
X243690Y230178D01*
G01X243696Y230699D02*
X243692Y230490D01*
G01X243700Y230772D02*
X243696Y230699D01*
G01X245210Y216200D02*
Y216570D01*
G01X245207Y215887D02*
X245210Y216200D01*
G01X245204Y215678D02*
X245207Y215887D01*
G01X245200Y215605D02*
X245204Y215678D01*
G01X251575Y215606D02*
X251574Y215605D01*
G01X251575Y215610D02*
Y215606D01*
G01X251576Y215617D02*
X251575Y215610D01*
G01X253073Y230771D02*
X253074Y230772D01*
G01X253073Y230768D02*
Y230771D01*
G01X253072Y230760D02*
X253073Y230768D01*
G01X259449Y215606D02*
X259448Y215605D01*
G01X259449Y215610D02*
Y215606D01*
G01X259450Y215617D02*
X259449Y215610D01*
G01X260947Y230771D02*
X260948Y230772D01*
G01X260947Y230768D02*
Y230771D01*
G01X260946Y230760D02*
X260947Y230768D01*
G01X247367Y214965D02*
X247372Y215117D01*
G01X247363Y214866D02*
X247367Y214965D01*
G01X247359Y214824D02*
X247363Y214866D01*
G01X249406Y231413D02*
X249402Y231260D01*
G01X249411Y231511D02*
X249406Y231413D01*
G01X249415Y231553D02*
X249411Y231511D01*
G01X251309Y214965D02*
X251313Y215117D01*
G01X251305Y214866D02*
X251309Y214965D01*
G01X251300Y214824D02*
X251305Y214866D01*
G01X253338Y231413D02*
X253334Y231260D01*
G01X253343Y231511D02*
X253338Y231413D01*
G01X253347Y231553D02*
X253343Y231511D01*
G01X255241Y214965D02*
X255246Y215117D01*
G01X255237Y214866D02*
X255241Y214965D01*
G01X255233Y214824D02*
X255237Y214866D01*
G01X257280Y231413D02*
X257276Y231260D01*
G01X257285Y231511D02*
X257280Y231413D01*
G01X257289Y231553D02*
X257285Y231511D01*
G01X259183Y214965D02*
X259187Y215117D01*
G01X259179Y214866D02*
X259183Y214965D01*
G01X259174Y214824D02*
X259179Y214866D01*
G01X261212Y231413D02*
X261208Y231260D01*
G01X261217Y231511D02*
X261212Y231413D01*
G01X261221Y231553D02*
X261217Y231511D01*
G01X263115Y214965D02*
X263120Y215117D01*
G01X263111Y214866D02*
X263115Y214965D01*
G01X263107Y214824D02*
X263111Y214866D01*
G01X265154Y231413D02*
X265150Y231260D01*
G01X265159Y231511D02*
X265154Y231413D01*
G01X265163Y231553D02*
X265159Y231511D01*
G01X249403Y232353D02*
X249397Y232147D01*
G01X249409Y232484D02*
X249403Y232353D01*
G01X249415Y232538D02*
X249409Y232484D01*
G01X247371Y214024D02*
X247376Y214231D01*
G01X247365Y213893D02*
X247371Y214024D01*
G01X247359Y213840D02*
X247365Y213893D01*
G01X253335Y232353D02*
X253329Y232147D01*
G01X253341Y232484D02*
X253335Y232353D01*
G01X253347Y232538D02*
X253341Y232484D01*
G01X251312Y214024D02*
X251318Y214231D01*
G01X251306Y213893D02*
X251312Y214024D01*
G01X251300Y213840D02*
X251306Y213893D01*
G01X257277Y232353D02*
X257271Y232147D01*
G01X257283Y232484D02*
X257277Y232353D01*
G01X257289Y232538D02*
X257283Y232484D01*
G01X255245Y214024D02*
X255251Y214231D01*
G01X255239Y213893D02*
X255245Y214024D01*
G01X255233Y213840D02*
X255239Y213893D01*
G01X261209Y232353D02*
X261203Y232147D01*
G01X261215Y232484D02*
X261209Y232353D01*
G01X261221Y232538D02*
X261215Y232484D01*
G01X259186Y214024D02*
X259192Y214231D01*
G01X259180Y213893D02*
X259186Y214024D01*
G01X259174Y213840D02*
X259180Y213893D01*
G01X265151Y232353D02*
X265145Y232147D01*
G01X265157Y232484D02*
X265151Y232353D01*
G01X265163Y232538D02*
X265157Y232484D01*
G01X263119Y214024D02*
X263125Y214231D01*
G01X263113Y213893D02*
X263119Y214024D01*
G01X263107Y213840D02*
X263113Y213893D01*
G01X255506Y230209D02*
X255505Y229807D01*
G01X255509Y230537D02*
X255506Y230209D01*
G01X255513Y230733D02*
X255509Y230537D01*
G01X255517Y230762D02*
X255513Y230733D01*
G01X257016Y216168D02*
X257017Y216570D01*
G01X257013Y215841D02*
X257016Y216168D01*
G01X257009Y215645D02*
X257013Y215841D01*
G01X257004Y215615D02*
X257009Y215645D01*
G01X263380Y230209D02*
X263379Y229807D01*
G01X263383Y230537D02*
X263380Y230209D01*
G01X263387Y230733D02*
X263383Y230537D01*
G01X263391Y230762D02*
X263387Y230733D01*
G01X264890Y216168D02*
X264891Y216570D01*
G01X264887Y215841D02*
X264890Y216168D01*
G01X264883Y215645D02*
X264887Y215841D01*
G01X264878Y215615D02*
X264883Y215645D01*
G01X213703Y214622D02*
Y214621D01*
G01X213702Y214624D02*
X213703Y214622D01*
G01X213702Y214627D02*
Y214624D01*
G01X212205Y231756D02*
X212204D01*
G01X212205Y231754D02*
Y231756D01*
G01X212206Y231750D02*
X212205Y231754D01*
G01X221577Y214622D02*
Y214621D01*
G01X221576Y214624D02*
X221577Y214622D01*
G01X221576Y214627D02*
Y214624D01*
G01X220079Y231756D02*
X220078D01*
G01X220079Y231754D02*
Y231756D01*
G01X220080Y231750D02*
X220079Y231754D01*
G01X229451Y214622D02*
Y214621D01*
G01X229450Y214624D02*
X229451Y214622D01*
G01X229450Y214627D02*
Y214624D01*
G01X227953Y231756D02*
X227952D01*
G01X227953Y231754D02*
Y231756D01*
G01X227954Y231750D02*
X227953Y231754D01*
G01X243701Y230771D02*
X243700Y230772D01*
G01X243701Y230768D02*
Y230771D01*
G01X243702Y230762D02*
X243701Y230768D01*
G01X245199Y215606D02*
X245200Y215605D01*
G01X245199Y215610D02*
Y215606D01*
G01X245198Y215615D02*
X245199Y215610D01*
G01X251564Y216197D02*
X251563Y216570D01*
G01X251566Y215887D02*
X251564Y216197D01*
G01X251570Y215680D02*
X251566Y215887D01*
G01X251574Y215605D02*
X251570Y215680D01*
G01X253084Y230180D02*
X253085Y229807D01*
G01X253081Y230490D02*
X253084Y230180D01*
G01X253078Y230698D02*
X253081Y230490D01*
G01X253074Y230772D02*
X253078Y230698D01*
G01X259438Y216197D02*
X259437Y216570D01*
G01X259440Y215887D02*
X259438Y216197D01*
G01X259444Y215680D02*
X259440Y215887D01*
G01X259448Y215605D02*
X259444Y215680D01*
G01X260958Y230180D02*
X260959Y229807D01*
G01X260955Y230490D02*
X260958Y230180D01*
G01X260952Y230698D02*
X260955Y230490D01*
G01X260948Y230772D02*
X260952Y230698D01*
G01X255248Y232484D02*
X255242Y232538D01*
G01X255254Y232353D02*
X255248Y232484D01*
G01X255260Y232147D02*
X255254Y232353D01*
G01X257274Y213893D02*
X257280Y213840D01*
G01X257268Y214024D02*
X257274Y213893D01*
G01X257262Y214231D02*
X257268Y214024D01*
G01X259180Y232484D02*
X259174Y232538D01*
G01X259186Y232353D02*
X259180Y232484D01*
G01X259192Y232147D02*
X259186Y232353D01*
G01X261215Y213893D02*
X261221Y213840D01*
G01X261209Y214024D02*
X261215Y213893D01*
G01X261203Y214231D02*
X261209Y214024D01*
G01X263122Y232484D02*
X263116Y232538D01*
G01X263128Y232353D02*
X263122Y232484D01*
G01X263134Y232147D02*
X263128Y232353D01*
G01X265148Y213893D02*
X265154Y213840D01*
G01X265142Y214024D02*
X265148Y213893D01*
G01X265136Y214231D02*
X265142Y214024D01*
G01X255246Y231511D02*
X255242Y231553D01*
G01X255251Y231413D02*
X255246Y231511D01*
G01X255255Y231260D02*
X255251Y231413D01*
G01X257275Y214866D02*
X257280Y214824D01*
G01X257271Y214965D02*
X257275Y214866D01*
G01X257267Y215117D02*
X257271Y214965D01*
G01X259179Y231511D02*
X259174Y231553D01*
G01X259183Y231413D02*
X259179Y231511D01*
G01X259187Y231260D02*
X259183Y231413D01*
G01X261217Y214866D02*
X261221Y214824D01*
G01X261212Y214965D02*
X261217Y214866D01*
G01X261208Y215117D02*
X261212Y214965D01*
G01X263120Y231511D02*
X263116Y231553D01*
G01X263125Y231413D02*
X263120Y231511D01*
G01X263129Y231260D02*
X263125Y231413D01*
G01X265149Y214866D02*
X265154Y214824D01*
G01X265145Y214965D02*
X265149Y214866D01*
G01X265141Y215117D02*
X265145Y214965D01*
G01X257018Y230733D02*
X257014Y230762D01*
G01X257022Y230537D02*
X257018Y230733D01*
G01X257025Y230209D02*
X257022Y230537D01*
G01X257026Y229807D02*
X257025Y230209D01*
G01X263377Y215645D02*
X263382Y215615D01*
G01X263373Y215841D02*
X263377Y215645D01*
G01X263370Y216168D02*
X263373Y215841D01*
G01X263369Y216570D02*
X263370Y216168D01*
G01X264892Y230733D02*
X264888Y230762D01*
G01X264896Y230537D02*
X264892Y230733D01*
G01X264899Y230209D02*
X264896Y230537D01*
G01X264900Y229807D02*
X264899Y230209D01*
G01X259440Y214770D02*
X259448Y214621D01*
G01X259433Y215184D02*
X259440Y214770D01*
G01X259428Y215804D02*
X259433Y215184D01*
G01X259426Y216551D02*
X259428Y215804D01*
G01X260956Y231608D02*
X260948Y231756D01*
G01X260963Y231193D02*
X260956Y231608D01*
G01X260968Y230573D02*
X260963Y231193D01*
G01X260969Y229826D02*
X260968Y230573D01*
G01X259444Y230698D02*
X259448Y230772D01*
G01X259440Y230490D02*
X259444Y230698D01*
G01X259438Y230180D02*
X259440Y230490D01*
G01X259437Y229807D02*
X259438Y230180D01*
G01X260952Y215680D02*
X260948Y215605D01*
G01X260955Y215887D02*
X260952Y215680D01*
G01X260958Y216197D02*
X260955Y215887D01*
G01X260959Y216570D02*
X260958Y216197D01*
G01X190080Y215610D02*
Y215617D01*
G01X190081Y215606D02*
X190080Y215610D01*
G01X190081Y215605D02*
Y215606D01*
G01X188583Y230768D02*
X188584Y230760D01*
G01X188582Y230771D02*
X188583Y230768D01*
G01X188582Y230772D02*
Y230771D01*
G01X237325Y214622D02*
Y214621D01*
G01X237324Y214624D02*
X237325Y214622D01*
G01X237324Y214627D02*
Y214624D01*
G01X235827Y231756D02*
X235826D01*
G01X235827Y231754D02*
Y231756D01*
G01X235828Y231750D02*
X235827Y231754D01*
G01X245199Y214622D02*
X245200Y214621D01*
G01X245198Y214624D02*
X245199Y214622D01*
G01X245198Y214627D02*
Y214624D01*
G01X243701Y231756D02*
X243700D01*
G01X243701Y231754D02*
Y231756D01*
G01X243702Y231750D02*
X243701Y231754D01*
G01X253073Y214622D02*
X253074Y214621D01*
G01X253072Y214624D02*
X253073Y214622D01*
G01X253072Y214627D02*
Y214624D01*
G01X251575Y231756D02*
X251574D01*
G01X251575Y231754D02*
Y231756D01*
G01X251576Y231750D02*
X251575Y231754D01*
G01X260947Y214622D02*
X260948Y214621D01*
G01X260946Y214624D02*
X260947Y214622D01*
G01X260946Y214627D02*
Y214624D01*
G01X259449Y231756D02*
X259448D01*
G01X259449Y231754D02*
Y231756D01*
G01X259450Y231750D02*
X259449Y231754D01*
G01X253073Y215610D02*
X253072Y215617D01*
G01X253073Y215606D02*
Y215610D01*
G01X253074Y215605D02*
X253073Y215606D01*
G01X251575Y230768D02*
X251576Y230760D01*
G01X251575Y230771D02*
Y230768D01*
G01X251574Y230772D02*
X251575Y230771D01*
G01X260947Y215610D02*
X260946Y215617D01*
G01X260947Y215606D02*
Y215610D01*
G01X260948Y215605D02*
X260947Y215606D01*
G01X259449Y230768D02*
X259450Y230760D01*
G01X259449Y230771D02*
Y230768D01*
G01X259448Y230772D02*
X259449Y230771D01*
G01X249436Y214823D02*
X249451Y214822D01*
G01X249421Y214823D02*
X249436D01*
G01X249406Y214824D02*
X249421Y214823D01*
G01X257310D02*
X257325Y214822D01*
G01X257295Y214823D02*
X257310D01*
G01X257280Y214824D02*
X257295Y214823D01*
G01X263077D02*
X263062Y214822D01*
G01X263092Y214823D02*
X263077D01*
G01X263107Y214824D02*
X263092Y214823D01*
G01X259144D02*
X259129Y214822D01*
G01X259159Y214823D02*
X259144D01*
G01X259174Y214824D02*
X259159Y214823D01*
G01X251270D02*
X251255Y214822D01*
G01X251285Y214823D02*
X251270D01*
G01X251300Y214824D02*
X251285Y214823D01*
G01X243396D02*
X243381Y214822D01*
G01X243411Y214823D02*
X243396D01*
G01X243426Y214824D02*
X243411Y214823D01*
G01X239454D02*
X239439Y214822D01*
G01X239469Y214823D02*
X239454D01*
G01X239484Y214824D02*
X239469Y214823D01*
G01X235522D02*
X235507Y214822D01*
G01X235537Y214823D02*
X235522D01*
G01X235552Y214824D02*
X235537Y214823D01*
G01X231580D02*
X231565Y214822D01*
G01X231595Y214823D02*
X231580D01*
G01X231610Y214824D02*
X231595Y214823D01*
G01X227648D02*
X227633Y214822D01*
G01X227663Y214823D02*
X227648D01*
G01X227678Y214824D02*
X227663Y214823D01*
G01X223706D02*
X223691Y214822D01*
G01X223721Y214823D02*
X223706D01*
G01X223736Y214824D02*
X223721Y214823D01*
G01X219774D02*
X219759Y214822D01*
G01X219789Y214823D02*
X219774D01*
G01X219804Y214824D02*
X219789Y214823D01*
G01X215832D02*
X215817Y214822D01*
G01X215847Y214823D02*
X215832D01*
G01X215862Y214824D02*
X215847Y214823D01*
G01X211900D02*
X211885Y214822D01*
G01X211915Y214823D02*
X211900D01*
G01X211930Y214824D02*
X211915Y214823D01*
G01X207958D02*
X207943Y214822D01*
G01X207973Y214823D02*
X207958D01*
G01X207988Y214824D02*
X207973Y214823D01*
G01X204026D02*
X204011Y214822D01*
G01X204041Y214823D02*
X204026D01*
G01X204056Y214824D02*
X204041Y214823D01*
G01X200084D02*
X200069Y214822D01*
G01X200099Y214823D02*
X200084D01*
G01X200114Y214824D02*
X200099Y214823D01*
G01X196152D02*
X196137Y214822D01*
G01X196167Y214823D02*
X196152D01*
G01X196182Y214824D02*
X196167Y214823D01*
G01X192210D02*
X192195Y214822D01*
G01X192225Y214823D02*
X192210D01*
G01X192240Y214824D02*
X192225Y214823D01*
G01X188278D02*
X188263Y214822D01*
G01X188293Y214823D02*
X188278D01*
G01X188308Y214824D02*
X188293Y214823D01*
G01X263077Y213838D02*
X263062D01*
G01X263092Y213839D02*
X263077Y213838D01*
G01X263107Y213840D02*
X263092Y213839D01*
G01X255203Y213838D02*
X255187D01*
G01X255217Y213839D02*
X255203Y213838D01*
G01X255233Y213840D02*
X255217Y213839D01*
G01X247328Y213838D02*
X247313D01*
G01X247343Y213839D02*
X247328Y213838D01*
G01X247359Y213840D02*
X247343Y213839D01*
G01X243396Y213838D02*
X243381D01*
G01X243411Y213839D02*
X243396Y213838D01*
G01X243426Y213840D02*
X243411Y213839D01*
G01X239454Y213838D02*
X239439D01*
G01X239469Y213839D02*
X239454Y213838D01*
G01X239484Y213840D02*
X239469Y213839D01*
G01X235522Y213838D02*
X235507D01*
G01X235537Y213839D02*
X235522Y213838D01*
G01X235552Y213840D02*
X235537Y213839D01*
G01X231580Y213838D02*
X231565D01*
G01X231595Y213839D02*
X231580Y213838D01*
G01X231610Y213840D02*
X231595Y213839D01*
G01X227648Y213838D02*
X227633D01*
G01X227663Y213839D02*
X227648Y213838D01*
G01X227678Y213840D02*
X227663Y213839D01*
G01X223706Y213838D02*
X223691D01*
G01X223721Y213839D02*
X223706Y213838D01*
G01X223736Y213840D02*
X223721Y213839D01*
G01X219774Y213838D02*
X219759D01*
G01X219789Y213839D02*
X219774Y213838D01*
G01X219804Y213840D02*
X219789Y213839D01*
G01X215832Y213838D02*
X215817D01*
G01X215847Y213839D02*
X215832Y213838D01*
G01X215862Y213840D02*
X215847Y213839D01*
G01X211900Y213838D02*
X211885D01*
G01X211915Y213839D02*
X211900Y213838D01*
G01X211930Y213840D02*
X211915Y213839D01*
G01X207958Y213838D02*
X207943D01*
G01X207973Y213839D02*
X207958Y213838D01*
G01X207988Y213840D02*
X207973Y213839D01*
G01X204026Y213838D02*
X204011D01*
G01X204041Y213839D02*
X204026Y213838D01*
G01X204056Y213840D02*
X204041Y213839D01*
G01X200084Y213838D02*
X200069D01*
G01X200099Y213839D02*
X200084Y213838D01*
G01X200114Y213840D02*
X200099Y213839D01*
G01X196152Y213838D02*
X196137D01*
G01X196167Y213839D02*
X196152Y213838D01*
G01X196182Y213840D02*
X196167Y213839D01*
G01X192210Y213838D02*
X192195D01*
G01X192225Y213839D02*
X192210Y213838D01*
G01X192240Y213840D02*
X192225Y213839D01*
G01X190370D02*
X190355Y213840D01*
G01X190385Y213838D02*
X190370Y213839D01*
G01X190400Y213838D02*
X190385D01*
G01X194303Y213839D02*
X194288Y213840D01*
G01X194318Y213838D02*
X194303Y213839D01*
G01X194333Y213838D02*
X194318D01*
G01X198244Y213839D02*
X198229Y213840D01*
G01X198259Y213838D02*
X198244Y213839D01*
G01X198274Y213838D02*
X198259D01*
G01X202177Y213839D02*
X202162Y213840D01*
G01X202192Y213838D02*
X202177Y213839D01*
G01X202207Y213838D02*
X202192D01*
G01X206118Y213839D02*
X206103Y213840D01*
G01X206133Y213838D02*
X206118Y213839D01*
G01X206148Y213838D02*
X206133D01*
G01X210051Y213839D02*
X210036Y213840D01*
G01X210066Y213838D02*
X210051Y213839D01*
G01X210081Y213838D02*
X210066D01*
G01X213992Y213839D02*
X213977Y213840D01*
G01X214007Y213838D02*
X213992Y213839D01*
G01X214022Y213838D02*
X214007D01*
G01X217925Y213839D02*
X217910Y213840D01*
G01X217940Y213838D02*
X217925Y213839D01*
G01X217955Y213838D02*
X217940D01*
G01X221866Y213839D02*
X221851Y213840D01*
G01X221881Y213838D02*
X221866Y213839D01*
G01X221896Y213838D02*
X221881D01*
G01X225799Y213839D02*
X225784Y213840D01*
G01X225814Y213838D02*
X225799Y213839D01*
G01X225829Y213838D02*
X225814D01*
G01X229740Y213839D02*
X229725Y213840D01*
G01X229755Y213838D02*
X229740Y213839D01*
G01X229770Y213838D02*
X229755D01*
G01X233673Y213839D02*
X233658Y213840D01*
G01X233688Y213838D02*
X233673Y213839D01*
G01X233703Y213838D02*
X233688D01*
G01X237614Y213839D02*
X237599Y213840D01*
G01X237629Y213838D02*
X237614Y213839D01*
G01X237644Y213838D02*
X237629D01*
G01X241547Y213839D02*
X241532Y213840D01*
G01X241562Y213838D02*
X241547Y213839D01*
G01X241577Y213838D02*
X241562D01*
G01X245488Y213839D02*
X245473Y213840D01*
G01X245503Y213838D02*
X245488Y213839D01*
G01X245518Y213838D02*
X245503D01*
G01X249421Y213839D02*
X249406Y213840D01*
G01X249436Y213838D02*
X249421Y213839D01*
G01X249451Y213838D02*
X249436D01*
G01X253362Y213839D02*
X253347Y213840D01*
G01X253377Y213838D02*
X253362Y213839D01*
G01X253392Y213838D02*
X253377D01*
G01X257295Y213839D02*
X257280Y213840D01*
G01X257310Y213838D02*
X257295Y213839D01*
G01X257325Y213838D02*
X257310D01*
G01X261236Y213839D02*
X261221Y213840D01*
G01X261251Y213838D02*
X261236Y213839D01*
G01X261266Y213838D02*
X261251D01*
G01X265169Y213839D02*
X265154Y213840D01*
G01X265184Y213838D02*
X265169Y213839D01*
G01X265199Y213838D02*
X265184D01*
G01X188293Y232538D02*
X188308D01*
G01X188278Y232539D02*
X188293Y232538D01*
G01X188263Y232539D02*
X188278D01*
G01X192235Y232538D02*
X192250D01*
G01X192220Y232539D02*
X192235Y232538D01*
G01X192205Y232539D02*
X192220D01*
G01X196167Y232538D02*
X196182D01*
G01X196152Y232539D02*
X196167Y232538D01*
G01X196137Y232539D02*
X196152D01*
G01X200109Y232538D02*
X200124D01*
G01X200094Y232539D02*
X200109Y232538D01*
G01X200079Y232539D02*
X200094D01*
G01X204041Y232538D02*
X204056D01*
G01X204026Y232539D02*
X204041Y232538D01*
G01X204011Y232539D02*
X204026D01*
G01X207983Y232538D02*
X207998D01*
G01X207968Y232539D02*
X207983Y232538D01*
G01X207953Y232539D02*
X207968D01*
G01X211915Y232538D02*
X211930D01*
G01X211900Y232539D02*
X211915Y232538D01*
G01X211885Y232539D02*
X211900D01*
G01X215857Y232538D02*
X215872D01*
G01X215842Y232539D02*
X215857Y232538D01*
G01X215827Y232539D02*
X215842D01*
G01X219789Y232538D02*
X219804D01*
G01X219774Y232539D02*
X219789Y232538D01*
G01X219759Y232539D02*
X219774D01*
G01X223731Y232538D02*
X223746D01*
G01X223716Y232539D02*
X223731Y232538D01*
G01X223701Y232539D02*
X223716D01*
G01X227663Y232538D02*
X227678D01*
G01X227648Y232539D02*
X227663Y232538D01*
G01X227633Y232539D02*
X227648D01*
G01X231605Y232538D02*
X231620D01*
G01X231590Y232539D02*
X231605Y232538D01*
G01X231575Y232539D02*
X231590D01*
G01X235537Y232538D02*
X235552D01*
G01X235522Y232539D02*
X235537Y232538D01*
G01X235507Y232539D02*
X235522D01*
G01X239479Y232538D02*
X239494D01*
G01X239464Y232539D02*
X239479Y232538D01*
G01X239449Y232539D02*
X239464D01*
G01X243411Y232538D02*
X243426D01*
G01X243396Y232539D02*
X243411Y232538D01*
G01X243381Y232539D02*
X243396D01*
G01X247353Y232538D02*
X247368D01*
G01X247338Y232539D02*
X247353Y232538D01*
G01X247323Y232539D02*
X247338D01*
G01X251285Y232538D02*
X251300D01*
G01X251270Y232539D02*
X251285Y232538D01*
G01X251255Y232539D02*
X251270D01*
G01X255227Y232538D02*
X255242D01*
G01X255212Y232539D02*
X255227Y232538D01*
G01X255197Y232539D02*
X255212D01*
G01X259159Y232538D02*
X259174D01*
G01X259144Y232539D02*
X259159Y232538D01*
G01X259129Y232539D02*
X259144D01*
G01X263101Y232538D02*
X263116D01*
G01X263086Y232539D02*
X263101Y232538D01*
G01X263071Y232539D02*
X263086D01*
G01X190370Y214823D02*
X190355Y214824D01*
G01X190385Y214823D02*
X190370D01*
G01X190400Y214822D02*
X190385Y214823D01*
G01X194303D02*
X194288Y214824D01*
G01X194318Y214823D02*
X194303D01*
G01X194333Y214822D02*
X194318Y214823D01*
G01X198244D02*
X198229Y214824D01*
G01X198259Y214823D02*
X198244D01*
G01X198274Y214822D02*
X198259Y214823D01*
G01X202177D02*
X202162Y214824D01*
G01X202192Y214823D02*
X202177D01*
G01X202207Y214822D02*
X202192Y214823D01*
G01X206118D02*
X206103Y214824D01*
G01X206133Y214823D02*
X206118D01*
G01X206148Y214822D02*
X206133Y214823D01*
G01X210051D02*
X210036Y214824D01*
G01X210066Y214823D02*
X210051D01*
G01X210081Y214822D02*
X210066Y214823D01*
G01X213992D02*
X213977Y214824D01*
G01X214007Y214823D02*
X213992D01*
G01X214022Y214822D02*
X214007Y214823D01*
G01X217925D02*
X217910Y214824D01*
G01X217940Y214823D02*
X217925D01*
G01X217955Y214822D02*
X217940Y214823D01*
G01X221866D02*
X221851Y214824D01*
G01X221881Y214823D02*
X221866D01*
G01X221896Y214822D02*
X221881Y214823D01*
G01X225799D02*
X225784Y214824D01*
G01X225814Y214823D02*
X225799D01*
G01X225829Y214822D02*
X225814Y214823D01*
G01X229740D02*
X229725Y214824D01*
G01X229755Y214823D02*
X229740D01*
G01X229770Y214822D02*
X229755Y214823D01*
G01X233673D02*
X233658Y214824D01*
G01X233688Y214823D02*
X233673D01*
G01X233703Y214822D02*
X233688Y214823D01*
G01X237614D02*
X237599Y214824D01*
G01X237629Y214823D02*
X237614D01*
G01X237644Y214822D02*
X237629Y214823D01*
G01X241547D02*
X241532Y214824D01*
G01X241562Y214823D02*
X241547D01*
G01X241577Y214822D02*
X241562Y214823D01*
G01X245488D02*
X245473Y214824D01*
G01X245503Y214823D02*
X245488D01*
G01X245518Y214822D02*
X245503Y214823D01*
G01X253362D02*
X253347Y214824D01*
G01X253377Y214823D02*
X253362D01*
G01X253392Y214822D02*
X253377Y214823D01*
G01X261236D02*
X261221Y214824D01*
G01X261251Y214823D02*
X261236D01*
G01X261266Y214822D02*
X261251Y214823D01*
G01X265169D02*
X265154Y214824D01*
G01X265184Y214823D02*
X265169D01*
G01X265199Y214822D02*
X265184Y214823D01*
G01X188293Y231554D02*
X188308Y231553D01*
G01X188278Y231555D02*
X188293Y231554D01*
G01X188263Y231555D02*
X188278D01*
G01X192235Y231554D02*
X192250Y231553D01*
G01X192220Y231555D02*
X192235Y231554D01*
G01X192205Y231555D02*
X192220D01*
G01X196167Y231554D02*
X196182Y231553D01*
G01X196152Y231555D02*
X196167Y231554D01*
G01X196137Y231555D02*
X196152D01*
G01X200109Y231554D02*
X200124Y231553D01*
G01X200094Y231555D02*
X200109Y231554D01*
G01X200079Y231555D02*
X200094D01*
G01X204041Y231554D02*
X204056Y231553D01*
G01X204026Y231555D02*
X204041Y231554D01*
G01X204011Y231555D02*
X204026D01*
G01X211915Y231554D02*
X211930Y231553D01*
G01X211900Y231555D02*
X211915Y231554D01*
G01X211885Y231555D02*
X211900D01*
G01X219789Y231554D02*
X219804Y231553D01*
G01X219774Y231555D02*
X219789Y231554D01*
G01X219759Y231555D02*
X219774D01*
G01X223731Y231554D02*
X223746Y231553D01*
G01X223716Y231555D02*
X223731Y231554D01*
G01X223701Y231555D02*
X223716D01*
G01X227663Y231554D02*
X227678Y231553D01*
G01X227648Y231555D02*
X227663Y231554D01*
G01X227633Y231555D02*
X227648D01*
G01X231605Y231554D02*
X231620Y231553D01*
G01X231590Y231555D02*
X231605Y231554D01*
G01X231575Y231555D02*
X231590D01*
G01X235537Y231554D02*
X235552Y231553D01*
G01X235522Y231555D02*
X235537Y231554D01*
G01X235507Y231555D02*
X235522D01*
G01X243411Y231554D02*
X243426Y231553D01*
G01X243396Y231555D02*
X243411Y231554D01*
G01X243381Y231555D02*
X243396D01*
G01X247353Y231554D02*
X247368Y231553D01*
G01X247338Y231555D02*
X247353Y231554D01*
G01X247323Y231555D02*
X247338D01*
G01X251285Y231554D02*
X251300Y231553D01*
G01X251270Y231555D02*
X251285Y231554D01*
G01X251255Y231555D02*
X251270D01*
G01X255227Y231554D02*
X255242Y231553D01*
G01X255212Y231555D02*
X255227Y231554D01*
G01X255197Y231555D02*
X255212D01*
G01X259159Y231554D02*
X259174Y231553D01*
G01X259144Y231555D02*
X259159Y231554D01*
G01X259129Y231555D02*
X259144D01*
G01X263101Y231554D02*
X263116Y231553D01*
G01X263086Y231555D02*
X263101Y231554D01*
G01X263071Y231555D02*
X263086D01*
G01X207968D02*
X207953D01*
G01X207983Y231554D02*
X207968Y231555D01*
G01X207998Y231553D02*
X207983Y231554D01*
G01X215842Y231555D02*
X215827D01*
G01X215857Y231554D02*
X215842Y231555D01*
G01X215872Y231553D02*
X215857Y231554D01*
G01X239464Y231555D02*
X239449D01*
G01X239479Y231554D02*
X239464Y231555D01*
G01X239494Y231553D02*
X239479Y231554D01*
G01X261251Y231555D02*
X261266D01*
G01X261236Y231554D02*
X261251Y231555D01*
G01X261221Y231553D02*
X261236Y231554D01*
G01X257319Y231555D02*
X257334D01*
G01X257304Y231554D02*
X257319Y231555D01*
G01X257289Y231553D02*
X257304Y231554D01*
G01X253377Y231555D02*
X253392D01*
G01X253362Y231554D02*
X253377Y231555D01*
G01X253347Y231553D02*
X253362Y231554D01*
G01X249445Y231555D02*
X249460D01*
G01X249430Y231554D02*
X249445Y231555D01*
G01X249415Y231553D02*
X249430Y231554D01*
G01X245503Y231555D02*
X245518D01*
G01X245488Y231554D02*
X245503Y231555D01*
G01X245473Y231553D02*
X245488Y231554D01*
G01X241571Y231555D02*
X241586D01*
G01X241556Y231554D02*
X241571Y231555D01*
G01X241541Y231553D02*
X241556Y231554D01*
G01X237629Y231555D02*
X237644D01*
G01X237614Y231554D02*
X237629Y231555D01*
G01X237599Y231553D02*
X237614Y231554D01*
G01X229755Y231555D02*
X229770D01*
G01X229740Y231554D02*
X229755Y231555D01*
G01X229725Y231553D02*
X229740Y231554D01*
G01X221881Y231555D02*
X221896D01*
G01X221866Y231554D02*
X221881Y231555D01*
G01X221851Y231553D02*
X221866Y231554D01*
G01X217949Y231555D02*
X217964D01*
G01X217934Y231554D02*
X217949Y231555D01*
G01X217919Y231553D02*
X217934Y231554D01*
G01X214007Y231555D02*
X214022D01*
G01X213992Y231554D02*
X214007Y231555D01*
G01X213977Y231553D02*
X213992Y231554D01*
G01X210075Y231555D02*
X210090D01*
G01X210060Y231554D02*
X210075Y231555D01*
G01X210045Y231553D02*
X210060Y231554D01*
G01X206133Y231555D02*
X206148D01*
G01X206118Y231554D02*
X206133Y231555D01*
G01X206103Y231553D02*
X206118Y231554D01*
G01X198259Y231555D02*
X198274D01*
G01X198244Y231554D02*
X198259Y231555D01*
G01X198229Y231553D02*
X198244Y231554D01*
G01X190385Y231555D02*
X190400D01*
G01X190370Y231554D02*
X190385Y231555D01*
G01X190355Y231553D02*
X190370Y231554D01*
G01X265193Y232539D02*
X265208D01*
G01X265178Y232538D02*
X265193Y232539D01*
G01X265163Y232538D02*
X265178D01*
G01X249445Y232539D02*
X249460D01*
G01X249430Y232538D02*
X249445Y232539D01*
G01X249415Y232538D02*
X249430D01*
G01X245503Y232539D02*
X245518D01*
G01X245488Y232538D02*
X245503Y232539D01*
G01X245473Y232538D02*
X245488D01*
G01X241571Y232539D02*
X241586D01*
G01X241556Y232538D02*
X241571Y232539D01*
G01X241541Y232538D02*
X241556D01*
G01X237629Y232539D02*
X237644D01*
G01X237614Y232538D02*
X237629Y232539D01*
G01X237599Y232538D02*
X237614D01*
G01X233697Y232539D02*
X233712D01*
G01X233682Y232538D02*
X233697Y232539D01*
G01X233667Y232538D02*
X233682D01*
G01X229755Y232539D02*
X229770D01*
G01X229740Y232538D02*
X229755Y232539D01*
G01X229725Y232538D02*
X229740D01*
G01X225823Y232539D02*
X225838D01*
G01X225808Y232538D02*
X225823Y232539D01*
G01X225793Y232538D02*
X225808D01*
G01X221881Y232539D02*
X221896D01*
G01X221866Y232538D02*
X221881Y232539D01*
G01X221851Y232538D02*
X221866D01*
G01X217949Y232539D02*
X217964D01*
G01X217934Y232538D02*
X217949Y232539D01*
G01X217919Y232538D02*
X217934D01*
G01X214007Y232539D02*
X214022D01*
G01X213992Y232538D02*
X214007Y232539D01*
G01X213977Y232538D02*
X213992D01*
G01X210075Y232539D02*
X210090D01*
G01X210060Y232538D02*
X210075Y232539D01*
G01X210045Y232538D02*
X210060D01*
G01X206133Y232539D02*
X206148D01*
G01X206118Y232538D02*
X206133Y232539D01*
G01X206103Y232538D02*
X206118D01*
G01X202201Y232539D02*
X202216D01*
G01X202186Y232538D02*
X202201Y232539D01*
G01X202171Y232538D02*
X202186D01*
G01X198259Y232539D02*
X198274D01*
G01X198244Y232538D02*
X198259Y232539D01*
G01X198229Y232538D02*
X198244D01*
G01X194327Y232539D02*
X194342D01*
G01X194312Y232538D02*
X194327Y232539D01*
G01X194297Y232538D02*
X194312D01*
G01X190001Y209943D02*
X190158Y209981D01*
G01X188505D02*
X188662Y209943D01*
G01X190001Y210965D02*
X190158Y211039D01*
G01X188505D02*
X188662Y210965D01*
G01X188263Y213838D02*
X188308Y213840D01*
G01X188584Y214627D02*
X188595Y214640D01*
G01X190068D02*
X190080Y214627D01*
G01X188662Y236434D02*
X188505Y236396D01*
G01X190158D02*
X190001Y236434D01*
G01X188662Y235412D02*
X188505Y235338D01*
G01X190158D02*
X190001Y235412D01*
G01X188595Y231737D02*
X188584Y231750D01*
G01X190080D02*
X190068Y231737D01*
G01X190400Y232539D02*
X190355Y232538D01*
G01X194001Y214640D02*
X194012Y214627D01*
G01X192516D02*
X192528Y214640D01*
G01X194095Y218680D02*
X193938Y218717D01*
G01X192599D02*
X192442Y218680D01*
G01X194095Y217621D02*
X193938Y217696D01*
G01X192599D02*
X192442Y217621D01*
G01Y227698D02*
X192599Y227660D01*
G01X192442Y228756D02*
X192599Y228681D01*
G01X193938D02*
X194095Y228756D01*
G01X193938Y227660D02*
X194095Y227698D01*
G01X194342Y231555D02*
X194297Y231553D01*
G01X192537Y231737D02*
X192525Y231750D01*
G01X194021D02*
X194010Y231737D01*
G01X196379Y209981D02*
X196536Y209943D01*
G01X197875D02*
X198032Y209981D01*
G01X196379Y211039D02*
X196536Y210965D01*
G01X197875D02*
X198032Y211039D01*
G01X196458Y214627D02*
X196469Y214640D01*
G01X197942D02*
X197954Y214627D01*
G01X198032Y236396D02*
X197875Y236434D01*
G01X196536D02*
X196379Y236396D01*
G01X198032Y235338D02*
X197875Y235412D01*
G01X196536D02*
X196379Y235338D01*
G01X196469Y231737D02*
X196458Y231750D01*
G01X197954D02*
X197942Y231737D01*
G01X201875Y214640D02*
X201886Y214627D01*
G01X200390D02*
X200402Y214640D01*
G01X201969Y218680D02*
X201812Y218717D01*
G01X200473D02*
X200316Y218680D01*
G01X201969Y217621D02*
X201812Y217696D01*
G01X200473D02*
X200316Y217621D01*
G01Y227698D02*
X200473Y227660D01*
G01X200316Y228756D02*
X200473Y228681D01*
G01X201812D02*
X201969Y228756D01*
G01X201812Y227660D02*
X201969Y227698D01*
G01X202216Y231555D02*
X202171Y231553D01*
G01X200411Y231737D02*
X200399Y231750D01*
G01X201895D02*
X201884Y231737D01*
G01X204253Y209981D02*
X204410Y209943D01*
G01X205749D02*
X205906Y209981D01*
G01X204253Y211039D02*
X204410Y210965D01*
G01X205749D02*
X205906Y211039D01*
G01X204332Y214627D02*
X204343Y214640D01*
G01X205816D02*
X205828Y214627D01*
G01X205906Y236396D02*
X205749Y236434D01*
G01X204410D02*
X204253Y236396D01*
G01X205906Y235338D02*
X205749Y235412D01*
G01X204410D02*
X204253Y235338D01*
G01X204343Y231737D02*
X204332Y231750D01*
G01X205828D02*
X205816Y231737D01*
G01X209749Y214640D02*
X209760Y214627D01*
G01X208264D02*
X208276Y214640D01*
G01X209843Y218680D02*
X209686Y218717D01*
G01X208347D02*
X208190Y218680D01*
G01X209843Y217621D02*
X209686Y217696D01*
G01X208347D02*
X208190Y217621D01*
G01Y227698D02*
X208347Y227660D01*
G01X209686D02*
X209843Y227698D01*
G01X208190Y228756D02*
X208347Y228681D01*
G01X209686D02*
X209843Y228756D01*
G01X208285Y231737D02*
X208273Y231750D01*
G01X209769D02*
X209758Y231737D01*
G01X212127Y209981D02*
X212284Y209943D01*
G01X213623D02*
X213780Y209981D01*
G01X212127Y211039D02*
X212284Y210965D01*
G01X213623D02*
X213780Y211039D01*
G01X212206Y214627D02*
X212217Y214640D01*
G01X213690D02*
X213702Y214627D01*
G01X213780Y236396D02*
X213623Y236434D01*
G01X212284D02*
X212127Y236396D01*
G01X213780Y235338D02*
X213623Y235412D01*
G01X212284D02*
X212127Y235338D01*
G01X212217Y231737D02*
X212206Y231750D01*
G01X213702D02*
X213690Y231737D01*
G01X217623Y214640D02*
X217634Y214627D01*
G01X216138D02*
X216150Y214640D01*
G01X217717Y218680D02*
X217560Y218717D01*
G01X216221D02*
X216064Y218680D01*
G01X217717Y217621D02*
X217560Y217696D01*
G01X216221D02*
X216064Y217621D01*
G01Y227698D02*
X216221Y227660D01*
G01X217560D02*
X217717Y227698D01*
G01X216064Y228756D02*
X216221Y228681D01*
G01X217560D02*
X217717Y228756D01*
G01X216159Y231737D02*
X216147Y231750D01*
G01X217643D02*
X217632Y231737D01*
G01X220001Y209981D02*
X220158Y209943D01*
G01X221497D02*
X221655Y209981D01*
G01X220001Y211039D02*
X220158Y210965D01*
G01X221497D02*
X221655Y211039D01*
G01X220080Y214627D02*
X220091Y214640D01*
G01X221564D02*
X221576Y214627D01*
G01X221655Y236396D02*
X221497Y236434D01*
G01X220158D02*
X220001Y236396D01*
G01X221655Y235338D02*
X221497Y235412D01*
G01X220158D02*
X220001Y235338D01*
G01X220091Y231737D02*
X220080Y231750D01*
G01X221576D02*
X221564Y231737D01*
G01X225497Y214640D02*
X225508Y214627D01*
G01X224012D02*
X224024Y214640D01*
G01X225592Y218680D02*
X225434Y218717D01*
G01X224095D02*
X223938Y218680D01*
G01X225592Y217621D02*
X225434Y217696D01*
G01X224095D02*
X223938Y217621D01*
G01Y227698D02*
X224095Y227660D01*
G01X223938Y228756D02*
X224095Y228681D01*
G01X225434D02*
X225592Y228756D01*
G01X225434Y227660D02*
X225592Y227698D01*
G01X225838Y231555D02*
X225793Y231553D01*
G01X224033Y231737D02*
X224021Y231750D01*
G01X225517D02*
X225506Y231737D01*
G01X227875Y209981D02*
X228032Y209943D01*
G01X229371D02*
X229529Y209981D01*
G01X227875Y211039D02*
X228032Y210965D01*
G01X229371D02*
X229529Y211039D01*
G01X227954Y214627D02*
X227965Y214640D01*
G01X229438D02*
X229450Y214627D01*
G01X229529Y236396D02*
X229371Y236434D01*
G01X228032D02*
X227875Y236396D01*
G01X229529Y235338D02*
X229371Y235412D01*
G01X228032D02*
X227875Y235338D01*
G01X227965Y231737D02*
X227954Y231750D01*
G01X229450D02*
X229438Y231737D01*
G01X233371Y214640D02*
X233382Y214627D01*
G01X231886D02*
X231898Y214640D01*
G01X233466Y218680D02*
X233308Y218717D01*
G01X231969D02*
X231812Y218680D01*
G01X233466Y217621D02*
X233308Y217696D01*
G01X231969D02*
X231812Y217621D01*
G01Y227698D02*
X231969Y227660D01*
G01X231812Y228756D02*
X231969Y228681D01*
G01X233308D02*
X233466Y228756D01*
G01X233308Y227660D02*
X233466Y227698D01*
G01X233712Y231555D02*
X233667Y231553D01*
G01X231907Y231737D02*
X231895Y231750D01*
G01X233391D02*
X233380Y231737D01*
G01X235749Y209981D02*
X235906Y209943D01*
G01X237245D02*
X237403Y209981D01*
G01X235749Y211039D02*
X235906Y210965D01*
G01X237245D02*
X237403Y211039D01*
G01X235828Y214627D02*
X235839Y214640D01*
G01X237312D02*
X237324Y214627D01*
G01X237403Y236396D02*
X237245Y236434D01*
G01X235906D02*
X235749Y236396D01*
G01X237403Y235338D02*
X237245Y235412D01*
G01X235906D02*
X235749Y235338D01*
G01X235839Y231737D02*
X235828Y231750D01*
G01X237324D02*
X237312Y231737D01*
G01X241245Y214640D02*
X241256Y214627D01*
G01X239760D02*
X239772Y214640D01*
G01X241340Y218680D02*
X241182Y218717D01*
G01X239843D02*
X239686Y218680D01*
G01X241340Y217621D02*
X241182Y217696D01*
G01X239843D02*
X239686Y217621D01*
G01Y227698D02*
X239843Y227660D01*
G01X241182D02*
X241340Y227698D01*
G01X239686Y228756D02*
X239843Y228681D01*
G01X241182D02*
X241340Y228756D01*
G01X239781Y231737D02*
X239769Y231750D01*
G01X241265D02*
X241254Y231737D01*
G01X243623Y209981D02*
X243780Y209943D01*
G01X245119D02*
X245277Y209981D01*
G01X243623Y211039D02*
X243780Y210965D01*
G01X245119D02*
X245277Y211039D01*
G01X243702Y214627D02*
X243713Y214640D01*
G01X245186D02*
X245198Y214627D01*
G01X245277Y236396D02*
X245119Y236434D01*
G01X243780D02*
X243623Y236396D01*
G01X245277Y235338D02*
X245119Y235412D01*
G01X243780D02*
X243623Y235338D01*
G01X243713Y231737D02*
X243702Y231750D01*
G01X245198D02*
X245186Y231737D01*
G01X249119Y214640D02*
X249130Y214627D01*
G01X247634D02*
X247646Y214640D01*
G01X247313Y214822D02*
X247359Y214824D01*
G01X247717Y218717D02*
X247560Y218680D01*
G01X249214D02*
X249056Y218717D01*
G01X247717Y217696D02*
X247560Y217621D01*
G01X249214D02*
X249056Y217696D01*
G01X247655Y231737D02*
X247643Y231750D01*
G01X249139D02*
X249128Y231737D01*
G01X249056Y227660D02*
X249214Y227698D01*
G01X247560D02*
X247717Y227660D01*
G01X249056Y228681D02*
X249214Y228756D01*
G01X247560D02*
X247717Y228681D01*
G01X252993Y209943D02*
X253151Y209981D01*
G01X251497D02*
X251655Y209943D01*
G01X252993Y210965D02*
X253151Y211039D01*
G01X251497D02*
X251655Y210965D01*
G01X251255Y213838D02*
X251300Y213840D01*
G01X251576Y214627D02*
X251587Y214640D01*
G01X253060D02*
X253072Y214627D01*
G01X251655Y236434D02*
X251497Y236396D01*
G01X253151D02*
X252993Y236434D01*
G01X251655Y235412D02*
X251497Y235338D01*
G01X253151D02*
X252993Y235412D01*
G01X251587Y231737D02*
X251576Y231750D01*
G01X253072D02*
X253060Y231737D01*
G01X253392Y232539D02*
X253347Y232538D01*
G01X257088Y218680D02*
X256930Y218717D01*
G01X255592D02*
X255434Y218680D01*
G01X255592Y217696D02*
X255434Y217621D01*
G01X257088D02*
X256930Y217696D01*
G01X256993Y214640D02*
X257004Y214627D01*
G01X255508D02*
X255520Y214640D01*
G01X255187Y214822D02*
X255233Y214824D01*
G01X255434Y227698D02*
X255592Y227660D01*
G01X256930Y228681D02*
X257088Y228756D01*
G01X255434D02*
X255592Y228681D01*
G01X256930Y227660D02*
X257088Y227698D01*
G01X255529Y231737D02*
X255517Y231750D01*
G01X257014D02*
X257002Y231737D01*
G01X257334Y232539D02*
X257289Y232538D01*
G01X260867Y209943D02*
X261025Y209981D01*
G01X259371D02*
X259529Y209943D01*
G01X260867Y210965D02*
X261025Y211039D01*
G01X259371D02*
X259529Y210965D01*
G01X259129Y213838D02*
X259174Y213840D01*
G01X259450Y214627D02*
X259461Y214640D01*
G01X260934D02*
X260946Y214627D01*
G01X259529Y236434D02*
X259371Y236396D01*
G01X261025D02*
X260867Y236434D01*
G01X259529Y235412D02*
X259371Y235338D01*
G01X261025D02*
X260867Y235412D01*
G01X259461Y231737D02*
X259450Y231750D01*
G01X260946D02*
X260934Y231737D01*
G01X261266Y232539D02*
X261221Y232538D01*
G01X264867Y214640D02*
X264878Y214627D01*
G01X263382D02*
X263394Y214640D01*
G01X264962Y218680D02*
X264804Y218717D01*
G01X263466D02*
X263308Y218680D01*
G01X264962Y217621D02*
X264804Y217696D01*
G01X263466D02*
X263308Y217621D01*
G01Y227698D02*
X263466Y227660D01*
G01X263308Y228756D02*
X263466Y228681D01*
G01X264804D02*
X264962Y228756D01*
G01X264804Y227660D02*
X264962Y227698D01*
G01X265208Y231555D02*
X265163Y231553D01*
G01X263403Y231737D02*
X263391Y231750D01*
G01X264888D02*
X264876Y231737D01*
G01X190513Y236476D02*
X188151D01*
G01X194450D02*
X192088D01*
G01X198387D02*
X196025D01*
G01X202324D02*
X199962D01*
G01X206261D02*
X203899D01*
G01X210198D02*
X207836D01*
G01X214135D02*
X211773D01*
G01X218072D02*
X215710D01*
G01X222009D02*
X219647D01*
G01X225946D02*
X223584D01*
G01X229883D02*
X227521D01*
G01X233820D02*
X231458D01*
G01X237757D02*
X235395D01*
G01X241694D02*
X239332D01*
G01X245631D02*
X243269D01*
G01X249568D02*
X247206D01*
G01X253505D02*
X251143D01*
G01X257442D02*
X255080D01*
G01X261379D02*
X259017D01*
G01X265316D02*
X262954D01*
G01X190001Y235492D02*
X188662D01*
G01X197875D02*
X196536D01*
G01X205749D02*
X204410D01*
G01X213623D02*
X212284D01*
G01X221497D02*
X220158D01*
G01X229371D02*
X228032D01*
G01X237245D02*
X235906D01*
G01X245119D02*
X243780D01*
G01X252993D02*
X251655D01*
G01X260867D02*
X259529D01*
G01X259371Y235393D02*
X261025D01*
G01X251497D02*
X253151D01*
G01X243623D02*
X245277D01*
G01X235749D02*
X237403D01*
G01X227875D02*
X229529D01*
G01X220001D02*
X221655D01*
G01X212127D02*
X213780D01*
G01X204253D02*
X205906D01*
G01X196379D02*
X198032D01*
G01X188505D02*
X190158D01*
G01X190513Y235295D02*
X188151D01*
G01X194450D02*
X192088D01*
G01X198387D02*
X196025D01*
G01X202324D02*
X199962D01*
G01X206261D02*
X203899D01*
G01X210198D02*
X207836D01*
G01X214135D02*
X211773D01*
G01X218072D02*
X215710D01*
G01X222009D02*
X219647D01*
G01X225946D02*
X223584D01*
G01X229883D02*
X227521D01*
G01X233820D02*
X231458D01*
G01X237757D02*
X235395D01*
G01X241694D02*
X239332D01*
G01X245631D02*
X243269D01*
G01X249568D02*
X247206D01*
G01X253505D02*
X251143D01*
G01X257442D02*
X255080D01*
G01X261379D02*
X259017D01*
G01X265316D02*
X262954D01*
G01X190158Y234901D02*
X188505D01*
G01X198032D02*
X196379D01*
G01X205906D02*
X204253D01*
G01X213780D02*
X212127D01*
G01X221655D02*
X220001D01*
G01X229529D02*
X227875D01*
G01X237403D02*
X235749D01*
G01X245277D02*
X243623D01*
G01X253151D02*
X251497D01*
G01X261025D02*
X259371D01*
G01X190749Y234035D02*
X187914D01*
G01X194686D02*
X191851D01*
G01X198623D02*
X195788D01*
G01X202560D02*
X199725D01*
G01X206497D02*
X203662D01*
G01X210434D02*
X207599D01*
G01X214371D02*
X211536D01*
G01X218308D02*
X215473D01*
G01X222245D02*
X219410D01*
G01X226182D02*
X223347D01*
G01X230119D02*
X227284D01*
G01X234056D02*
X231221D01*
G01X237993D02*
X235158D01*
G01X241930D02*
X239095D01*
G01X245867D02*
X243032D01*
G01X249804D02*
X246969D01*
G01X253741D02*
X250906D01*
G01X257678D02*
X254843D01*
G01X261615D02*
X258780D01*
G01X265552D02*
X262717D01*
G01X269489D02*
X266655D01*
G01X190158Y233130D02*
X188505D01*
G01X198032D02*
X196379D01*
G01X205906D02*
X204253D01*
G01X213780D02*
X212127D01*
G01X221655D02*
X220001D01*
G01X229529D02*
X227875D01*
G01X237403D02*
X235749D01*
G01X245277D02*
X243623D01*
G01X253151D02*
X251497D01*
G01X261025D02*
X259371D01*
G01Y232637D02*
X261025D01*
G01X251497D02*
X253151D01*
G01X243623D02*
X245277D01*
G01X235749D02*
X237403D01*
G01X227875D02*
X229529D01*
G01X220001D02*
X221655D01*
G01X212127D02*
X213780D01*
G01X204253D02*
X205906D01*
G01X196379D02*
X198032D01*
G01X188505D02*
X190158D01*
G01X190749Y232539D02*
X187914D01*
G01X194686D02*
X191851D01*
G01X198623D02*
X195788D01*
G01X202560D02*
X199725D01*
G01X206497D02*
X203662D01*
G01X210434D02*
X207599D01*
G01X214371D02*
X211536D01*
G01X218308D02*
X215473D01*
G01X222245D02*
X219410D01*
G01X226182D02*
X223347D01*
G01X230119D02*
X227284D01*
G01X234056D02*
X231221D01*
G01X237993D02*
X235158D01*
G01X241930D02*
X239095D01*
G01X245867D02*
X243032D01*
G01X249804D02*
X246969D01*
G01X253741D02*
X250906D01*
G01X257678D02*
X254843D01*
G01X261615D02*
X258780D01*
G01X265552D02*
X262717D01*
G01X269489D02*
X266655D01*
G01Y232382D02*
X267245D01*
G01X264962D02*
X265552D01*
G01X262717D02*
X263308D01*
G01X261025D02*
X261615D01*
G01X258780D02*
X259371D01*
G01X257088D02*
X257678D01*
G01X254843D02*
X255434D01*
G01X253151D02*
X253741D01*
G01X250906D02*
X251497D01*
G01X249214D02*
X249804D01*
G01X246969D02*
X247560D01*
G01X245277D02*
X245867D01*
G01X243032D02*
X243623D01*
G01X241340D02*
X241930D01*
G01X239095D02*
X239686D01*
G01X237403D02*
X237993D01*
G01X235158D02*
X235749D01*
G01X233466D02*
X234056D01*
G01X231221D02*
X231812D01*
G01X229529D02*
X230119D01*
G01X227284D02*
X227875D01*
G01X225592D02*
X226182D01*
G01X223347D02*
X223938D01*
G01X221655D02*
X222245D01*
G01X219410D02*
X220001D01*
G01X217717D02*
X218308D01*
G01X215473D02*
X216064D01*
G01X213780D02*
X214371D01*
G01X211536D02*
X212127D01*
G01X209843D02*
X210434D01*
G01X207599D02*
X208190D01*
G01X205906D02*
X206497D01*
G01X203662D02*
X204253D01*
G01X201969D02*
X202560D01*
G01X199725D02*
X200316D01*
G01X198032D02*
X198623D01*
G01X195788D02*
X196379D01*
G01X194095D02*
X194686D01*
G01X191851D02*
X192442D01*
G01X190158D02*
X190749D01*
G01X187914D02*
X188505D01*
G01X263134Y232147D02*
X265145D01*
G01X259192D02*
X261203D01*
G01X255260D02*
X257271D01*
G01X251318D02*
X253329D01*
G01X247386D02*
X249397D01*
G01X243444D02*
X245455D01*
G01X239512D02*
X241523D01*
G01X235570D02*
X237581D01*
G01X231638D02*
X233649D01*
G01X227696D02*
X229707D01*
G01X223764D02*
X225775D01*
G01X219822D02*
X221833D01*
G01X215890D02*
X217901D01*
G01X211948D02*
X213959D01*
G01X208016D02*
X210027D01*
G01X204074D02*
X206085D01*
G01X200142D02*
X202153D01*
G01X196200D02*
X198211D01*
G01X192268D02*
X194279D01*
G01X188326D02*
X190337D01*
G01X190081Y231756D02*
X188582D01*
G01X194023D02*
X192524D01*
G01X197955D02*
X196456D01*
G01X201897D02*
X200398D01*
G01X205829D02*
X204330D01*
G01X209771D02*
X208272D01*
G01X213703D02*
X212204D01*
G01X217645D02*
X216146D01*
G01X221577D02*
X220078D01*
G01X225519D02*
X224020D01*
G01X229451D02*
X227952D01*
G01X233393D02*
X231894D01*
G01X237325D02*
X235826D01*
G01X241267D02*
X239768D01*
G01X245200D02*
X243700D01*
G01X249141D02*
X247642D01*
G01X253074D02*
X251574D01*
G01X257015D02*
X255516D01*
G01X260948D02*
X259448D01*
G01X264889D02*
X263390D01*
G01X263403Y231737D02*
X264876D01*
G01X259461D02*
X260934D01*
G01X255529D02*
X257002D01*
G01X251587D02*
X253060D01*
G01X247655D02*
X249128D01*
G01X243713D02*
X245186D01*
G01X239781D02*
X241254D01*
G01X235839D02*
X237312D01*
G01X231907D02*
X233380D01*
G01X227965D02*
X229438D01*
G01X224033D02*
X225506D01*
G01X220091D02*
X221564D01*
G01X216159D02*
X217632D01*
G01X212217D02*
X213690D01*
G01X208285D02*
X209758D01*
G01X204343D02*
X205816D01*
G01X200411D02*
X201884D01*
G01X196469D02*
X197942D01*
G01X192537D02*
X194010D01*
G01X188595D02*
X190068D01*
G01X188505Y231712D02*
X187914D01*
G01X190749D02*
X190158D01*
G01X192442D02*
X191851D01*
G01X194686D02*
X194095D01*
G01X196379D02*
X195788D01*
G01X198623D02*
X198032D01*
G01X200316D02*
X199725D01*
G01X202560D02*
X201969D01*
G01X204253D02*
X203662D01*
G01X206497D02*
X205906D01*
G01X208190D02*
X207599D01*
G01X210434D02*
X209843D01*
G01X212127D02*
X211536D01*
G01X214371D02*
X213780D01*
G01X216064D02*
X215473D01*
G01X218308D02*
X217717D01*
G01X220001D02*
X219410D01*
G01X222245D02*
X221655D01*
G01X223938D02*
X223347D01*
G01X226182D02*
X225592D01*
G01X227875D02*
X227284D01*
G01X230119D02*
X229529D01*
G01X231812D02*
X231221D01*
G01X234056D02*
X233466D01*
G01X235749D02*
X235158D01*
G01X237993D02*
X237403D01*
G01X239686D02*
X239095D01*
G01X241930D02*
X241340D01*
G01X243623D02*
X243032D01*
G01X245867D02*
X245277D01*
G01X247560D02*
X246969D01*
G01X249804D02*
X249214D01*
G01X251497D02*
X250906D01*
G01X253741D02*
X253151D01*
G01X255434D02*
X254843D01*
G01X257678D02*
X257088D01*
G01X259371D02*
X258780D01*
G01X261615D02*
X261025D01*
G01X263308D02*
X262717D01*
G01X265552D02*
X264962D01*
G01X267245D02*
X266655D01*
G01Y231555D02*
X269489D01*
G01X262717D02*
X265552D01*
G01X258780D02*
X261615D01*
G01X254843D02*
X257678D01*
G01X250906D02*
X253741D01*
G01X243032D02*
X245867D01*
G01X239095D02*
X241930D01*
G01X235158D02*
X237993D01*
G01X231221D02*
X234056D01*
G01X227284D02*
X230119D01*
G01X223347D02*
X226182D01*
G01X219410D02*
X222245D01*
G01X211536D02*
X214371D01*
G01X207599D02*
X210434D01*
G01X203662D02*
X206497D01*
G01X199725D02*
X202560D01*
G01X195788D02*
X198623D01*
G01X191851D02*
X194686D01*
G01X187914D02*
X190749D01*
G01X218308D02*
X215473D01*
G01X249804D02*
X246969D01*
G01X194095Y231456D02*
X192442D01*
G01X201969D02*
X200316D01*
G01X209843D02*
X208190D01*
G01X217717D02*
X216064D01*
G01X225592D02*
X223938D01*
G01X233466D02*
X231812D01*
G01X241340D02*
X239686D01*
G01X249214D02*
X247560D01*
G01X257088D02*
X255434D01*
G01X264962D02*
X263308D01*
G01X189814Y231368D02*
X188849D01*
G01X193756D02*
X192791D01*
G01X197688D02*
X196723D01*
G01X201630D02*
X200665D01*
G01X205562D02*
X204597D01*
G01X209504D02*
X208539D01*
G01X213436D02*
X212471D01*
G01X217378D02*
X216413D01*
G01X221310D02*
X220345D01*
G01X225252D02*
X224287D01*
G01X229184D02*
X228219D01*
G01X233126D02*
X232161D01*
G01X237058D02*
X236093D01*
G01X241000D02*
X240035D01*
G01X244932D02*
X243967D01*
G01X248874D02*
X247909D01*
G01X252806D02*
X251841D01*
G01X256748D02*
X255783D01*
G01X260680D02*
X259715D01*
G01X264622D02*
X263657D01*
G01X266655Y231358D02*
X266969D01*
G01X262717D02*
X263032D01*
G01X254843D02*
X255158D01*
G01X246969D02*
X247284D01*
G01X243032D02*
X243347D01*
G01X239095D02*
X239410D01*
G01X235158D02*
X235473D01*
G01X231221D02*
X231536D01*
G01X227284D02*
X227599D01*
G01X223347D02*
X223662D01*
G01X219410D02*
X219725D01*
G01X215473D02*
X215788D01*
G01X211536D02*
X211851D01*
G01X207599D02*
X207914D01*
G01X203662D02*
X203977D01*
G01X199725D02*
X200040D01*
G01X195788D02*
X196103D01*
G01X191851D02*
X192166D01*
G01X188229D02*
X187914D01*
G01X190749D02*
X190434D01*
G01X194686D02*
X194371D01*
G01X198623D02*
X198308D01*
G01X202560D02*
X202245D01*
G01X206497D02*
X206182D01*
G01X210434D02*
X210119D01*
G01X214371D02*
X214056D01*
G01X218308D02*
X217993D01*
G01X222245D02*
X221930D01*
G01X226182D02*
X225867D01*
G01X230119D02*
X229804D01*
G01X234056D02*
X233741D01*
G01X237993D02*
X237678D01*
G01X241930D02*
X241615D01*
G01X245867D02*
X245552D01*
G01X249804D02*
X249489D01*
G01X251221D02*
X250906D01*
G01X253741D02*
X253426D01*
G01X257678D02*
X257363D01*
G01X259095D02*
X258780D01*
G01X261615D02*
X261300D01*
G01X265552D02*
X265237D01*
G01X190342Y231260D02*
X188321D01*
G01X194284D02*
X192263D01*
G01X198216D02*
X196195D01*
G01X202158D02*
X200137D01*
G01X206090D02*
X204069D01*
G01X210032D02*
X208011D01*
G01X213964D02*
X211943D01*
G01X217906D02*
X215885D01*
G01X221838D02*
X219817D01*
G01X225780D02*
X223759D01*
G01X229712D02*
X227691D01*
G01X233654D02*
X231633D01*
G01X237586D02*
X235565D01*
G01X241528D02*
X239507D01*
G01X245460D02*
X243439D01*
G01X249402D02*
X247381D01*
G01X253334D02*
X251313D01*
G01X257276D02*
X255255D01*
G01X261208D02*
X259187D01*
G01X265150D02*
X263129D01*
G01X263308Y230964D02*
X264962D01*
G01X255434D02*
X257088D01*
G01X247560D02*
X249214D01*
G01X239686D02*
X241340D01*
G01X231812D02*
X233466D01*
G01X223938D02*
X225592D01*
G01X216064D02*
X217717D01*
G01X208190D02*
X209843D01*
G01X200316D02*
X201969D01*
G01X192442D02*
X194095D01*
G01X190081Y230772D02*
X188582D01*
G01X194023D02*
X192524D01*
G01X197955D02*
X196456D01*
G01X201897D02*
X200398D01*
G01X205829D02*
X204330D01*
G01X209771D02*
X208272D01*
G01X213703D02*
X212204D01*
G01X217645D02*
X216146D01*
G01X221577D02*
X220078D01*
G01X225519D02*
X224020D01*
G01X229451D02*
X227952D01*
G01X233393D02*
X231894D01*
G01X237325D02*
X235826D01*
G01X241267D02*
X239768D01*
G01X245200D02*
X243700D01*
G01X249141D02*
X247642D01*
G01X253074D02*
X251574D01*
G01X257015D02*
X255516D01*
G01X260948D02*
X259448D01*
G01X264889D02*
X263390D01*
G01X190080Y230762D02*
X188583D01*
G01X194022D02*
X192525D01*
G01X197954D02*
X196457D01*
G01X201896D02*
X200399D01*
G01X205828D02*
X204331D01*
G01X209770D02*
X208273D01*
G01X213702D02*
X212205D01*
G01X217644D02*
X216147D01*
G01X221576D02*
X220080D01*
G01X225518D02*
X224021D01*
G01X229450D02*
X227954D01*
G01X233392D02*
X231895D01*
G01X237324D02*
X235828D01*
G01X241266D02*
X239769D01*
G01X245198D02*
X243702D01*
G01X249140D02*
X247643D01*
G01X253072D02*
X251576D01*
G01X257014D02*
X255517D01*
G01X260946D02*
X259450D01*
G01X264888D02*
X263391D01*
G01X263611Y230441D02*
X264668D01*
G01X259670D02*
X260726D01*
G01X255737D02*
X256794D01*
G01X251796D02*
X252852D01*
G01X247863D02*
X248920D01*
G01X243921D02*
X244978D01*
G01X239989D02*
X241046D01*
G01X236047D02*
X237104D01*
G01X232115D02*
X233172D01*
G01X228173D02*
X229230D01*
G01X224241D02*
X225298D01*
G01X220299D02*
X221356D01*
G01X216367D02*
X217424D01*
G01X212425D02*
X213482D01*
G01X208493D02*
X209550D01*
G01X204551D02*
X205608D01*
G01X200619D02*
X201676D01*
G01X196677D02*
X197734D01*
G01X192745D02*
X193802D01*
G01X188803D02*
X189860D01*
G01X259017Y230393D02*
X261379D01*
G01X255080D02*
X257442D01*
G01X251143D02*
X253505D01*
G01X188151D02*
X190513D01*
G01X194450D02*
X192088D01*
G01X198387D02*
X196025D01*
G01X202324D02*
X199962D01*
G01X206261D02*
X203899D01*
G01X210198D02*
X207836D01*
G01X214135D02*
X211773D01*
G01X218072D02*
X215710D01*
G01X222009D02*
X219647D01*
G01X225946D02*
X223584D01*
G01X229883D02*
X227521D01*
G01X233820D02*
X231458D01*
G01X237757D02*
X235395D01*
G01X241694D02*
X239332D01*
G01X245631D02*
X243269D01*
G01X249568D02*
X247206D01*
G01X265316D02*
X262954D01*
G01X266655Y229862D02*
X266969D01*
G01X265237D02*
X265552D01*
G01X262717D02*
X263032D01*
G01X261300D02*
X261615D01*
G01X258780D02*
X259095D01*
G01X257363D02*
X257678D01*
G01X254843D02*
X255158D01*
G01X253426D02*
X253741D01*
G01X250906D02*
X251221D01*
G01X249489D02*
X249804D01*
G01X246969D02*
X247284D01*
G01X245552D02*
X245867D01*
G01X243032D02*
X243347D01*
G01X241615D02*
X241930D01*
G01X239095D02*
X239410D01*
G01X237678D02*
X237993D01*
G01X235158D02*
X235473D01*
G01X233741D02*
X234056D01*
G01X231221D02*
X231536D01*
G01X229804D02*
X230119D01*
G01X227284D02*
X227599D01*
G01X225867D02*
X226182D01*
G01X223347D02*
X223662D01*
G01X221930D02*
X222245D01*
G01X217993D02*
X218308D01*
G01X219410D02*
X219725D01*
G01X215473D02*
X215788D01*
G01X214056D02*
X214371D01*
G01X211536D02*
X211851D01*
G01X210119D02*
X210434D01*
G01X207599D02*
X207914D01*
G01X206182D02*
X206497D01*
G01X203662D02*
X203977D01*
G01X202245D02*
X202560D01*
G01X199725D02*
X200040D01*
G01X198308D02*
X198623D01*
G01X195788D02*
X196103D01*
G01X194371D02*
X194686D01*
G01X191851D02*
X192166D01*
G01X190434D02*
X190749D01*
G01X187914D02*
X188229D01*
G01X263368Y229826D02*
X264911D01*
G01X259426D02*
X260969D01*
G01X255494D02*
X257037D01*
G01X251552D02*
X253095D01*
G01X247620D02*
X249163D01*
G01X243678D02*
X245221D01*
G01X239746D02*
X241289D01*
G01X235804D02*
X237347D01*
G01X231872D02*
X233415D01*
G01X227930D02*
X229473D01*
G01X223998D02*
X225541D01*
G01X220056D02*
X221599D01*
G01X216124D02*
X217667D01*
G01X212182D02*
X213725D01*
G01X208250D02*
X209793D01*
G01X204308D02*
X205851D01*
G01X200376D02*
X201919D01*
G01X196434D02*
X197977D01*
G01X192502D02*
X194045D01*
G01X188560D02*
X190103D01*
G01X263379Y229807D02*
X264900D01*
G01X259437D02*
X260959D01*
G01X255505D02*
X257026D01*
G01X251563D02*
X253085D01*
G01X247631D02*
X249152D01*
G01X243689D02*
X245210D01*
G01X239757D02*
X241278D01*
G01X235815D02*
X237336D01*
G01X231883D02*
X233404D01*
G01X227941D02*
X229462D01*
G01X224009D02*
X225530D01*
G01X220067D02*
X221588D01*
G01X216135D02*
X217656D01*
G01X212193D02*
X213714D01*
G01X208261D02*
X209782D01*
G01X204319D02*
X205840D01*
G01X200387D02*
X201908D01*
G01X196445D02*
X197966D01*
G01X192513D02*
X194034D01*
G01X188571D02*
X190092D01*
G01X263308Y229193D02*
X264962D01*
G01X255434D02*
X257088D01*
G01X247560D02*
X249214D01*
G01X239686D02*
X241340D01*
G01X231812D02*
X233466D01*
G01X223938D02*
X225592D01*
G01X216064D02*
X217717D01*
G01X208190D02*
X209843D01*
G01X200316D02*
X201969D01*
G01X192442D02*
X194095D01*
G01Y228700D02*
X192442D01*
G01X201969D02*
X200316D01*
G01X209843D02*
X208190D01*
G01X217717D02*
X216064D01*
G01X225592D02*
X223938D01*
G01X233466D02*
X231812D01*
G01X241340D02*
X239686D01*
G01X249214D02*
X247560D01*
G01X257088D02*
X255434D01*
G01X264962D02*
X263308D01*
G01X193938Y228602D02*
X192599D01*
G01X201812D02*
X200473D01*
G01X209686D02*
X208347D01*
G01X217560D02*
X216221D01*
G01X225434D02*
X224095D01*
G01X233308D02*
X231969D01*
G01X241182D02*
X239843D01*
G01X249056D02*
X247717D01*
G01X256930D02*
X255592D01*
G01X264804D02*
X263466D01*
G01Y227618D02*
X264804D01*
G01X255592D02*
X256930D01*
G01X247717D02*
X249056D01*
G01X239843D02*
X241182D01*
G01X231969D02*
X233308D01*
G01X224095D02*
X225434D01*
G01X216221D02*
X217560D01*
G01X208347D02*
X209686D01*
G01X200473D02*
X201812D01*
G01X192599D02*
X193938D01*
G01X190129Y226999D02*
X188534D01*
G01X194071D02*
X192476D01*
G01X198003D02*
X196408D01*
G01X201945D02*
X200350D01*
G01X205877D02*
X204282D01*
G01X209819D02*
X208224D01*
G01X213751D02*
X212156D01*
G01X217693D02*
X216098D01*
G01X221625D02*
X220030D01*
G01X225567D02*
X223972D01*
G01X229499D02*
X227904D01*
G01X233441D02*
X231846D01*
G01X237373D02*
X235778D01*
G01X241315D02*
X239720D01*
G01X245247D02*
X243652D01*
G01X249189D02*
X247594D01*
G01X253121D02*
X251526D01*
G01X257063D02*
X255468D01*
G01X260995D02*
X259400D01*
G01X264937D02*
X263342D01*
G01X190434Y226889D02*
X188229D01*
G01X194371D02*
X192166D01*
G01X198308D02*
X196103D01*
G01X202245D02*
X200040D01*
G01X206182D02*
X203977D01*
G01X210119D02*
X207914D01*
G01X214056D02*
X211851D01*
G01X217993D02*
X215788D01*
G01X221930D02*
X219725D01*
G01X225867D02*
X223662D01*
G01X229804D02*
X227599D01*
G01X233741D02*
X231536D01*
G01X237678D02*
X235473D01*
G01X241615D02*
X239410D01*
G01X245552D02*
X243347D01*
G01X249489D02*
X247284D01*
G01X253426D02*
X251221D01*
G01X257363D02*
X255158D01*
G01X261300D02*
X259095D01*
G01X265237D02*
X263032D01*
G01X190201Y226239D02*
X188462D01*
G01X194143D02*
X192404D01*
G01X198075D02*
X196336D01*
G01X202017D02*
X200278D01*
G01X205949D02*
X204210D01*
G01X209891D02*
X208152D01*
G01X213823D02*
X212084D01*
G01X217765D02*
X216026D01*
G01X221697D02*
X219958D01*
G01X225639D02*
X223900D01*
G01X229571D02*
X227832D01*
G01X233513D02*
X231774D01*
G01X237445D02*
X235706D01*
G01X241387D02*
X239648D01*
G01X245319D02*
X243580D01*
G01X249261D02*
X247522D01*
G01X253193D02*
X251454D01*
G01X257135D02*
X255396D01*
G01X261067D02*
X259328D01*
G01X265009D02*
X263270D01*
G01X263344Y226037D02*
X264935D01*
G01X259403D02*
X260993D01*
G01X255470D02*
X257061D01*
G01X251529D02*
X253119D01*
G01X247596D02*
X249187D01*
G01X243655D02*
X245245D01*
G01X239722D02*
X241313D01*
G01X235781D02*
X237371D01*
G01X231848D02*
X233439D01*
G01X227907D02*
X229497D01*
G01X223974D02*
X225565D01*
G01X220032D02*
X221623D01*
G01X216100D02*
X217691D01*
G01X212158D02*
X213749D01*
G01X208226D02*
X209817D01*
G01X204284D02*
X205875D01*
G01X200352D02*
X201943D01*
G01X196410D02*
X198001D01*
G01X192478D02*
X194069D01*
G01X188536D02*
X190127D01*
G01X263291Y226012D02*
X264988D01*
G01X259350D02*
X261046D01*
G01X255417D02*
X257114D01*
G01X251476D02*
X253172D01*
G01X247543D02*
X249240D01*
G01X243602D02*
X245298D01*
G01X239669D02*
X241366D01*
G01X235728D02*
X237424D01*
G01X231795D02*
X233491D01*
G01X227854D02*
X229550D01*
G01X223921D02*
X225617D01*
G01X219980D02*
X221676D01*
G01X216047D02*
X217743D01*
G01X212106D02*
X213802D01*
G01X208173D02*
X209869D01*
G01X204232D02*
X205928D01*
G01X200299D02*
X201995D01*
G01X196358D02*
X198054D01*
G01X192425D02*
X194121D01*
G01X188484D02*
X190180D01*
G01X190187Y225945D02*
X188477D01*
G01X194128D02*
X192418D01*
G01X198061D02*
X196351D01*
G01X202002D02*
X200292D01*
G01X205935D02*
X204225D01*
G01X209876D02*
X208166D01*
G01X213809D02*
X212099D01*
G01X217750D02*
X216040D01*
G01X221683D02*
X219973D01*
G01X225624D02*
X223914D01*
G01X229557D02*
X227847D01*
G01X233499D02*
X231788D01*
G01X237431D02*
X235721D01*
G01X241373D02*
X239662D01*
G01X245305D02*
X243595D01*
G01X249247D02*
X247536D01*
G01X253179D02*
X251469D01*
G01X257121D02*
X255410D01*
G01X261053D02*
X259343D01*
G01X264995D02*
X263284D01*
G01X263265Y225353D02*
X265014D01*
G01X259324D02*
X261072D01*
G01X255391D02*
X257140D01*
G01X251450D02*
X253198D01*
G01X247517D02*
X249266D01*
G01X243576D02*
X245324D01*
G01X239643D02*
X241392D01*
G01X235702D02*
X237450D01*
G01X231769D02*
X233518D01*
G01X227828D02*
X229576D01*
G01X223895D02*
X225644D01*
G01X219954D02*
X221702D01*
G01X216021D02*
X217770D01*
G01X212080D02*
X213828D01*
G01X208147D02*
X209896D01*
G01X204206D02*
X205954D01*
G01X200273D02*
X202022D01*
G01X196331D02*
X198080D01*
G01X192399D02*
X194148D01*
G01X188457D02*
X190206D01*
G01X190177Y225050D02*
X188486D01*
G01X194119D02*
X192428D01*
G01X198051D02*
X196360D01*
G01X201993D02*
X200302D01*
G01X205925D02*
X204234D01*
G01X209867D02*
X208176D01*
G01X213799D02*
X212108D01*
G01X217741D02*
X216050D01*
G01X221673D02*
X219982D01*
G01X225615D02*
X223924D01*
G01X229547D02*
X227856D01*
G01X233489D02*
X231798D01*
G01X237421D02*
X235730D01*
G01X241363D02*
X239672D01*
G01X245296D02*
X243604D01*
G01X249237D02*
X247546D01*
G01X253170D02*
X251478D01*
G01X257111D02*
X255420D01*
G01X261044D02*
X259352D01*
G01X264985D02*
X263294D01*
G01X190187Y224960D02*
X188477D01*
G01X194128D02*
X192418D01*
G01X198061D02*
X196351D01*
G01X202002D02*
X200292D01*
G01X205935D02*
X204225D01*
G01X209876D02*
X208166D01*
G01X213809D02*
X212099D01*
G01X217750D02*
X216040D01*
G01X221683D02*
X219973D01*
G01X225624D02*
X223914D01*
G01X229557D02*
X227847D01*
G01X233499D02*
X231788D01*
G01X237431D02*
X235721D01*
G01X241373D02*
X239662D01*
G01X245305D02*
X243595D01*
G01X249247D02*
X247536D01*
G01X253179D02*
X251469D01*
G01X257121D02*
X255410D01*
G01X261053D02*
X259343D01*
G01X264995D02*
X263284D01*
G01X263032Y224634D02*
X265237D01*
G01X259095D02*
X261300D01*
G01X255158D02*
X257363D01*
G01X251221D02*
X253426D01*
G01X247284D02*
X249489D01*
G01X243347D02*
X245552D01*
G01X239410D02*
X241615D01*
G01X235473D02*
X237678D01*
G01X231536D02*
X233741D01*
G01X227599D02*
X229804D01*
G01X223662D02*
X225867D01*
G01X219725D02*
X221930D01*
G01X215788D02*
X217993D01*
G01X211851D02*
X214056D01*
G01X207914D02*
X210119D01*
G01X203977D02*
X206182D01*
G01X200040D02*
X202245D01*
G01X196103D02*
X198308D01*
G01X192166D02*
X194371D01*
G01X188229D02*
X190434D01*
G01X263032Y224467D02*
X265237D01*
G01X259095D02*
X261300D01*
G01X255158D02*
X257363D01*
G01X251221D02*
X253426D01*
G01X247284D02*
X249489D01*
G01X243347D02*
X245552D01*
G01X239410D02*
X241615D01*
G01X235473D02*
X237678D01*
G01X231536D02*
X233741D01*
G01X227599D02*
X229804D01*
G01X223662D02*
X225867D01*
G01X219725D02*
X221930D01*
G01X215788D02*
X217993D01*
G01X211851D02*
X214056D01*
G01X207914D02*
X210119D01*
G01X203977D02*
X206182D01*
G01X200040D02*
X202245D01*
G01X196103D02*
X198308D01*
G01X192166D02*
X194371D01*
G01X188229D02*
X190434D01*
G01Y221910D02*
X188229D01*
G01X194371D02*
X192166D01*
G01X198308D02*
X196103D01*
G01X202245D02*
X200040D01*
G01X206182D02*
X203977D01*
G01X210119D02*
X207914D01*
G01X214056D02*
X211851D01*
G01X217993D02*
X215788D01*
G01X221930D02*
X219725D01*
G01X225867D02*
X223662D01*
G01X229804D02*
X227599D01*
G01X233741D02*
X231536D01*
G01X237678D02*
X235473D01*
G01X241615D02*
X239410D01*
G01X245552D02*
X243347D01*
G01X249489D02*
X247284D01*
G01X253426D02*
X251221D01*
G01X257363D02*
X255158D01*
G01X261300D02*
X259095D01*
G01X265237D02*
X263032D01*
G01X190434Y221743D02*
X188229D01*
G01X194371D02*
X192166D01*
G01X198308D02*
X196103D01*
G01X202245D02*
X200040D01*
G01X206182D02*
X203977D01*
G01X210119D02*
X207914D01*
G01X214056D02*
X211851D01*
G01X217993D02*
X215788D01*
G01X221930D02*
X219725D01*
G01X225867D02*
X223662D01*
G01X229804D02*
X227599D01*
G01X233741D02*
X231536D01*
G01X237678D02*
X235473D01*
G01X241615D02*
X239410D01*
G01X245552D02*
X243347D01*
G01X249489D02*
X247284D01*
G01X253426D02*
X251221D01*
G01X257363D02*
X255158D01*
G01X261300D02*
X259095D01*
G01X265237D02*
X263032D01*
G01X263275Y221417D02*
X264985D01*
G01X259343D02*
X261053D01*
G01X255401D02*
X257111D01*
G01X251469D02*
X253179D01*
G01X247527D02*
X249237D01*
G01X243595D02*
X245305D01*
G01X239653D02*
X241363D01*
G01X235721D02*
X237431D01*
G01X231779D02*
X233489D01*
G01X227847D02*
X229557D01*
G01X223905D02*
X225615D01*
G01X219973D02*
X221683D01*
G01X216031D02*
X217741D01*
G01X212099D02*
X213809D01*
G01X208157D02*
X209867D01*
G01X204225D02*
X205935D01*
G01X200283D02*
X201993D01*
G01X196351D02*
X198061D01*
G01X192409D02*
X194119D01*
G01X188477D02*
X190187D01*
G01X263284Y221327D02*
X264976D01*
G01X259352D02*
X261044D01*
G01X255410D02*
X257102D01*
G01X251478D02*
X253170D01*
G01X247536D02*
X249228D01*
G01X243604D02*
X245296D01*
G01X239662D02*
X241354D01*
G01X235730D02*
X237421D01*
G01X231788D02*
X233480D01*
G01X227856D02*
X229547D01*
G01X223914D02*
X225606D01*
G01X219982D02*
X221673D01*
G01X216040D02*
X217732D01*
G01X212108D02*
X213799D01*
G01X208166D02*
X209858D01*
G01X204234D02*
X205925D01*
G01X200292D02*
X201984D01*
G01X196360D02*
X198051D01*
G01X192418D02*
X194110D01*
G01X188486D02*
X190177D01*
G01X190206Y221024D02*
X188457D01*
G01X194138D02*
X192390D01*
G01X198080D02*
X196331D01*
G01X202012D02*
X200264D01*
G01X205954D02*
X204206D01*
G01X209886D02*
X208138D01*
G01X213828D02*
X212080D01*
G01X217760D02*
X216012D01*
G01X221702D02*
X219954D01*
G01X225634D02*
X223886D01*
G01X229576D02*
X227828D01*
G01X233508D02*
X231760D01*
G01X237450D02*
X235702D01*
G01X241382D02*
X239634D01*
G01X245324D02*
X243576D01*
G01X249256D02*
X247508D01*
G01X253198D02*
X251450D01*
G01X257130D02*
X255382D01*
G01X261072D02*
X259324D01*
G01X265004D02*
X263256D01*
G01X263275Y220433D02*
X264985D01*
G01X259343D02*
X261053D01*
G01X255401D02*
X257111D01*
G01X251469D02*
X253179D01*
G01X247527D02*
X249237D01*
G01X243595D02*
X245305D01*
G01X239653D02*
X241363D01*
G01X235721D02*
X237431D01*
G01X231779D02*
X233489D01*
G01X227847D02*
X229557D01*
G01X223905D02*
X225615D01*
G01X219973D02*
X221683D01*
G01X216031D02*
X217741D01*
G01X212099D02*
X213809D01*
G01X208157D02*
X209867D01*
G01X204225D02*
X205935D01*
G01X200283D02*
X201993D01*
G01X196351D02*
X198061D01*
G01X192409D02*
X194119D01*
G01X188477D02*
X190187D01*
G01X190180Y220365D02*
X188484D01*
G01X194112D02*
X192416D01*
G01X198054D02*
X196358D01*
G01X201986D02*
X200290D01*
G01X205928D02*
X204232D01*
G01X209860D02*
X208164D01*
G01X213802D02*
X212106D01*
G01X217734D02*
X216038D01*
G01X221676D02*
X219980D01*
G01X225608D02*
X223912D01*
G01X229550D02*
X227854D01*
G01X233482D02*
X231786D01*
G01X237424D02*
X235728D01*
G01X241356D02*
X239660D01*
G01X245298D02*
X243602D01*
G01X249230D02*
X247534D01*
G01X253172D02*
X251476D01*
G01X257104D02*
X255408D01*
G01X261046D02*
X259350D01*
G01X264978D02*
X263282D01*
G01X190127Y220340D02*
X188536D01*
G01X194059D02*
X192469D01*
G01X198001D02*
X196410D01*
G01X201933D02*
X200343D01*
G01X205875D02*
X204284D01*
G01X209807D02*
X208217D01*
G01X213749D02*
X212158D01*
G01X217681D02*
X216091D01*
G01X221623D02*
X220032D01*
G01X225555D02*
X223965D01*
G01X229497D02*
X227907D01*
G01X233429D02*
X231839D01*
G01X237371D02*
X235781D01*
G01X241303D02*
X239713D01*
G01X245245D02*
X243655D01*
G01X249177D02*
X247587D01*
G01X253119D02*
X251529D01*
G01X257051D02*
X255461D01*
G01X260993D02*
X259403D01*
G01X264925D02*
X263335D01*
G01X263261Y220138D02*
X265000D01*
G01X259328D02*
X261067D01*
G01X255387D02*
X257126D01*
G01X251454D02*
X253193D01*
G01X247513D02*
X249252D01*
G01X243580D02*
X245319D01*
G01X239639D02*
X241378D01*
G01X235706D02*
X237445D01*
G01X231765D02*
X233503D01*
G01X227832D02*
X229571D01*
G01X223891D02*
X225629D01*
G01X219958D02*
X221697D01*
G01X216017D02*
X217755D01*
G01X212084D02*
X213823D01*
G01X208143D02*
X209881D01*
G01X204210D02*
X205949D01*
G01X200269D02*
X202007D01*
G01X196336D02*
X198075D01*
G01X192395D02*
X194133D01*
G01X188462D02*
X190201D01*
G01X263032Y219488D02*
X265237D01*
G01X259095D02*
X261300D01*
G01X255158D02*
X257363D01*
G01X251221D02*
X253426D01*
G01X247284D02*
X249489D01*
G01X243347D02*
X245552D01*
G01X239410D02*
X241615D01*
G01X235473D02*
X237678D01*
G01X231536D02*
X233741D01*
G01X227599D02*
X229804D01*
G01X223662D02*
X225867D01*
G01X219725D02*
X221930D01*
G01X215788D02*
X217993D01*
G01X211851D02*
X214056D01*
G01X207914D02*
X210119D01*
G01X203977D02*
X206182D01*
G01X200040D02*
X202245D01*
G01X196103D02*
X198308D01*
G01X192166D02*
X194371D01*
G01X188229D02*
X190434D01*
G01X263333Y219379D02*
X264928D01*
G01X259400D02*
X260995D01*
G01X255459D02*
X257054D01*
G01X251526D02*
X253121D01*
G01X247585D02*
X249180D01*
G01X243652D02*
X245247D01*
G01X239711D02*
X241306D01*
G01X235778D02*
X237373D01*
G01X231837D02*
X233432D01*
G01X227904D02*
X229499D01*
G01X223962D02*
X225558D01*
G01X220030D02*
X221625D01*
G01X216088D02*
X217684D01*
G01X212156D02*
X213751D01*
G01X208214D02*
X209810D01*
G01X204282D02*
X205877D01*
G01X200340D02*
X201936D01*
G01X196408D02*
X198003D01*
G01X192466D02*
X194062D01*
G01X188534D02*
X190129D01*
G01X193938Y218760D02*
X192599D01*
G01X201812D02*
X200473D01*
G01X209686D02*
X208347D01*
G01X217560D02*
X216221D01*
G01X225434D02*
X224095D01*
G01X233308D02*
X231969D01*
G01X241182D02*
X239843D01*
G01X249056D02*
X247717D01*
G01X256930D02*
X255592D01*
G01X264804D02*
X263466D01*
G01X193938Y217775D02*
X192599D01*
G01X201812D02*
X200473D01*
G01X209686D02*
X208347D01*
G01X217560D02*
X216221D01*
G01X225434D02*
X224095D01*
G01X233308D02*
X231969D01*
G01X241182D02*
X239843D01*
G01X249056D02*
X247717D01*
G01X256930D02*
X255592D01*
G01X264804D02*
X263466D01*
G01X263308Y217677D02*
X264962D01*
G01X255434D02*
X257088D01*
G01X247560D02*
X249214D01*
G01X239686D02*
X241340D01*
G01X231812D02*
X233466D01*
G01X223938D02*
X225592D01*
G01X216064D02*
X217717D01*
G01X208190D02*
X209843D01*
G01X200316D02*
X201969D01*
G01X192442D02*
X194095D01*
G01Y217185D02*
X192442D01*
G01X201969D02*
X200316D01*
G01X209843D02*
X208190D01*
G01X217717D02*
X216064D01*
G01X225592D02*
X223938D01*
G01X233466D02*
X231812D01*
G01X241340D02*
X239686D01*
G01X249214D02*
X247560D01*
G01X257088D02*
X255434D01*
G01X264962D02*
X263308D01*
G01X190092Y216570D02*
X188571D01*
G01X194025D02*
X192503D01*
G01X197966D02*
X196445D01*
G01X201899D02*
X200377D01*
G01X205840D02*
X204319D01*
G01X209773D02*
X208251D01*
G01X213714D02*
X212193D01*
G01X217647D02*
X216125D01*
G01X221588D02*
X220067D01*
G01X225521D02*
X223999D01*
G01X229462D02*
X227941D01*
G01X233395D02*
X231873D01*
G01X237336D02*
X235815D01*
G01X241269D02*
X239747D01*
G01X245210D02*
X243689D01*
G01X249143D02*
X247621D01*
G01X253085D02*
X251563D01*
G01X257017D02*
X255495D01*
G01X260959D02*
X259437D01*
G01X264891D02*
X263369D01*
G01X190103Y216551D02*
X188560D01*
G01X194036D02*
X192492D01*
G01X197977D02*
X196434D01*
G01X201910D02*
X200366D01*
G01X205851D02*
X204308D01*
G01X209784D02*
X208240D01*
G01X213725D02*
X212182D01*
G01X217658D02*
X216114D01*
G01X221599D02*
X220056D01*
G01X225532D02*
X223988D01*
G01X229473D02*
X227930D01*
G01X233406D02*
X231862D01*
G01X237347D02*
X235804D01*
G01X241280D02*
X239736D01*
G01X245221D02*
X243678D01*
G01X249154D02*
X247610D01*
G01X253095D02*
X251552D01*
G01X257028D02*
X255484D01*
G01X260969D02*
X259426D01*
G01X264902D02*
X263358D01*
G01X188229Y216515D02*
X187914D01*
G01X190749D02*
X190434D01*
G01X192166D02*
X191851D01*
G01X194686D02*
X194371D01*
G01X196103D02*
X195788D01*
G01X198623D02*
X198308D01*
G01X200040D02*
X199725D01*
G01X202560D02*
X202245D01*
G01X203977D02*
X203662D01*
G01X206497D02*
X206182D01*
G01X207914D02*
X207599D01*
G01X210434D02*
X210119D01*
G01X211851D02*
X211536D01*
G01X214371D02*
X214056D01*
G01X215788D02*
X215473D01*
G01X218308D02*
X217993D01*
G01X219725D02*
X219410D01*
G01X222245D02*
X221930D01*
G01X223662D02*
X223347D01*
G01X226182D02*
X225867D01*
G01X227599D02*
X227284D01*
G01X230119D02*
X229804D01*
G01X231536D02*
X231221D01*
G01X234056D02*
X233741D01*
G01X235473D02*
X235158D01*
G01X239410D02*
X239095D01*
G01X237993D02*
X237678D01*
G01X241930D02*
X241615D01*
G01X243347D02*
X243032D01*
G01X245867D02*
X245552D01*
G01X247284D02*
X246969D01*
G01X249804D02*
X249489D01*
G01X251221D02*
X250906D01*
G01X253741D02*
X253426D01*
G01X255158D02*
X254843D01*
G01X257678D02*
X257363D01*
G01X259095D02*
X258780D01*
G01X261615D02*
X261300D01*
G01X263032D02*
X262717D01*
G01X265552D02*
X265237D01*
G01X266969D02*
X266655D01*
G01X190513Y215984D02*
X188151D01*
G01X194450D02*
X192088D01*
G01X198387D02*
X196025D01*
G01X202324D02*
X199962D01*
G01X206261D02*
X203899D01*
G01X210198D02*
X207836D01*
G01X214135D02*
X211773D01*
G01X218072D02*
X215710D01*
G01X222009D02*
X219647D01*
G01X225946D02*
X223584D01*
G01X229883D02*
X227521D01*
G01X233820D02*
X231458D01*
G01X237757D02*
X235395D01*
G01X241694D02*
X239332D01*
G01X245631D02*
X243269D01*
G01X249568D02*
X247206D01*
G01X253505D02*
X251143D01*
G01X257442D02*
X255080D01*
G01X261379D02*
X259017D01*
G01X265316D02*
X262954D01*
G01X189860Y215937D02*
X188803D01*
G01X193792D02*
X192736D01*
G01X197734D02*
X196677D01*
G01X201666D02*
X200610D01*
G01X205608D02*
X204551D01*
G01X209540D02*
X208484D01*
G01X213482D02*
X212425D01*
G01X217414D02*
X216358D01*
G01X221356D02*
X220299D01*
G01X225288D02*
X224232D01*
G01X229230D02*
X228173D01*
G01X233162D02*
X232106D01*
G01X237104D02*
X236047D01*
G01X241036D02*
X239980D01*
G01X244978D02*
X243921D01*
G01X248910D02*
X247854D01*
G01X252852D02*
X251796D01*
G01X256784D02*
X255728D01*
G01X260726D02*
X259670D01*
G01X264658D02*
X263602D01*
G01X263382Y215615D02*
X264878D01*
G01X259450D02*
X260946D01*
G01X255508D02*
X257004D01*
G01X251576D02*
X253072D01*
G01X247634D02*
X249130D01*
G01X243702D02*
X245198D01*
G01X239760D02*
X241256D01*
G01X235828D02*
X237324D01*
G01X231886D02*
X233382D01*
G01X227954D02*
X229450D01*
G01X224012D02*
X225508D01*
G01X220080D02*
X221576D01*
G01X216138D02*
X217634D01*
G01X212205D02*
X213702D01*
G01X208264D02*
X209760D01*
G01X204331D02*
X205828D01*
G01X200390D02*
X201886D01*
G01X196457D02*
X197954D01*
G01X192516D02*
X194012D01*
G01X188583D02*
X190080D01*
G01X263380Y215605D02*
X264880D01*
G01X259448D02*
X260948D01*
G01X255506D02*
X257006D01*
G01X251574D02*
X253074D01*
G01X247632D02*
X249132D01*
G01X243700D02*
X245200D01*
G01X239758D02*
X241258D01*
G01X235826D02*
X237325D01*
G01X231884D02*
X233384D01*
G01X227952D02*
X229451D01*
G01X224010D02*
X225510D01*
G01X220078D02*
X221577D01*
G01X216136D02*
X217636D01*
G01X212204D02*
X213703D01*
G01X208262D02*
X209762D01*
G01X204330D02*
X205829D01*
G01X200388D02*
X201888D01*
G01X196456D02*
X197955D01*
G01X192514D02*
X194014D01*
G01X188582D02*
X190081D01*
G01X194095Y215413D02*
X192442D01*
G01X201969D02*
X200316D01*
G01X209843D02*
X208190D01*
G01X217717D02*
X216064D01*
G01X225592D02*
X223938D01*
G01X233466D02*
X231812D01*
G01X241340D02*
X239686D01*
G01X249214D02*
X247560D01*
G01X257088D02*
X255434D01*
G01X264962D02*
X263308D01*
G01X263120Y215117D02*
X265141D01*
G01X259187D02*
X261208D01*
G01X255246D02*
X257267D01*
G01X251313D02*
X253334D01*
G01X247372D02*
X249393D01*
G01X243439D02*
X245460D01*
G01X239498D02*
X241519D01*
G01X235565D02*
X237586D01*
G01X231624D02*
X233645D01*
G01X227691D02*
X229712D01*
G01X223750D02*
X225770D01*
G01X219817D02*
X221838D01*
G01X215876D02*
X217896D01*
G01X211943D02*
X213964D01*
G01X208002D02*
X210022D01*
G01X204069D02*
X206090D01*
G01X200128D02*
X202148D01*
G01X196195D02*
X198216D01*
G01X192254D02*
X194274D01*
G01X188321D02*
X190342D01*
G01X265237Y215019D02*
X265552D01*
G01X257363D02*
X257678D01*
G01X249489D02*
X249804D01*
G01X245552D02*
X245867D01*
G01X241615D02*
X241930D01*
G01X237678D02*
X237993D01*
G01X233741D02*
X234056D01*
G01X229804D02*
X230119D01*
G01X225867D02*
X226182D01*
G01X221930D02*
X222245D01*
G01X217993D02*
X218308D01*
G01X214056D02*
X214371D01*
G01X210119D02*
X210434D01*
G01X206182D02*
X206497D01*
G01X202245D02*
X202560D01*
G01X198308D02*
X198623D01*
G01X194371D02*
X194686D01*
G01X188229D02*
X187914D01*
G01X190749D02*
X190434D01*
G01X192166D02*
X191851D01*
G01X196103D02*
X195788D01*
G01X200040D02*
X199725D01*
G01X203977D02*
X203662D01*
G01X207914D02*
X207599D01*
G01X211851D02*
X211536D01*
G01X215788D02*
X215473D01*
G01X219725D02*
X219410D01*
G01X223662D02*
X223347D01*
G01X227599D02*
X227284D01*
G01X231536D02*
X231221D01*
G01X235473D02*
X235158D01*
G01X239410D02*
X239095D01*
G01X243347D02*
X243032D01*
G01X247284D02*
X246969D01*
G01X251221D02*
X250906D01*
G01X253741D02*
X253426D01*
G01X255158D02*
X254843D01*
G01X259095D02*
X258780D01*
G01X261615D02*
X261300D01*
G01X263032D02*
X262717D01*
G01X266969D02*
X266655D01*
G01X263647Y215009D02*
X264613D01*
G01X259715D02*
X260680D01*
G01X255773D02*
X256739D01*
G01X251841D02*
X252806D01*
G01X247899D02*
X248865D01*
G01X243967D02*
X244932D01*
G01X240025D02*
X240991D01*
G01X236093D02*
X237058D01*
G01X232151D02*
X233117D01*
G01X228219D02*
X229184D01*
G01X224277D02*
X225243D01*
G01X220345D02*
X221310D01*
G01X216403D02*
X217369D01*
G01X212471D02*
X213436D01*
G01X208529D02*
X209495D01*
G01X204597D02*
X205562D01*
G01X200655D02*
X201621D01*
G01X196723D02*
X197688D01*
G01X192781D02*
X193747D01*
G01X188849D02*
X189814D01*
G01X263308Y214921D02*
X264962D01*
G01X255434D02*
X257088D01*
G01X247560D02*
X249214D01*
G01X239686D02*
X241340D01*
G01X231812D02*
X233466D01*
G01X223938D02*
X225592D01*
G01X216064D02*
X217717D01*
G01X208190D02*
X209843D01*
G01X200316D02*
X201969D01*
G01X192442D02*
X194095D01*
G01X266655Y214822D02*
X269489D01*
G01X262717D02*
X265552D01*
G01X258780D02*
X261615D01*
G01X254843D02*
X257678D01*
G01X250906D02*
X253741D01*
G01X246969D02*
X249804D01*
G01X243032D02*
X245867D01*
G01X239095D02*
X241930D01*
G01X235158D02*
X237993D01*
G01X231221D02*
X234056D01*
G01X227284D02*
X230119D01*
G01X223347D02*
X226182D01*
G01X219410D02*
X222245D01*
G01X215473D02*
X218308D01*
G01X211536D02*
X214371D01*
G01X207599D02*
X210434D01*
G01X203662D02*
X206497D01*
G01X199725D02*
X202560D01*
G01X195788D02*
X198623D01*
G01X191851D02*
X194686D01*
G01X187914D02*
X190749D01*
G01X266655Y214665D02*
X267245D01*
G01X264962D02*
X265552D01*
G01X262717D02*
X263308D01*
G01X261025D02*
X261615D01*
G01X258780D02*
X259371D01*
G01X257088D02*
X257678D01*
G01X254843D02*
X255434D01*
G01X253151D02*
X253741D01*
G01X250906D02*
X251497D01*
G01X249214D02*
X249804D01*
G01X246969D02*
X247560D01*
G01X245277D02*
X245867D01*
G01X243032D02*
X243623D01*
G01X241340D02*
X241930D01*
G01X239095D02*
X239686D01*
G01X237403D02*
X237993D01*
G01X235158D02*
X235749D01*
G01X233466D02*
X234056D01*
G01X231221D02*
X231812D01*
G01X229529D02*
X230119D01*
G01X227284D02*
X227875D01*
G01X225592D02*
X226182D01*
G01X223347D02*
X223938D01*
G01X221655D02*
X222245D01*
G01X219410D02*
X220001D01*
G01X217717D02*
X218308D01*
G01X215473D02*
X216064D01*
G01X213780D02*
X214371D01*
G01X211536D02*
X212127D01*
G01X209843D02*
X210434D01*
G01X207599D02*
X208190D01*
G01X205906D02*
X206497D01*
G01X203662D02*
X204253D01*
G01X201969D02*
X202560D01*
G01X199725D02*
X200316D01*
G01X198032D02*
X198623D01*
G01X195788D02*
X196379D01*
G01X194095D02*
X194686D01*
G01X191851D02*
X192442D01*
G01X190158D02*
X190749D01*
G01X187914D02*
X188505D01*
G01X190068Y214640D02*
X188595D01*
G01X194001D02*
X192528D01*
G01X197942D02*
X196469D01*
G01X201875D02*
X200402D01*
G01X205816D02*
X204343D01*
G01X209749D02*
X208276D01*
G01X213690D02*
X212217D01*
G01X217623D02*
X216150D01*
G01X221564D02*
X220091D01*
G01X225497D02*
X224024D01*
G01X229438D02*
X227965D01*
G01X233371D02*
X231898D01*
G01X237312D02*
X235839D01*
G01X241245D02*
X239772D01*
G01X245186D02*
X243713D01*
G01X249119D02*
X247646D01*
G01X253060D02*
X251587D01*
G01X256993D02*
X255520D01*
G01X260934D02*
X259461D01*
G01X264867D02*
X263394D01*
G01X263380Y214621D02*
X264880D01*
G01X259448D02*
X260948D01*
G01X255506D02*
X257006D01*
G01X251574D02*
X253074D01*
G01X247632D02*
X249132D01*
G01X243700D02*
X245200D01*
G01X239758D02*
X241258D01*
G01X235826D02*
X237325D01*
G01X231884D02*
X233384D01*
G01X227952D02*
X229451D01*
G01X224010D02*
X225510D01*
G01X220078D02*
X221577D01*
G01X216136D02*
X217636D01*
G01X212204D02*
X213703D01*
G01X208262D02*
X209762D01*
G01X204330D02*
X205829D01*
G01X200388D02*
X201888D01*
G01X196456D02*
X197955D01*
G01X192514D02*
X194014D01*
G01X188582D02*
X190081D01*
G01X190337Y214231D02*
X188326D01*
G01X194270D02*
X192258D01*
G01X198211D02*
X196200D01*
G01X202144D02*
X200132D01*
G01X206085D02*
X204074D01*
G01X210018D02*
X208006D01*
G01X213959D02*
X211948D01*
G01X217892D02*
X215880D01*
G01X221833D02*
X219822D01*
G01X225766D02*
X223754D01*
G01X229707D02*
X227696D01*
G01X233640D02*
X231628D01*
G01X237581D02*
X235570D01*
G01X241514D02*
X239502D01*
G01X245455D02*
X243444D01*
G01X249388D02*
X247376D01*
G01X253329D02*
X251318D01*
G01X257262D02*
X255251D01*
G01X261203D02*
X259192D01*
G01X265136D02*
X263125D01*
G01X188505Y213996D02*
X187914D01*
G01X190749D02*
X190158D01*
G01X192442D02*
X191851D01*
G01X194686D02*
X194095D01*
G01X196379D02*
X195788D01*
G01X198623D02*
X198032D01*
G01X200316D02*
X199725D01*
G01X202560D02*
X201969D01*
G01X204253D02*
X203662D01*
G01X206497D02*
X205906D01*
G01X208190D02*
X207599D01*
G01X210434D02*
X209843D01*
G01X212127D02*
X211536D01*
G01X214371D02*
X213780D01*
G01X216064D02*
X215473D01*
G01X218308D02*
X217717D01*
G01X220001D02*
X219410D01*
G01X222245D02*
X221655D01*
G01X223938D02*
X223347D01*
G01X226182D02*
X225592D01*
G01X227875D02*
X227284D01*
G01X230119D02*
X229529D01*
G01X231812D02*
X231221D01*
G01X234056D02*
X233466D01*
G01X235749D02*
X235158D01*
G01X237993D02*
X237403D01*
G01X239686D02*
X239095D01*
G01X241930D02*
X241340D01*
G01X243623D02*
X243032D01*
G01X245867D02*
X245277D01*
G01X247560D02*
X246969D01*
G01X249804D02*
X249214D01*
G01X251497D02*
X250906D01*
G01X253741D02*
X253151D01*
G01X255434D02*
X254843D01*
G01X257678D02*
X257088D01*
G01X259371D02*
X258780D01*
G01X261615D02*
X261025D01*
G01X263308D02*
X262717D01*
G01X265552D02*
X264962D01*
G01X267245D02*
X266655D01*
G01X190749Y213838D02*
X187914D01*
G01X194686D02*
X191851D01*
G01X198623D02*
X195788D01*
G01X202560D02*
X199725D01*
G01X206497D02*
X203662D01*
G01X210434D02*
X207599D01*
G01X214371D02*
X211536D01*
G01X218308D02*
X215473D01*
G01X222245D02*
X219410D01*
G01X226182D02*
X223347D01*
G01X230119D02*
X227284D01*
G01X234056D02*
X231221D01*
G01X237993D02*
X235158D01*
G01X241930D02*
X239095D01*
G01X245867D02*
X243032D01*
G01X249804D02*
X246969D01*
G01X253741D02*
X250906D01*
G01X257678D02*
X254843D01*
G01X261615D02*
X258780D01*
G01X265552D02*
X262717D01*
G01X269489D02*
X266655D01*
G01X190158Y213740D02*
X188505D01*
G01X198032D02*
X196379D01*
G01X205906D02*
X204253D01*
G01X213780D02*
X212127D01*
G01X221655D02*
X220001D01*
G01X229529D02*
X227875D01*
G01X237403D02*
X235749D01*
G01X245277D02*
X243623D01*
G01X253151D02*
X251497D01*
G01X261025D02*
X259371D01*
G01Y213248D02*
X261025D01*
G01X251497D02*
X253151D01*
G01X243623D02*
X245277D01*
G01X235749D02*
X237403D01*
G01X227875D02*
X229529D01*
G01X220001D02*
X221655D01*
G01X212127D02*
X213780D01*
G01X204253D02*
X205906D01*
G01X196379D02*
X198032D01*
G01X188505D02*
X190158D01*
G01X266655Y212342D02*
X269489D01*
G01X262717D02*
X265552D01*
G01X258780D02*
X261615D01*
G01X254843D02*
X257678D01*
G01X250906D02*
X253741D01*
G01X246969D02*
X249804D01*
G01X243032D02*
X245867D01*
G01X239095D02*
X241930D01*
G01X235158D02*
X237993D01*
G01X231221D02*
X234056D01*
G01X227284D02*
X230119D01*
G01X223347D02*
X226182D01*
G01X219410D02*
X222245D01*
G01X215473D02*
X218308D01*
G01X211536D02*
X214371D01*
G01X207599D02*
X210434D01*
G01X203662D02*
X206497D01*
G01X199725D02*
X202560D01*
G01X195788D02*
X198623D01*
G01X191851D02*
X194686D01*
G01X187914D02*
X190749D01*
G01X259371Y211476D02*
X261025D01*
G01X251497D02*
X253151D01*
G01X243623D02*
X245277D01*
G01X235749D02*
X237403D01*
G01X227875D02*
X229529D01*
G01X220001D02*
X221655D01*
G01X212127D02*
X213780D01*
G01X204253D02*
X205906D01*
G01X196379D02*
X198032D01*
G01X188505D02*
X190158D01*
G01X259017Y211082D02*
X261379D01*
G01X255080D02*
X257442D01*
G01X251143D02*
X253505D01*
G01X247206D02*
X249568D01*
G01X188151D02*
X190513D01*
G01X194450D02*
X192088D01*
G01X198387D02*
X196025D01*
G01X202324D02*
X199962D01*
G01X206261D02*
X203899D01*
G01X210198D02*
X207836D01*
G01X214135D02*
X211773D01*
G01X218072D02*
X215710D01*
G01X222009D02*
X219647D01*
G01X225946D02*
X223584D01*
G01X229883D02*
X227521D01*
G01X233820D02*
X231458D01*
G01X237757D02*
X235395D01*
G01X241694D02*
X239332D01*
G01X245631D02*
X243269D01*
G01X265316D02*
X262954D01*
G01X190158Y210984D02*
X188505D01*
G01X198032D02*
X196379D01*
G01X205906D02*
X204253D01*
G01X213780D02*
X212127D01*
G01X221655D02*
X220001D01*
G01X229529D02*
X227875D01*
G01X237403D02*
X235749D01*
G01X245277D02*
X243623D01*
G01X253151D02*
X251497D01*
G01X261025D02*
X259371D01*
G01X190001Y210885D02*
X188662D01*
G01X197875D02*
X196536D01*
G01X205749D02*
X204410D01*
G01X213623D02*
X212284D01*
G01X221497D02*
X220158D01*
G01X229371D02*
X228032D01*
G01X237245D02*
X235906D01*
G01X245119D02*
X243780D01*
G01X252993D02*
X251655D01*
G01X260867D02*
X259529D01*
G01X262954Y209901D02*
X265316D01*
G01X259017D02*
X261379D01*
G01X255080D02*
X257442D01*
G01X251143D02*
X253505D01*
G01X247206D02*
X249568D01*
G01X243269D02*
X245631D01*
G01X239332D02*
X241694D01*
G01X235395D02*
X237757D01*
G01X231458D02*
X233820D01*
G01X227521D02*
X229883D01*
G01X223584D02*
X225946D01*
G01X219647D02*
X222009D01*
G01X215710D02*
X218072D01*
G01X211773D02*
X214135D01*
G01X207836D02*
X210198D01*
G01X203899D02*
X206261D01*
G01X199962D02*
X202324D01*
G01X196025D02*
X198387D01*
G01X192088D02*
X194450D01*
G01X188151D02*
X190513D01*
G01X252324Y203011D02*
X272009D01*
G01X228702D02*
X248387D01*
G01X205080D02*
X224765D01*
G01X263403Y231737D02*
X263657Y231368D01*
G01X263611Y230441D02*
X263390Y230762D01*
G01X259715Y231368D02*
X259461Y231737D01*
G01X259450Y230760D02*
X259670Y230441D01*
G01X255783Y231368D02*
X255529Y231737D01*
G01X255737Y230441D02*
X255516Y230762D01*
G01X264658Y215937D02*
X264880Y215615D01*
G01X264867Y214640D02*
X264613Y215009D01*
G01X251841Y231368D02*
X251587Y231737D01*
G01X251576Y230760D02*
X251796Y230441D01*
G01X260946Y215617D02*
X260726Y215937D01*
G01X260680Y215009D02*
X260934Y214640D01*
G01X247909Y231368D02*
X247655Y231737D01*
G01X247863Y230441D02*
X247642Y230762D01*
G01X256784Y215937D02*
X257006Y215615D01*
G01X256739Y215009D02*
X256993Y214640D01*
G01X243713Y231737D02*
X243967Y231368D01*
G01X243921Y230441D02*
X243700Y230762D01*
G01X253072Y215617D02*
X252852Y215937D01*
G01X252806Y215009D02*
X253060Y214640D01*
G01X239781Y231737D02*
X240035Y231368D01*
G01X239989Y230441D02*
X239768Y230762D01*
G01X248910Y215937D02*
X249132Y215615D01*
G01X248865Y215009D02*
X249119Y214640D01*
G01X235839Y231737D02*
X236093Y231368D01*
G01X236047Y230441D02*
X235826Y230762D01*
G01X244978Y215937D02*
X245199Y215615D01*
G01X245186Y214640D02*
X244932Y215009D01*
G01X231907Y231737D02*
X232161Y231368D01*
G01X232115Y230441D02*
X231894Y230762D01*
G01X241036Y215937D02*
X241258Y215615D01*
G01X241245Y214640D02*
X240991Y215009D01*
G01X227965Y231737D02*
X228219Y231368D01*
G01X228173Y230441D02*
X227952Y230762D01*
G01X237104Y215937D02*
X237325Y215615D01*
G01X237312Y214640D02*
X237058Y215009D01*
G01X224033Y231737D02*
X224287Y231368D01*
G01X224241Y230441D02*
X224020Y230762D01*
G01X233162Y215937D02*
X233384Y215615D01*
G01X233371Y214640D02*
X233117Y215009D01*
G01X220091Y231737D02*
X220345Y231368D01*
G01X220299Y230441D02*
X220078Y230762D01*
G01X229230Y215937D02*
X229451Y215615D01*
G01X229438Y214640D02*
X229184Y215009D01*
G01X216159Y231737D02*
X216413Y231368D01*
G01X216367Y230441D02*
X216146Y230762D01*
G01X225288Y215937D02*
X225510Y215615D01*
G01X225497Y214640D02*
X225243Y215009D01*
G01X212217Y231737D02*
X212471Y231368D01*
G01X212425Y230441D02*
X212204Y230762D01*
G01X221356Y215937D02*
X221577Y215615D01*
G01X221564Y214640D02*
X221310Y215009D01*
G01X208285Y231737D02*
X208539Y231368D01*
G01X208493Y230441D02*
X208272Y230762D01*
G01X217414Y215937D02*
X217636Y215615D01*
G01X217623Y214640D02*
X217369Y215009D01*
G01X204343Y231737D02*
X204597Y231368D01*
G01X204551Y230441D02*
X204330Y230762D01*
G01X213482Y215937D02*
X213703Y215615D01*
G01X213690Y214640D02*
X213436Y215009D01*
G01X263611Y230441D02*
X263621Y230393D01*
G01X264658Y215937D02*
X264649Y215984D01*
G01X259679Y230393D02*
X259670Y230441D01*
G01X260717Y215984D02*
X260726Y215937D01*
G01X255737Y230441D02*
X255747Y230393D01*
G01X256784Y215937D02*
X256775Y215984D01*
G01X251805Y230393D02*
X251796Y230441D01*
G01X200411Y231737D02*
X200665Y231368D01*
G01X200619Y230441D02*
X200398Y230762D01*
G01X209540Y215937D02*
X209762Y215615D01*
G01X209749Y214640D02*
X209495Y215009D01*
G01X196469Y231737D02*
X196723Y231368D01*
G01X196677Y230441D02*
X196456Y230762D01*
G01X205608Y215937D02*
X205829Y215615D01*
G01X205816Y214640D02*
X205562Y215009D01*
G01X192537Y231737D02*
X192791Y231368D01*
G01X192745Y230441D02*
X192524Y230762D01*
G01X201666Y215937D02*
X201888Y215615D01*
G01X201875Y214640D02*
X201621Y215009D01*
G01X188849Y231368D02*
X188595Y231737D01*
G01X188584Y230760D02*
X188803Y230441D01*
G01X197734Y215937D02*
X197955Y215615D01*
G01X197942Y214640D02*
X197688Y215009D01*
G01X193792Y215937D02*
X194014Y215615D01*
G01X194001Y214640D02*
X193747Y215009D01*
G01X190080Y215617D02*
X189860Y215937D01*
G01X189814Y215009D02*
X190068Y214640D01*
G01X252842Y215984D02*
X252852Y215937D01*
G01X247863Y230441D02*
X247873Y230393D01*
G01X248910Y215937D02*
X248901Y215984D01*
G01X243921Y230441D02*
X243931Y230393D01*
G01X244978Y215937D02*
X244968Y215984D01*
G01X239989Y230441D02*
X239999Y230393D01*
G01X241036Y215937D02*
X241027Y215984D01*
G01X236047Y230441D02*
X236057Y230393D01*
G01X237104Y215937D02*
X237094Y215984D01*
G01X232115Y230441D02*
X232125Y230393D01*
G01X233162Y215937D02*
X233153Y215984D01*
G01X228173Y230441D02*
X228183Y230393D01*
G01X229230Y215937D02*
X229220Y215984D01*
G01X264928Y219379D02*
X264978Y220365D01*
G01X264976Y221327D02*
X264925Y220340D01*
G01X265014Y225353D02*
X265150Y231260D01*
G01X265145Y232147D02*
X265009Y226239D01*
G01X263125Y214231D02*
X263261Y220138D01*
G01X263256Y221024D02*
X263120Y215117D01*
G01X261072Y225353D02*
X261208Y231260D01*
G01X261203Y232147D02*
X261067Y226239D01*
G01X264626Y215984D02*
X264613Y215009D01*
G01X263644Y230393D02*
X263657Y231368D01*
G01X260694Y215984D02*
X260680Y215009D01*
G01X259702Y230393D02*
X259715Y231368D01*
G01X266694Y214822D02*
Y213838D01*
G01Y232539D02*
Y231555D01*
G01X266689Y232539D02*
Y231555D01*
G01X266655Y216515D02*
Y212342D01*
G01Y234035D02*
Y229862D01*
G01X265552D02*
Y234035D01*
G01Y212342D02*
Y216515D01*
G01X265517Y232539D02*
Y231555D01*
G01X265513Y214822D02*
Y213838D01*
G01X265508Y214822D02*
Y213838D01*
G01X265316Y215984D02*
Y209901D01*
G01Y236476D02*
Y230393D01*
G01X265237Y213838D02*
Y232539D01*
G01X265163Y232538D02*
Y231553D01*
G01X265154Y214824D02*
Y213840D01*
G01X264962Y227698D02*
Y232539D01*
G01Y213838D02*
Y218680D01*
G01X264888Y230760D02*
Y231750D01*
G01X264878Y214627D02*
Y215617D01*
G01X264804Y218760D02*
Y217696D01*
G01Y228681D02*
Y227618D01*
G01X264529D02*
Y228602D01*
G01Y218760D02*
Y217775D01*
G01X263741Y227618D02*
Y228602D01*
G01Y217775D02*
Y218760D01*
G01X263466D02*
Y217696D01*
G01Y228681D02*
Y227618D01*
G01X263391Y231750D02*
Y230760D01*
G01X263382Y215617D02*
Y214627D01*
G01X263308Y227698D02*
Y232539D01*
G01Y213838D02*
Y218680D01*
G01X263116Y231553D02*
Y232538D01*
G01X263107Y213840D02*
Y214824D01*
G01X263032Y232539D02*
Y213838D01*
G01X262954Y215984D02*
Y209901D01*
G01Y236476D02*
Y230393D01*
G01X262762Y232539D02*
Y231555D01*
G01X262757Y232539D02*
Y231555D01*
G01X262752Y214822D02*
Y213838D01*
G01X262717Y216515D02*
Y212342D01*
G01Y234035D02*
Y229862D01*
G01X261615D02*
Y234035D01*
G01Y212342D02*
Y216515D01*
G01X261580Y214822D02*
Y213838D01*
G01X261576Y214822D02*
Y213838D01*
G01Y232539D02*
Y231555D01*
G01X261379Y215984D02*
Y209901D01*
G01Y236476D02*
Y230393D01*
G01X261300Y213838D02*
Y232539D01*
G01X261221Y214824D02*
Y213840D01*
G01Y232538D02*
Y231553D01*
G01X261025Y231555D02*
Y236396D01*
G01Y209981D02*
Y214822D01*
G01X260946Y230760D02*
Y231750D01*
G01Y214627D02*
Y215617D01*
G01X260867Y210965D02*
Y209901D01*
G01Y236476D02*
Y235412D01*
G01X260592Y209901D02*
Y210885D01*
G01Y236476D02*
Y235492D01*
G01X259804Y210885D02*
Y209901D01*
G01Y236476D02*
Y235492D01*
G01X259529Y210965D02*
Y209901D01*
G01Y236476D02*
Y235412D01*
G01X259450Y215617D02*
Y214627D01*
G01Y231750D02*
Y230760D01*
G01X259371Y231555D02*
Y236396D01*
G01Y209981D02*
Y214822D01*
G01X259174Y213840D02*
Y214824D01*
G01Y231553D02*
Y232538D01*
G01X259095Y232539D02*
Y213838D01*
G01X259017Y215984D02*
Y209901D01*
G01Y236476D02*
Y230393D01*
G01X258820Y214822D02*
Y213838D01*
G01Y232539D02*
Y231555D01*
G01X258815Y232539D02*
Y231555D01*
G01X258780Y216515D02*
Y212342D01*
G01Y234035D02*
Y229862D01*
G01X257678D02*
Y234035D01*
G01Y212342D02*
Y216515D01*
G01X257643Y232539D02*
Y231555D01*
G01X257639Y214822D02*
Y213838D01*
G01X257634Y214822D02*
Y213838D01*
G01X257442Y215984D02*
Y209901D01*
G01Y236476D02*
Y230393D01*
G01X257363Y213838D02*
Y232539D01*
G01X257289Y232538D02*
Y231553D01*
G01X257280Y214824D02*
Y213840D01*
G01X264622Y231368D02*
X264635Y230393D01*
G01X263647Y215009D02*
X263634Y215984D01*
G01X260680Y231368D02*
X260694Y230393D01*
G01X259715Y215009D02*
X259702Y215984D01*
G01X256748Y231368D02*
X256761Y230393D01*
G01X255773Y215009D02*
X255760Y215984D01*
G01X265141Y215117D02*
X265004Y221024D01*
G01X265000Y220138D02*
X265136Y214231D01*
G01X263270Y226239D02*
X263134Y232147D01*
G01X263129Y231260D02*
X263265Y225353D01*
G01X261208Y215117D02*
X261072Y221024D01*
G01X261067Y220138D02*
X261203Y214231D01*
G01X259328Y226239D02*
X259192Y232147D01*
G01X259187Y231260D02*
X259324Y225353D01*
G01X257267Y215117D02*
X257130Y221024D01*
G01X257126Y220138D02*
X257262Y214231D01*
G01X255396Y226239D02*
X255260Y232147D01*
G01X255255Y231260D02*
X255391Y225353D01*
G01X264988Y226012D02*
X264937Y226999D01*
G01X264935Y226037D02*
X264985Y225050D01*
G01X263335Y220340D02*
X263284Y221327D01*
G01X263282Y220365D02*
X263333Y219379D01*
G01X261046Y226012D02*
X260995Y226999D01*
G01X260993Y226037D02*
X261044Y225050D01*
G01X259403Y220340D02*
X259352Y221327D01*
G01X259350Y220365D02*
X259400Y219379D01*
G01X257114Y226012D02*
X257063Y226999D01*
G01X257061Y226037D02*
X257111Y225050D01*
G01X255461Y220340D02*
X255410Y221327D01*
G01X255408Y220365D02*
X255459Y219379D01*
G01X253172Y226012D02*
X253121Y226999D01*
G01X253119Y226037D02*
X253170Y225050D01*
G01X251529Y220340D02*
X251478Y221327D01*
G01X251476Y220365D02*
X251526Y219379D01*
G01X224241Y230441D02*
X224251Y230393D01*
G01X225288Y215937D02*
X225279Y215984D01*
G01X220299Y230441D02*
X220309Y230393D01*
G01X221356Y215937D02*
X221346Y215984D01*
G01X216367Y230441D02*
X216377Y230393D01*
G01X217414Y215937D02*
X217405Y215984D01*
G01X212425Y230441D02*
X212435Y230393D01*
G01X213482Y215937D02*
X213472Y215984D01*
G01X208493Y230441D02*
X208503Y230393D01*
G01X209540Y215937D02*
X209531Y215984D01*
G01X204551Y230441D02*
X204561Y230393D01*
G01X205608Y215937D02*
X205598Y215984D01*
G01X263611D02*
X263602Y215937D01*
G01X264658Y230393D02*
X264668Y230441D01*
G01X259670Y215937D02*
X259679Y215984D01*
G01X260726Y230441D02*
X260717Y230393D01*
G01X263294Y225050D02*
X263344Y226037D01*
G01X263342Y226999D02*
X263291Y226012D01*
G01X260995Y219379D02*
X261046Y220365D01*
G01X261044Y221327D02*
X260993Y220340D01*
G01X259352Y225050D02*
X259403Y226037D01*
G01X259400Y226999D02*
X259350Y226012D01*
G01X257054Y219379D02*
X257104Y220365D01*
G01X257102Y221327D02*
X257051Y220340D01*
G01X255420Y225050D02*
X255470Y226037D01*
G01X255468Y226999D02*
X255417Y226012D01*
G01X253121Y219379D02*
X253172Y220365D01*
G01X253170Y221327D02*
X253119Y220340D01*
G01X251478Y225050D02*
X251529Y226037D01*
G01X251526Y226999D02*
X251476Y226012D01*
G01X249180Y219379D02*
X249230Y220365D01*
G01X249228Y221327D02*
X249177Y220340D01*
G01X247546Y225050D02*
X247596Y226037D01*
G01X247594Y226999D02*
X247543Y226012D01*
G01X245247Y219379D02*
X245298Y220365D01*
G01X245296Y221327D02*
X245245Y220340D01*
G01X243604Y225050D02*
X243655Y226037D01*
G01X243652Y226999D02*
X243602Y226012D01*
G01X241306Y219379D02*
X241356Y220365D01*
G01X241354Y221327D02*
X241303Y220340D01*
G01X259192Y214231D02*
X259328Y220138D01*
G01X259324Y221024D02*
X259187Y215117D01*
G01X257140Y225353D02*
X257276Y231260D01*
G01X257271Y232147D02*
X257135Y226239D01*
G01X255251Y214231D02*
X255387Y220138D01*
G01X255382Y221024D02*
X255246Y215117D01*
G01X253198Y225353D02*
X253334Y231260D01*
G01X253329Y232147D02*
X253193Y226239D01*
G01X251318Y214231D02*
X251454Y220138D01*
G01X251450Y221024D02*
X251313Y215117D01*
G01X249266Y225353D02*
X249402Y231260D01*
G01X249397Y232147D02*
X249261Y226239D01*
G01X247376Y214231D02*
X247513Y220138D01*
G01X247508Y221024D02*
X247372Y215117D01*
G01X245324Y225353D02*
X245460Y231260D01*
G01X245455Y232147D02*
X245319Y226239D01*
G01X243444Y214231D02*
X243580Y220138D01*
G01X243576Y221024D02*
X243439Y215117D01*
G01X241392Y225353D02*
X241528Y231260D01*
G01X241523Y232147D02*
X241387Y226239D01*
G01X239502Y214231D02*
X239639Y220138D01*
G01X239634Y221024D02*
X239498Y215117D01*
G01X237450Y225353D02*
X237586Y231260D01*
G01X237581Y232147D02*
X237445Y226239D01*
G01X256752Y215984D02*
X256739Y215009D01*
G01X255770Y230393D02*
X255783Y231368D01*
G01X252820Y215984D02*
X252806Y215009D01*
G01X251828Y230393D02*
X251841Y231368D01*
G01X248878Y215984D02*
X248865Y215009D01*
G01X247896Y230393D02*
X247909Y231368D01*
G01X244946Y215984D02*
X244932Y215009D01*
G01X243954Y230393D02*
X243967Y231368D01*
G01X241004Y215984D02*
X240991Y215009D01*
G01X240022Y230393D02*
X240035Y231368D01*
G01X237072Y215984D02*
X237058Y215009D01*
G01X236080Y230393D02*
X236093Y231368D01*
G01X257088Y227698D02*
Y232539D01*
G01Y213838D02*
Y218680D01*
G01X257014Y230760D02*
Y231750D01*
G01X257004Y214627D02*
Y215617D01*
G01X256930Y218760D02*
Y217696D01*
G01Y228681D02*
Y227618D01*
G01X256655D02*
Y228602D01*
G01Y218760D02*
Y217775D01*
G01X255867Y227618D02*
Y228602D01*
G01Y218760D02*
Y217775D01*
G01X255592Y218760D02*
Y217696D01*
G01Y228681D02*
Y227618D01*
G01X255517Y231750D02*
Y230760D01*
G01X255508Y215617D02*
Y214627D01*
G01X255473Y208523D02*
Y203011D01*
G01X255434Y227698D02*
Y232539D01*
G01Y213838D02*
Y218680D01*
G01X255242Y231553D02*
Y232538D01*
G01X255233Y213840D02*
Y214824D01*
G01X255158Y232539D02*
Y213838D01*
G01X255080Y215984D02*
Y209901D01*
G01Y236476D02*
Y230393D01*
G01X254888Y232539D02*
Y231555D01*
G01X254883Y232539D02*
Y231555D01*
G01X254878Y214822D02*
Y213838D01*
G01X254843Y216515D02*
Y212342D01*
G01Y234035D02*
Y229862D01*
G01X253741D02*
Y234035D01*
G01Y212342D02*
Y216515D01*
G01X253706Y214822D02*
Y213838D01*
G01X253702Y214822D02*
Y213838D01*
G01Y232539D02*
Y231555D01*
G01X253505Y215984D02*
Y209901D01*
G01Y236476D02*
Y230393D01*
G01X253426Y213838D02*
Y232539D01*
G01X253347Y214824D02*
Y213840D01*
G01Y232538D02*
Y231553D01*
G01X253151Y231555D02*
Y236396D01*
G01Y209981D02*
Y214822D01*
G01X253072Y230760D02*
Y231750D01*
G01Y214627D02*
Y215617D01*
G01X252993Y210965D02*
Y209901D01*
G01Y236476D02*
Y235412D01*
G01X252717Y209901D02*
Y210885D01*
G01Y236476D02*
Y235492D01*
G01X252324Y208523D02*
Y203011D01*
G01X251930Y210885D02*
Y209901D01*
G01Y236476D02*
Y235492D01*
G01X251655Y210965D02*
Y209901D01*
G01Y236476D02*
Y235412D01*
G01X251576Y215617D02*
Y214627D01*
G01Y231750D02*
Y230760D01*
G01X251497Y231555D02*
Y236396D01*
G01Y209981D02*
Y214822D01*
G01X251300Y213840D02*
Y214824D01*
G01Y231553D02*
Y232538D01*
G01X251221Y232539D02*
Y213838D01*
G01X251143Y215984D02*
Y209901D01*
G01Y236476D02*
Y230393D01*
G01X250946Y214822D02*
Y213838D01*
G01Y232539D02*
Y231555D01*
G01X250941Y232539D02*
Y231555D01*
G01X250906Y216515D02*
Y212342D01*
G01Y234035D02*
Y229862D01*
G01X249804D02*
Y234035D01*
G01Y212342D02*
Y216515D01*
G01X249769Y232539D02*
Y231555D01*
G01X249765Y214822D02*
Y213838D01*
G01X249760Y214822D02*
Y213838D01*
G01X249568Y215984D02*
Y209901D01*
G01Y236476D02*
Y230393D01*
G01X249489Y213838D02*
Y232539D01*
G01X249415Y232538D02*
Y231553D01*
G01X249406Y214824D02*
Y213840D01*
G01X249214Y227698D02*
Y232539D01*
G01Y213838D02*
Y218680D01*
G01X249139Y230760D02*
Y231750D01*
G01X249130Y214627D02*
Y215617D01*
G01X249056Y218760D02*
Y217696D01*
G01Y228681D02*
Y227618D01*
G01X248780D02*
Y228602D01*
G01Y218760D02*
Y217775D01*
G01X248387Y208523D02*
Y203011D01*
G01X247993Y227618D02*
Y228602D01*
G01Y218760D02*
Y217775D01*
G01X247717Y218760D02*
Y217696D01*
G01Y228681D02*
Y227618D01*
G01X247643Y231750D02*
Y230760D01*
G01X247634Y215617D02*
Y214627D01*
G01X247560Y227698D02*
Y232539D01*
G01Y213838D02*
Y218680D01*
G01X247368Y231553D02*
Y232538D01*
G01X247359Y213840D02*
Y214824D01*
G01X247284Y232539D02*
Y213838D01*
G01X247206Y215984D02*
Y209901D01*
G01Y236476D02*
Y230393D01*
G01X247014Y232539D02*
Y231555D01*
G01X247009Y232539D02*
Y231555D01*
G01X247004Y214822D02*
Y213838D01*
G01X246969Y216515D02*
Y212342D01*
G01Y234035D02*
Y229862D01*
G01X245867D02*
Y234035D01*
G01Y212342D02*
Y216515D01*
G01X245832Y214822D02*
Y213838D01*
G01X245828Y214822D02*
Y213838D01*
G01Y232539D02*
Y231555D01*
G01X245631Y215984D02*
Y209901D01*
G01Y236476D02*
Y230393D01*
G01X245552Y213838D02*
Y232539D01*
G01X245473Y214824D02*
Y213840D01*
G01Y232538D02*
Y231553D01*
G01X245277Y231555D02*
Y236396D01*
G01Y209981D02*
Y214822D01*
G01X245237Y208523D02*
Y203011D01*
G01X245198Y230760D02*
Y231750D01*
G01Y214627D02*
Y215617D01*
G01X245119Y210965D02*
Y209901D01*
G01Y236476D02*
Y235412D01*
G01X244843Y210885D02*
Y209901D01*
G01Y236476D02*
Y235492D01*
G01X244056D02*
Y236476D01*
G01Y210885D02*
Y209901D01*
G01X243780Y210965D02*
Y209901D01*
G01Y236476D02*
Y235412D01*
G01X243702Y215617D02*
Y214627D01*
G01Y231750D02*
Y230760D01*
G01X243623Y231555D02*
Y236396D01*
G01Y209981D02*
Y214822D01*
G01X243426Y231553D02*
Y232538D01*
G01Y213840D02*
Y214824D01*
G01X243347Y232539D02*
Y213838D01*
G01X243269Y215984D02*
Y209901D01*
G01Y236476D02*
Y230393D01*
G01X243072Y214822D02*
Y213838D01*
G01Y232539D02*
Y231555D01*
G01X243067Y232539D02*
Y231555D01*
G01X243032Y216515D02*
Y212342D01*
G01Y234035D02*
Y229862D01*
G01X241930D02*
Y234035D01*
G01Y212342D02*
Y216515D01*
G01X241895Y232539D02*
Y231555D01*
G01X241891Y214822D02*
Y213838D01*
G01X241886Y214822D02*
Y213838D01*
G01X241694Y215984D02*
Y209901D01*
G01Y236476D02*
Y230393D01*
G01X241615Y213838D02*
Y232539D01*
G01X241541Y232538D02*
Y231553D01*
G01X241532Y214824D02*
Y213840D01*
G01X241340Y227698D02*
Y232539D01*
G01Y213838D02*
Y218680D01*
G01X241265Y230760D02*
Y231750D01*
G01X241256Y214627D02*
Y215617D01*
G01X241182Y218760D02*
Y217696D01*
G01Y228681D02*
Y227618D01*
G01X240906Y218760D02*
Y217775D01*
G01Y228602D02*
Y227618D01*
G01X240119Y218760D02*
Y217775D01*
G01Y228602D02*
Y227618D01*
G01X239843Y218760D02*
Y217696D01*
G01Y228681D02*
Y227618D01*
G01X239769Y231750D02*
Y230760D01*
G01X239760Y215617D02*
Y214627D01*
G01X239686Y227698D02*
Y232539D01*
G01Y213838D02*
Y218680D01*
G01X239494Y231553D02*
Y232538D01*
G01X239484Y213840D02*
Y214824D01*
G01X239410Y232539D02*
Y213838D01*
G01X239332Y215984D02*
Y209901D01*
G01Y236476D02*
Y230393D01*
G01X239139Y232539D02*
Y231555D01*
G01X239135Y232539D02*
Y231555D01*
G01X239130Y214822D02*
Y213838D01*
G01X239095Y216515D02*
Y212342D01*
G01Y234035D02*
Y229862D01*
G01X237993D02*
Y234035D01*
G01Y212342D02*
Y216515D01*
G01X237958Y214822D02*
Y213838D01*
G01X237954Y214822D02*
Y213838D01*
G01Y232539D02*
Y231555D01*
G01X237757Y215984D02*
Y209901D01*
G01Y236476D02*
Y230393D01*
G01X237678Y213838D02*
Y232539D01*
G01X237599Y214824D02*
Y213840D01*
G01Y232538D02*
Y231553D01*
G01X237403Y231555D02*
Y236396D01*
G01Y209981D02*
Y214822D01*
G01X237324Y230760D02*
Y231750D01*
G01Y214627D02*
Y215617D01*
G01X237245Y210965D02*
Y209901D01*
G01Y236476D02*
Y235412D01*
G01X236969Y210885D02*
Y209901D01*
G01Y236476D02*
Y235492D01*
G01X236182D02*
Y236476D01*
G01Y210885D02*
Y209901D01*
G01X235906Y210965D02*
Y209901D01*
G01Y236476D02*
Y235412D01*
G01X235828Y215617D02*
Y214627D01*
G01Y231750D02*
Y230760D01*
G01X235749Y231555D02*
Y236396D01*
G01Y209981D02*
Y214822D01*
G01X235552Y231553D02*
Y232538D01*
G01Y213840D02*
Y214824D01*
G01X235473Y232539D02*
Y213838D01*
G01X235395Y215984D02*
Y209901D01*
G01Y236476D02*
Y230393D01*
G01X235198Y214822D02*
Y213838D01*
G01Y232539D02*
Y231555D01*
G01X235193Y232539D02*
Y231555D01*
G01X235158Y216515D02*
Y212342D01*
G01Y234035D02*
Y229862D01*
G01X234056D02*
Y234035D01*
G01Y212342D02*
Y216515D01*
G01X234021Y232539D02*
Y231555D01*
G01X234017Y214822D02*
Y213838D01*
G01X234012Y214822D02*
Y213838D01*
G01X233820Y215984D02*
Y209901D01*
G01Y236476D02*
Y230393D01*
G01X233741Y213838D02*
Y232539D01*
G01X233667Y232538D02*
Y231553D01*
G01X233658Y214824D02*
Y213840D01*
G01X233466Y227698D02*
Y232539D01*
G01Y213838D02*
Y218680D01*
G01X233391Y230760D02*
Y231750D01*
G01X233382Y214627D02*
Y215617D01*
G01X233308Y218760D02*
Y217696D01*
G01Y228681D02*
Y227618D01*
G01X233032D02*
Y228602D01*
G01Y218760D02*
Y217775D01*
G01X252806Y231368D02*
X252820Y230393D01*
G01X251841Y215009D02*
X251828Y215984D01*
G01X248874Y231368D02*
X248887Y230393D01*
G01X247899Y215009D02*
X247886Y215984D01*
G01X244932Y231368D02*
X244946Y230393D01*
G01X243967Y215009D02*
X243954Y215984D01*
G01X241000Y231368D02*
X241013Y230393D01*
G01X240025Y215009D02*
X240012Y215984D01*
G01X237058Y231368D02*
X237072Y230393D01*
G01X236093Y215009D02*
X236080Y215984D01*
G01X233126Y231368D02*
X233139Y230393D01*
G01X232151Y215009D02*
X232138Y215984D01*
G01X253334Y215117D02*
X253198Y221024D01*
G01X253193Y220138D02*
X253329Y214231D01*
G01X251454Y226239D02*
X251318Y232147D01*
G01X251313Y231260D02*
X251450Y225353D01*
G01X249393Y215117D02*
X249256Y221024D01*
G01X249252Y220138D02*
X249388Y214231D01*
G01X247522Y226239D02*
X247386Y232147D01*
G01X247381Y231260D02*
X247517Y225353D01*
G01X245460Y215117D02*
X245324Y221024D01*
G01X245319Y220138D02*
X245455Y214231D01*
G01X243580Y226239D02*
X243444Y232147D01*
G01X243439Y231260D02*
X243576Y225353D01*
G01X241519Y215117D02*
X241382Y221024D01*
G01X241378Y220138D02*
X241514Y214231D01*
G01X239648Y226239D02*
X239512Y232147D01*
G01X239507Y231260D02*
X239643Y225353D01*
G01X237586Y215117D02*
X237450Y221024D01*
G01X237445Y220138D02*
X237581Y214231D01*
G01X235706Y226239D02*
X235570Y232147D01*
G01X235565Y231260D02*
X235702Y225353D01*
G01X233645Y215117D02*
X233508Y221024D01*
G01X233503Y220138D02*
X233640Y214231D01*
G01X231774Y226239D02*
X231638Y232147D01*
G01X231633Y231260D02*
X231769Y225353D01*
G01X229712Y215117D02*
X229576Y221024D01*
G01X249240Y226012D02*
X249189Y226999D01*
G01X249187Y226037D02*
X249237Y225050D01*
G01X247587Y220340D02*
X247536Y221327D01*
G01X247534Y220365D02*
X247585Y219379D01*
G01X245298Y226012D02*
X245247Y226999D01*
G01X245245Y226037D02*
X245296Y225050D01*
G01X243655Y220340D02*
X243604Y221327D01*
G01X243602Y220365D02*
X243652Y219379D01*
G01X241366Y226012D02*
X241315Y226999D01*
G01X241313Y226037D02*
X241363Y225050D01*
G01X239713Y220340D02*
X239662Y221327D01*
G01X239660Y220365D02*
X239711Y219379D01*
G01X237424Y226012D02*
X237373Y226999D01*
G01X237371Y226037D02*
X237421Y225050D01*
G01X235781Y220340D02*
X235730Y221327D01*
G01X235728Y220365D02*
X235778Y219379D01*
G01X233491Y226012D02*
X233441Y226999D01*
G01X233439Y226037D02*
X233489Y225050D01*
G01X231839Y220340D02*
X231788Y221327D01*
G01X231786Y220365D02*
X231837Y219379D01*
G01X229550Y226012D02*
X229499Y226999D01*
G01X229497Y226037D02*
X229547Y225050D01*
G01X227907Y220340D02*
X227856Y221327D01*
G01X227854Y220365D02*
X227904Y219379D01*
G01X225617Y226012D02*
X225567Y226999D01*
G01X225565Y226037D02*
X225615Y225050D01*
G01X200619Y230441D02*
X200629Y230393D01*
G01X201666Y215937D02*
X201657Y215984D01*
G01X196677Y230441D02*
X196687Y230393D01*
G01X197734Y215937D02*
X197724Y215984D01*
G01X192745Y230441D02*
X192755Y230393D01*
G01X193792Y215937D02*
X193783Y215984D01*
G01X188813Y230393D02*
X188803Y230441D01*
G01X189850Y215984D02*
X189860Y215937D01*
G01X255737Y215984D02*
X255728Y215937D01*
G01X256784Y230393D02*
X256794Y230441D01*
G01X251796Y215937D02*
X251805Y215984D01*
G01X252852Y230441D02*
X252842Y230393D01*
G01X247863Y215984D02*
X247854Y215937D01*
G01X248910Y230393D02*
X248920Y230441D01*
G01X243931Y215984D02*
X243921Y215937D01*
G01X244968Y230393D02*
X244978Y230441D01*
G01X239989Y215984D02*
X239980Y215937D01*
G01X241036Y230393D02*
X241046Y230441D01*
G01X236057Y215984D02*
X236047Y215937D01*
G01X237094Y230393D02*
X237104Y230441D01*
G01X239672Y225050D02*
X239722Y226037D01*
G01X239720Y226999D02*
X239669Y226012D01*
G01X237373Y219379D02*
X237424Y220365D01*
G01X237421Y221327D02*
X237371Y220340D01*
G01X235730Y225050D02*
X235781Y226037D01*
G01X235778Y226999D02*
X235728Y226012D01*
G01X233432Y219379D02*
X233482Y220365D01*
G01X233480Y221327D02*
X233429Y220340D01*
G01X231798Y225050D02*
X231848Y226037D01*
G01X231846Y226999D02*
X231795Y226012D01*
G01X229499Y219379D02*
X229550Y220365D01*
G01X229547Y221327D02*
X229497Y220340D01*
G01X227856Y225050D02*
X227907Y226037D01*
G01X227904Y226999D02*
X227854Y226012D01*
G01X225558Y219379D02*
X225608Y220365D01*
G01X225606Y221327D02*
X225555Y220340D01*
G01X223924Y225050D02*
X223974Y226037D01*
G01X223972Y226999D02*
X223921Y226012D01*
G01X221625Y219379D02*
X221676Y220365D01*
G01X221673Y221327D02*
X221623Y220340D01*
G01X219982Y225050D02*
X220032Y226037D01*
G01X220030Y226999D02*
X219980Y226012D01*
G01X217684Y219379D02*
X217734Y220365D01*
G01X217732Y221327D02*
X217681Y220340D01*
G01X216050Y225050D02*
X216100Y226037D01*
G01X216098Y226999D02*
X216047Y226012D01*
G01X235570Y214231D02*
X235706Y220138D01*
G01X235702Y221024D02*
X235565Y215117D01*
G01X233518Y225353D02*
X233654Y231260D01*
G01X233649Y232147D02*
X233513Y226239D01*
G01X231628Y214231D02*
X231765Y220138D01*
G01X231760Y221024D02*
X231624Y215117D01*
G01X229576Y225353D02*
X229712Y231260D01*
G01X229707Y232147D02*
X229571Y226239D01*
G01X227696Y214231D02*
X227832Y220138D01*
G01X227828Y221024D02*
X227691Y215117D01*
G01X225644Y225353D02*
X225780Y231260D01*
G01X225775Y232147D02*
X225639Y226239D01*
G01X223754Y214231D02*
X223891Y220138D01*
G01X223886Y221024D02*
X223750Y215117D01*
G01X221702Y225353D02*
X221838Y231260D01*
G01X221833Y232147D02*
X221697Y226239D01*
G01X219822Y214231D02*
X219958Y220138D01*
G01X219954Y221024D02*
X219817Y215117D01*
G01X217770Y225353D02*
X217906Y231260D01*
G01X217901Y232147D02*
X217765Y226239D01*
G01X215880Y214231D02*
X216017Y220138D01*
G01X216012Y221024D02*
X215876Y215117D01*
G01X213828Y225353D02*
X213964Y231260D01*
G01X213959Y232147D02*
X213823Y226239D01*
G01X211948Y214231D02*
X212084Y220138D01*
G01X212080Y221024D02*
X211943Y215117D01*
G01X233130Y215984D02*
X233117Y215009D01*
G01X232148Y230393D02*
X232161Y231368D01*
G01X229198Y215984D02*
X229184Y215009D01*
G01X228206Y230393D02*
X228219Y231368D01*
G01X225256Y215984D02*
X225243Y215009D01*
G01X224274Y230393D02*
X224287Y231368D01*
G01X221324Y215984D02*
X221310Y215009D01*
G01X220332Y230393D02*
X220345Y231368D01*
G01X217382Y215984D02*
X217369Y215009D01*
G01X216400Y230393D02*
X216413Y231368D01*
G01X213450Y215984D02*
X213436Y215009D01*
G01X212458Y230393D02*
X212471Y231368D01*
G01X232245Y227618D02*
Y228602D01*
G01Y217775D02*
Y218760D01*
G01X231969D02*
Y217696D01*
G01Y228681D02*
Y227618D01*
G01X231895Y231750D02*
Y230760D01*
G01X231886Y215617D02*
Y214627D01*
G01X231851Y208523D02*
Y203011D01*
G01X231812Y227698D02*
Y232539D01*
G01Y213838D02*
Y218680D01*
G01X231620Y231553D02*
Y232538D01*
G01X231610Y213840D02*
Y214824D01*
G01X231536Y232539D02*
Y213838D01*
G01X231458Y215984D02*
Y209901D01*
G01Y236476D02*
Y230393D01*
G01X231265Y232539D02*
Y231555D01*
G01X231261Y232539D02*
Y231555D01*
G01X231256Y214822D02*
Y213838D01*
G01X231221Y216515D02*
Y212342D01*
G01Y234035D02*
Y229862D01*
G01X230119D02*
Y234035D01*
G01Y212342D02*
Y216515D01*
G01X230084Y214822D02*
Y213838D01*
G01X230080Y214822D02*
Y213838D01*
G01Y232539D02*
Y231555D01*
G01X229883Y215984D02*
Y209901D01*
G01Y236476D02*
Y230393D01*
G01X229804Y213838D02*
Y232539D01*
G01X229725Y214824D02*
Y213840D01*
G01Y232538D02*
Y231553D01*
G01X229529Y231555D02*
Y236396D01*
G01Y209981D02*
Y214822D01*
G01X229450Y230760D02*
Y231750D01*
G01Y214627D02*
Y215617D01*
G01X229371Y210965D02*
Y209901D01*
G01Y236476D02*
Y235412D01*
G01X229095Y210885D02*
Y209901D01*
G01Y236476D02*
Y235492D01*
G01X228702Y208523D02*
Y203011D01*
G01X228308Y235492D02*
Y236476D01*
G01Y210885D02*
Y209901D01*
G01X228032Y210965D02*
Y209901D01*
G01Y236476D02*
Y235412D01*
G01X227954Y215617D02*
Y214627D01*
G01Y231750D02*
Y230760D01*
G01X227875Y231555D02*
Y236396D01*
G01Y209981D02*
Y214822D01*
G01X227678Y231553D02*
Y232538D01*
G01Y213840D02*
Y214824D01*
G01X227599Y232539D02*
Y213838D01*
G01X227521Y215984D02*
Y209901D01*
G01Y236476D02*
Y230393D01*
G01X227324Y214822D02*
Y213838D01*
G01Y232539D02*
Y231555D01*
G01X227319Y232539D02*
Y231555D01*
G01X227284Y216515D02*
Y212342D01*
G01Y234035D02*
Y229862D01*
G01X226182D02*
Y234035D01*
G01Y212342D02*
Y216515D01*
G01X226147Y232539D02*
Y231555D01*
G01X226143Y214822D02*
Y213838D01*
G01X226138Y214822D02*
Y213838D01*
G01X225946Y215984D02*
Y209901D01*
G01Y236476D02*
Y230393D01*
G01X225867Y213838D02*
Y232539D01*
G01X225793Y232538D02*
Y231553D01*
G01X225784Y214824D02*
Y213840D01*
G01X225592Y227698D02*
Y232539D01*
G01Y213838D02*
Y218680D01*
G01X225517Y230760D02*
Y231750D01*
G01X225508Y214627D02*
Y215617D01*
G01X225434Y218760D02*
Y217696D01*
G01Y228681D02*
Y227618D01*
G01X225158D02*
Y228602D01*
G01Y218760D02*
Y217775D01*
G01X224765Y208523D02*
Y203011D01*
G01X224371Y227618D02*
Y228602D01*
G01Y217775D02*
Y218760D01*
G01X224095D02*
Y217696D01*
G01Y228681D02*
Y227618D01*
G01X224021Y231750D02*
Y230760D01*
G01X224012Y215617D02*
Y214627D01*
G01X223938Y227698D02*
Y232539D01*
G01Y213838D02*
Y218680D01*
G01X223746Y231553D02*
Y232538D01*
G01X223736Y213840D02*
Y214824D01*
G01X223662Y232539D02*
Y213838D01*
G01X223584Y215984D02*
Y209901D01*
G01Y236476D02*
Y230393D01*
G01X223391Y232539D02*
Y231555D01*
G01X223387Y232539D02*
Y231555D01*
G01X223382Y214822D02*
Y213838D01*
G01X223347Y216515D02*
Y212342D01*
G01Y234035D02*
Y229862D01*
G01X222245D02*
Y234035D01*
G01Y212342D02*
Y216515D01*
G01X222210Y214822D02*
Y213838D01*
G01X222206Y214822D02*
Y213838D01*
G01Y232539D02*
Y231555D01*
G01X222009Y215984D02*
Y209901D01*
G01Y236476D02*
Y230393D01*
G01X221930Y213838D02*
Y232539D01*
G01X221851Y214824D02*
Y213840D01*
G01Y232538D02*
Y231553D01*
G01X221655Y231555D02*
Y236396D01*
G01Y209981D02*
Y214822D01*
G01X221615Y208523D02*
Y203011D01*
G01X221576Y230760D02*
Y231750D01*
G01Y214627D02*
Y215617D01*
G01X221497Y210965D02*
Y209901D01*
G01Y236476D02*
Y235412D01*
G01X221221Y210885D02*
Y209901D01*
G01Y236476D02*
Y235492D01*
G01X220434D02*
Y236476D01*
G01Y210885D02*
Y209901D01*
G01X220158Y210965D02*
Y209901D01*
G01Y236476D02*
Y235412D01*
G01X220080Y215617D02*
Y214627D01*
G01Y231750D02*
Y230760D01*
G01X220001Y231555D02*
Y236396D01*
G01Y209981D02*
Y214822D01*
G01X219804Y231553D02*
Y232538D01*
G01Y213840D02*
Y214824D01*
G01X219725Y232539D02*
Y213838D01*
G01X219647Y215984D02*
Y209901D01*
G01Y236476D02*
Y230393D01*
G01X219450Y214822D02*
Y213838D01*
G01Y232539D02*
Y231555D01*
G01X219445Y232539D02*
Y231555D01*
G01X219410Y216515D02*
Y212342D01*
G01Y234035D02*
Y229862D01*
G01X218308D02*
Y234035D01*
G01Y212342D02*
Y216515D01*
G01X218273Y232539D02*
Y231555D01*
G01X218269Y214822D02*
Y213838D01*
G01X218264Y214822D02*
Y213838D01*
G01X218072Y215984D02*
Y209901D01*
G01Y236476D02*
Y230393D01*
G01X217993Y213838D02*
Y232539D01*
G01X217919Y232538D02*
Y231553D01*
G01X217910Y214824D02*
Y213840D01*
G01X217717Y227698D02*
Y232539D01*
G01Y213838D02*
Y218680D01*
G01X217643Y230760D02*
Y231750D01*
G01X217634Y214627D02*
Y215617D01*
G01X217560Y218760D02*
Y217696D01*
G01Y228681D02*
Y227618D01*
G01X217284Y218760D02*
Y217775D01*
G01Y228602D02*
Y227618D01*
G01X216497Y218760D02*
Y217775D01*
G01Y228602D02*
Y227618D01*
G01X216221Y218760D02*
Y217696D01*
G01Y228681D02*
Y227618D01*
G01X216147Y231750D02*
Y230760D01*
G01X216138Y215617D02*
Y214627D01*
G01X216064Y227698D02*
Y232539D01*
G01Y213838D02*
Y218680D01*
G01X215872Y231553D02*
Y232538D01*
G01X215862Y213840D02*
Y214824D01*
G01X215788Y232539D02*
Y213838D01*
G01X215710Y215984D02*
Y209901D01*
G01Y236476D02*
Y230393D01*
G01X215517Y232539D02*
Y231555D01*
G01X215513Y232539D02*
Y231555D01*
G01X215508Y214822D02*
Y213838D01*
G01X215473Y216515D02*
Y212342D01*
G01Y234035D02*
Y229862D01*
G01X214371D02*
Y234035D01*
G01Y212342D02*
Y216515D01*
G01X214336Y214822D02*
Y213838D01*
G01X214332Y214822D02*
Y213838D01*
G01Y232539D02*
Y231555D01*
G01X214135Y215984D02*
Y209901D01*
G01Y236476D02*
Y230393D01*
G01X214056Y213838D02*
Y232539D01*
G01X213977Y214824D02*
Y213840D01*
G01Y232538D02*
Y231553D01*
G01X213780Y231555D02*
Y236396D01*
G01Y209981D02*
Y214822D01*
G01X213702Y230760D02*
Y231750D01*
G01Y214627D02*
Y215617D01*
G01X213623Y210965D02*
Y209901D01*
G01Y236476D02*
Y235412D01*
G01X213347Y210885D02*
Y209901D01*
G01Y236476D02*
Y235492D01*
G01X212560D02*
Y236476D01*
G01Y210885D02*
Y209901D01*
G01X212284Y210965D02*
Y209901D01*
G01Y236476D02*
Y235412D01*
G01X212206Y215617D02*
Y214627D01*
G01Y231750D02*
Y230760D01*
G01X212127Y231555D02*
Y236396D01*
G01Y209981D02*
Y214822D01*
G01X211930Y231553D02*
Y232538D01*
G01Y213840D02*
Y214824D01*
G01X211851Y232539D02*
Y213838D01*
G01X211773Y215984D02*
Y209901D01*
G01Y236476D02*
Y230393D01*
G01X211576Y214822D02*
Y213838D01*
G01Y232539D02*
Y231555D01*
G01X211571Y232539D02*
Y231555D01*
G01X211536Y216515D02*
Y212342D01*
G01Y234035D02*
Y229862D01*
G01X210434D02*
Y234035D01*
G01Y212342D02*
Y216515D01*
G01X210399Y232539D02*
Y231555D01*
G01X210395Y214822D02*
Y213838D01*
G01X210390Y214822D02*
Y213838D01*
G01X210198Y215984D02*
Y209901D01*
G01Y236476D02*
Y230393D01*
G01X210119Y213838D02*
Y232539D01*
G01X210045Y232538D02*
Y231553D01*
G01X210036Y214824D02*
Y213840D01*
G01X209843Y227698D02*
Y232539D01*
G01Y213838D02*
Y218680D01*
G01X209769Y230760D02*
Y231750D01*
G01X209760Y214627D02*
Y215617D01*
G01X209686Y218760D02*
Y217696D01*
G01Y228681D02*
Y227618D01*
G01X209410Y218760D02*
Y217775D01*
G01Y228602D02*
Y227618D01*
G01X208623Y218760D02*
Y217775D01*
G01Y228602D02*
Y227618D01*
G01X208347Y218760D02*
Y217696D01*
G01Y228681D02*
Y227618D01*
G01X208273Y231750D02*
Y230760D01*
G01X208264Y215617D02*
Y214627D01*
G01X229184Y231368D02*
X229198Y230393D01*
G01X228219Y215009D02*
X228206Y215984D01*
G01X225252Y231368D02*
X225265Y230393D01*
G01X224277Y215009D02*
X224264Y215984D01*
G01X221310Y231368D02*
X221324Y230393D01*
G01X220345Y215009D02*
X220332Y215984D01*
G01X217378Y231368D02*
X217391Y230393D01*
G01X216403Y215009D02*
X216390Y215984D01*
G01X213436Y231368D02*
X213450Y230393D01*
G01X212471Y215009D02*
X212458Y215984D01*
G01X209504Y231368D02*
X209517Y230393D01*
G01X208529Y215009D02*
X208516Y215984D01*
G01X229571Y220138D02*
X229707Y214231D01*
G01X227832Y226239D02*
X227696Y232147D01*
G01X227691Y231260D02*
X227828Y225353D01*
G01X225770Y215117D02*
X225634Y221024D01*
G01X225629Y220138D02*
X225766Y214231D01*
G01X223900Y226239D02*
X223764Y232147D01*
G01X223759Y231260D02*
X223895Y225353D01*
G01X221838Y215117D02*
X221702Y221024D01*
G01X221697Y220138D02*
X221833Y214231D01*
G01X219958Y226239D02*
X219822Y232147D01*
G01X219817Y231260D02*
X219954Y225353D01*
G01X217896Y215117D02*
X217760Y221024D01*
G01X217755Y220138D02*
X217892Y214231D01*
G01X216026Y226239D02*
X215890Y232147D01*
G01X215885Y231260D02*
X216021Y225353D01*
G01X213964Y215117D02*
X213828Y221024D01*
G01X213823Y220138D02*
X213959Y214231D01*
G01X212084Y226239D02*
X211948Y232147D01*
G01X211943Y231260D02*
X212080Y225353D01*
G01X210022Y215117D02*
X209886Y221024D01*
G01X209881Y220138D02*
X210018Y214231D01*
G01X208152Y226239D02*
X208016Y232147D01*
G01X208011Y231260D02*
X208147Y225353D01*
G01X206090Y215117D02*
X205954Y221024D01*
G01X205949Y220138D02*
X206085Y214231D01*
G01X223965Y220340D02*
X223914Y221327D01*
G01X223912Y220365D02*
X223962Y219379D01*
G01X221676Y226012D02*
X221625Y226999D01*
G01X221623Y226037D02*
X221673Y225050D01*
G01X220032Y220340D02*
X219982Y221327D01*
G01X219980Y220365D02*
X220030Y219379D01*
G01X217743Y226012D02*
X217693Y226999D01*
G01X217691Y226037D02*
X217741Y225050D01*
G01X216091Y220340D02*
X216040Y221327D01*
G01X216038Y220365D02*
X216088Y219379D01*
G01X213802Y226012D02*
X213751Y226999D01*
G01X213749Y226037D02*
X213799Y225050D01*
G01X212158Y220340D02*
X212108Y221327D01*
G01X212106Y220365D02*
X212156Y219379D01*
G01X209869Y226012D02*
X209819Y226999D01*
G01X209817Y226037D02*
X209867Y225050D01*
G01X208217Y220340D02*
X208166Y221327D01*
G01X208164Y220365D02*
X208214Y219379D01*
G01X205928Y226012D02*
X205877Y226999D01*
G01X205875Y226037D02*
X205925Y225050D01*
G01X204284Y220340D02*
X204234Y221327D01*
G01X204232Y220365D02*
X204282Y219379D01*
G01X201995Y226012D02*
X201945Y226999D01*
G01X201943Y226037D02*
X201993Y225050D01*
G01X263394Y214640D02*
X263647Y215009D01*
G01X263381Y215615D02*
X263602Y215937D01*
G01X259461Y214640D02*
X259715Y215009D01*
G01X259670Y215937D02*
X259450Y215617D01*
G01X255520Y214640D02*
X255773Y215009D01*
G01X255507Y215615D02*
X255728Y215937D01*
G01X264889Y230762D02*
X264668Y230441D01*
G01X264876Y231737D02*
X264622Y231368D01*
G01X251587Y214640D02*
X251841Y215009D01*
G01X251796Y215937D02*
X251576Y215617D01*
G01X260726Y230441D02*
X260946Y230760D01*
G01X260934Y231737D02*
X260680Y231368D01*
G01X247646Y214640D02*
X247899Y215009D01*
G01X247632Y215615D02*
X247854Y215937D01*
G01X257015Y230762D02*
X256794Y230441D01*
G01X257002Y231737D02*
X256748Y231368D01*
G01X243713Y214640D02*
X243967Y215009D01*
G01X243700Y215615D02*
X243921Y215937D01*
G01X232115Y215984D02*
X232106Y215937D01*
G01X233162Y230393D02*
X233172Y230441D01*
G01X228183Y215984D02*
X228173Y215937D01*
G01X229220Y230393D02*
X229230Y230441D01*
G01X224241Y215984D02*
X224232Y215937D01*
G01X225288Y230393D02*
X225298Y230441D01*
G01X220309Y215984D02*
X220299Y215937D01*
G01X221346Y230393D02*
X221356Y230441D01*
G01X216367Y215984D02*
X216358Y215937D01*
G01X217414Y230393D02*
X217424Y230441D01*
G01X212435Y215984D02*
X212425Y215937D01*
G01X213472Y230393D02*
X213482Y230441D01*
G01X208493Y215984D02*
X208484Y215937D01*
G01X213751Y219379D02*
X213802Y220365D01*
G01X213799Y221327D02*
X213749Y220340D01*
G01X212108Y225050D02*
X212158Y226037D01*
G01X212156Y226999D02*
X212106Y226012D01*
G01X209810Y219379D02*
X209860Y220365D01*
G01X209858Y221327D02*
X209807Y220340D01*
G01X208176Y225050D02*
X208226Y226037D01*
G01X208224Y226999D02*
X208173Y226012D01*
G01X205877Y219379D02*
X205928Y220365D01*
G01X205925Y221327D02*
X205875Y220340D01*
G01X204234Y225050D02*
X204284Y226037D01*
G01X204282Y226999D02*
X204232Y226012D01*
G01X201936Y219379D02*
X201986Y220365D01*
G01X201984Y221327D02*
X201933Y220340D01*
G01X200302Y225050D02*
X200352Y226037D01*
G01X200350Y226999D02*
X200299Y226012D01*
G01X198003Y219379D02*
X198054Y220365D01*
G01X198051Y221327D02*
X198001Y220340D01*
G01X196360Y225050D02*
X196410Y226037D01*
G01X196408Y226999D02*
X196358Y226012D01*
G01X194062Y219379D02*
X194112Y220365D01*
G01X194110Y221327D02*
X194059Y220340D01*
G01X192428Y225050D02*
X192478Y226037D01*
G01X192476Y226999D02*
X192425Y226012D01*
G01X209896Y225353D02*
X210032Y231260D01*
G01X210027Y232147D02*
X209891Y226239D01*
G01X208006Y214231D02*
X208143Y220138D01*
G01X208138Y221024D02*
X208002Y215117D01*
G01X205954Y225353D02*
X206090Y231260D01*
G01X206085Y232147D02*
X205949Y226239D01*
G01X204074Y214231D02*
X204210Y220138D01*
G01X204206Y221024D02*
X204069Y215117D01*
G01X202022Y225353D02*
X202158Y231260D01*
G01X202153Y232147D02*
X202017Y226239D01*
G01X200132Y214231D02*
X200269Y220138D01*
G01X200264Y221024D02*
X200128Y215117D01*
G01X198080Y225353D02*
X198216Y231260D01*
G01X198211Y232147D02*
X198075Y226239D01*
G01X196200Y214231D02*
X196336Y220138D01*
G01X196331Y221024D02*
X196195Y215117D01*
G01X194148Y225353D02*
X194284Y231260D01*
G01X194279Y232147D02*
X194143Y226239D01*
G01X192258Y214231D02*
X192395Y220138D01*
G01X192390Y221024D02*
X192254Y215117D01*
G01X190206Y225353D02*
X190342Y231260D01*
G01X190337Y232147D02*
X190201Y226239D01*
G01X188326Y214231D02*
X188462Y220138D01*
G01X188457Y221024D02*
X188321Y215117D01*
G01X209508Y215984D02*
X209495Y215009D01*
G01X208526Y230393D02*
X208539Y231368D01*
G01X205576Y215984D02*
X205562Y215009D01*
G01X204584Y230393D02*
X204597Y231368D01*
G01X201634Y215984D02*
X201621Y215009D01*
G01X200652Y230393D02*
X200665Y231368D01*
G01X197701Y215984D02*
X197688Y215009D01*
G01X196710Y230393D02*
X196723Y231368D01*
G01X193760Y215984D02*
X193747Y215009D01*
G01X192778Y230393D02*
X192791Y231368D01*
G01X189827Y215984D02*
X189814Y215009D01*
G01X188836Y230393D02*
X188849Y231368D01*
G01X208229Y208523D02*
Y203011D01*
G01X208190Y227698D02*
Y232539D01*
G01Y213838D02*
Y218680D01*
G01X207998Y231553D02*
Y232538D01*
G01X207988Y213840D02*
Y214824D01*
G01X207914Y232539D02*
Y213838D01*
G01X207836Y215984D02*
Y209901D01*
G01Y236476D02*
Y230393D01*
G01X207643Y232539D02*
Y231555D01*
G01X207639Y232539D02*
Y231555D01*
G01X207634Y214822D02*
Y213838D01*
G01X207599Y216515D02*
Y212342D01*
G01Y234035D02*
Y229862D01*
G01X206497D02*
Y234035D01*
G01Y212342D02*
Y216515D01*
G01X206462Y214822D02*
Y213838D01*
G01X206458Y214822D02*
Y213838D01*
G01Y232539D02*
Y231555D01*
G01X206261Y215984D02*
Y209901D01*
G01Y236476D02*
Y230393D01*
G01X206182Y213838D02*
Y232539D01*
G01X206103Y214824D02*
Y213840D01*
G01Y232538D02*
Y231553D01*
G01X205906Y231555D02*
Y236396D01*
G01Y209981D02*
Y214822D01*
G01X205828Y230760D02*
Y231750D01*
G01Y214627D02*
Y215617D01*
G01X205749Y210965D02*
Y209901D01*
G01Y236476D02*
Y235412D01*
G01X205473Y210885D02*
Y209901D01*
G01Y236476D02*
Y235492D01*
G01X205080Y208523D02*
Y203011D01*
G01X204686Y235492D02*
Y236476D01*
G01Y210885D02*
Y209901D01*
G01X204410Y210965D02*
Y209901D01*
G01Y236476D02*
Y235412D01*
G01X204332Y215617D02*
Y214627D01*
G01Y231750D02*
Y230760D01*
G01X204253Y231555D02*
Y236396D01*
G01Y209981D02*
Y214822D01*
G01X204056Y213840D02*
Y214824D01*
G01Y231553D02*
Y232538D01*
G01X203977Y232539D02*
Y213838D01*
G01X203899Y215984D02*
Y209901D01*
G01Y236476D02*
Y230393D01*
G01X203702Y214822D02*
Y213838D01*
G01Y232539D02*
Y231555D01*
G01X203697Y232539D02*
Y231555D01*
G01X203662Y216515D02*
Y212342D01*
G01Y234035D02*
Y229862D01*
G01X202560D02*
Y234035D01*
G01Y212342D02*
Y216515D01*
G01X202525Y232539D02*
Y231555D01*
G01X202521Y214822D02*
Y213838D01*
G01X202516Y214822D02*
Y213838D01*
G01X202324Y215984D02*
Y209901D01*
G01Y236476D02*
Y230393D01*
G01X202245Y213838D02*
Y232539D01*
G01X202171Y232538D02*
Y231553D01*
G01X202162Y214824D02*
Y213840D01*
G01X201969Y227698D02*
Y232539D01*
G01Y213838D02*
Y218680D01*
G01X201895Y230760D02*
Y231750D01*
G01X201886Y214627D02*
Y215617D01*
G01X201812Y218760D02*
Y217696D01*
G01Y228681D02*
Y227618D01*
G01X201536D02*
Y228602D01*
G01Y218760D02*
Y217775D01*
G01X201143Y208523D02*
Y203011D01*
G01X200749Y227618D02*
Y228602D01*
G01Y217775D02*
Y218760D01*
G01X200473D02*
Y217696D01*
G01Y228681D02*
Y227618D01*
G01X200399Y231750D02*
Y230760D01*
G01X200390Y215617D02*
Y214627D01*
G01X200316Y227698D02*
Y232539D01*
G01Y213838D02*
Y218680D01*
G01X200124Y231553D02*
Y232538D01*
G01X200114Y213840D02*
Y214824D01*
G01X200040Y232539D02*
Y213838D01*
G01X199962Y215984D02*
Y209901D01*
G01Y236476D02*
Y230393D01*
G01X199769Y232539D02*
Y231555D01*
G01X199765Y232539D02*
Y231555D01*
G01X199760Y214822D02*
Y213838D01*
G01X199725Y216515D02*
Y212342D01*
G01Y234035D02*
Y229862D01*
G01X198623D02*
Y234035D01*
G01Y212342D02*
Y216515D01*
G01X198588Y214822D02*
Y213838D01*
G01X198584Y214822D02*
Y213838D01*
G01Y232539D02*
Y231555D01*
G01X198387Y215984D02*
Y209901D01*
G01Y236476D02*
Y230393D01*
G01X198308Y213838D02*
Y232539D01*
G01X198229Y214824D02*
Y213840D01*
G01Y232538D02*
Y231553D01*
G01X198032Y231555D02*
Y236396D01*
G01Y209981D02*
Y214822D01*
G01X197993Y208523D02*
Y203011D01*
G01X197954Y230760D02*
Y231750D01*
G01Y214627D02*
Y215617D01*
G01X197875Y210965D02*
Y209901D01*
G01Y236476D02*
Y235412D01*
G01X197599Y210885D02*
Y209901D01*
G01Y236476D02*
Y235492D01*
G01X196812D02*
Y236476D01*
G01Y210885D02*
Y209901D01*
G01X196536Y210965D02*
Y209901D01*
G01Y236476D02*
Y235412D01*
G01X196458Y215617D02*
Y214627D01*
G01Y231750D02*
Y230760D01*
G01X196379Y231555D02*
Y236396D01*
G01Y209981D02*
Y214822D01*
G01X196182Y231553D02*
Y232538D01*
G01Y213840D02*
Y214824D01*
G01X196103Y232539D02*
Y213838D01*
G01X196025Y215984D02*
Y209901D01*
G01Y236476D02*
Y230393D01*
G01X195828Y214822D02*
Y213838D01*
G01Y232539D02*
Y231555D01*
G01X195823Y232539D02*
Y231555D01*
G01X195788Y216515D02*
Y212342D01*
G01Y234035D02*
Y229862D01*
G01X194686D02*
Y234035D01*
G01Y212342D02*
Y216515D01*
G01X194651Y232539D02*
Y231555D01*
G01X194647Y214822D02*
Y213838D01*
G01X194642Y214822D02*
Y213838D01*
G01X194450Y215984D02*
Y209901D01*
G01Y236476D02*
Y230393D01*
G01X194371Y213838D02*
Y232539D01*
G01X194297Y232538D02*
Y231553D01*
G01X194288Y214824D02*
Y213840D01*
G01X194095Y227698D02*
Y232539D01*
G01Y213838D02*
Y218680D01*
G01X194021Y230760D02*
Y231750D01*
G01X194012Y214627D02*
Y215617D01*
G01X193938Y218760D02*
Y217696D01*
G01Y228681D02*
Y227618D01*
G01X193662D02*
Y228602D01*
G01Y218760D02*
Y217775D01*
G01X192875Y227618D02*
Y228602D01*
G01Y217775D02*
Y218760D01*
G01X192599D02*
Y217696D01*
G01Y228681D02*
Y227618D01*
G01X192525Y231750D02*
Y230760D01*
G01X192516Y215617D02*
Y214627D01*
G01X192442Y227698D02*
Y232539D01*
G01Y213838D02*
Y218680D01*
G01X192250Y231553D02*
Y232538D01*
G01X192240Y213840D02*
Y214824D01*
G01X192166Y232539D02*
Y213838D01*
G01X192088Y215984D02*
Y209901D01*
G01Y236476D02*
Y230393D01*
G01X191895Y232539D02*
Y231555D01*
G01X191891Y232539D02*
Y231555D01*
G01X191886Y214822D02*
Y213838D01*
G01X191851Y216515D02*
Y212342D01*
G01Y234035D02*
Y229862D01*
G01X190749D02*
Y234035D01*
G01Y212342D02*
Y216515D01*
G01X190714Y214822D02*
Y213838D01*
G01X190710Y214822D02*
Y213838D01*
G01Y232539D02*
Y231555D01*
G01X190513Y215984D02*
Y209901D01*
G01Y236476D02*
Y230393D01*
G01X190434Y213838D02*
Y232539D01*
G01X190355Y214824D02*
Y213840D01*
G01Y232538D02*
Y231553D01*
G01X190158Y231555D02*
Y236396D01*
G01Y209981D02*
Y214822D01*
G01X190080Y230760D02*
Y231750D01*
G01Y214627D02*
Y215617D01*
G01X190001Y210965D02*
Y209901D01*
G01Y236476D02*
Y235412D01*
G01X189725Y209901D02*
Y210885D01*
G01Y236476D02*
Y235492D01*
G01X188938Y210885D02*
Y209901D01*
G01Y236476D02*
Y235492D01*
G01X188662Y210965D02*
Y209901D01*
G01Y236476D02*
Y235412D01*
G01X188584Y215617D02*
Y214627D01*
G01Y231750D02*
Y230760D01*
G01X188505Y231555D02*
Y236396D01*
G01Y209981D02*
Y214822D01*
G01X188308Y231553D02*
Y232538D01*
G01Y213840D02*
Y214824D01*
G01X188229Y232539D02*
Y213838D01*
G01X188151Y215984D02*
Y209901D01*
G01Y236476D02*
Y230393D01*
G01X187954Y214822D02*
Y213838D01*
G01Y232539D02*
Y231555D01*
G01X187949Y232539D02*
Y231555D01*
G01X187914Y216515D02*
Y212342D01*
G01Y234035D02*
Y229862D01*
G01X186812D02*
Y234035D01*
G01Y212342D02*
Y216515D01*
G01X205562Y231368D02*
X205576Y230393D01*
G01X204597Y215009D02*
X204584Y215984D01*
G01X201630Y231368D02*
X201643Y230393D01*
G01X200655Y215009D02*
X200642Y215984D01*
G01X197688Y231368D02*
X197701Y230393D01*
G01X196723Y215009D02*
X196710Y215984D01*
G01X193756Y231368D02*
X193769Y230393D01*
G01X192781Y215009D02*
X192768Y215984D01*
G01X189814Y231368D02*
X189827Y230393D01*
G01X188849Y215009D02*
X188836Y215984D01*
G01X204210Y226239D02*
X204074Y232147D01*
G01X204069Y231260D02*
X204206Y225353D01*
G01X202148Y215117D02*
X202012Y221024D01*
G01X202007Y220138D02*
X202144Y214231D01*
G01X200278Y226239D02*
X200142Y232147D01*
G01X200137Y231260D02*
X200273Y225353D01*
G01X198216Y215117D02*
X198080Y221024D01*
G01X198075Y220138D02*
X198211Y214231D01*
G01X196336Y226239D02*
X196200Y232147D01*
G01X196195Y231260D02*
X196331Y225353D01*
G01X194274Y215117D02*
X194138Y221024D01*
G01X194133Y220138D02*
X194270Y214231D01*
G01X192404Y226239D02*
X192268Y232147D01*
G01X192263Y231260D02*
X192399Y225353D01*
G01X190342Y215117D02*
X190206Y221024D01*
G01X190201Y220138D02*
X190337Y214231D01*
G01X188462Y226239D02*
X188326Y232147D01*
G01X188321Y231260D02*
X188457Y225353D01*
G01X200343Y220340D02*
X200292Y221327D01*
G01X200290Y220365D02*
X200340Y219379D01*
G01X198054Y226012D02*
X198003Y226999D01*
G01X198001Y226037D02*
X198051Y225050D01*
G01X196410Y220340D02*
X196360Y221327D01*
G01X196358Y220365D02*
X196408Y219379D01*
G01X194121Y226012D02*
X194071Y226999D01*
G01X194069Y226037D02*
X194119Y225050D01*
G01X192469Y220340D02*
X192418Y221327D01*
G01X192416Y220365D02*
X192466Y219379D01*
G01X190180Y226012D02*
X190129Y226999D01*
G01X190127Y226037D02*
X190177Y225050D01*
G01X188536Y220340D02*
X188486Y221327D01*
G01X188484Y220365D02*
X188534Y219379D01*
G01X252852Y230441D02*
X253072Y230760D01*
G01X253060Y231737D02*
X252806Y231368D01*
G01X239772Y214640D02*
X240025Y215009D01*
G01X239758Y215615D02*
X239980Y215937D01*
G01X249141Y230762D02*
X248920Y230441D01*
G01X249128Y231737D02*
X248874Y231368D01*
G01X235839Y214640D02*
X236093Y215009D01*
G01X235826Y215615D02*
X236047Y215937D01*
G01X245199Y230762D02*
X244978Y230441D01*
G01X245186Y231737D02*
X244932Y231368D01*
G01X231898Y214640D02*
X232151Y215009D01*
G01X231884Y215615D02*
X232106Y215937D01*
G01X241267Y230762D02*
X241046Y230441D01*
G01X241254Y231737D02*
X241000Y231368D01*
G01X227965Y214640D02*
X228219Y215009D01*
G01X227952Y215615D02*
X228173Y215937D01*
G01X237325Y230762D02*
X237104Y230441D01*
G01X237312Y231737D02*
X237058Y231368D01*
G01X224024Y214640D02*
X224277Y215009D01*
G01X224010Y215615D02*
X224232Y215937D01*
G01X233393Y230762D02*
X233172Y230441D01*
G01X233380Y231737D02*
X233126Y231368D01*
G01X220091Y214640D02*
X220345Y215009D01*
G01X220078Y215615D02*
X220299Y215937D01*
G01X229451Y230762D02*
X229230Y230441D01*
G01X229438Y231737D02*
X229184Y231368D01*
G01X216150Y214640D02*
X216403Y215009D01*
G01X216136Y215615D02*
X216358Y215937D01*
G01X225519Y230762D02*
X225298Y230441D01*
G01X225506Y231737D02*
X225252Y231368D01*
G01X209540Y230393D02*
X209550Y230441D01*
G01X204561Y215984D02*
X204551Y215937D01*
G01X205598Y230393D02*
X205608Y230441D01*
G01X200619Y215984D02*
X200610Y215937D01*
G01X201666Y230393D02*
X201676Y230441D01*
G01X196687Y215984D02*
X196677Y215937D01*
G01X197724Y230393D02*
X197734Y230441D01*
G01X192745Y215984D02*
X192736Y215937D01*
G01X193792Y230393D02*
X193802Y230441D01*
G01X188803Y215937D02*
X188813Y215984D01*
G01X189860Y230441D02*
X189850Y230393D01*
G01X190129Y219379D02*
X190180Y220365D01*
G01X190177Y221327D02*
X190127Y220340D01*
G01X188486Y225050D02*
X188536Y226037D01*
G01X188534Y226999D02*
X188484Y226012D01*
G01X212217Y214640D02*
X212471Y215009D01*
G01X212204Y215615D02*
X212425Y215937D01*
G01X221577Y230762D02*
X221356Y230441D01*
G01X221564Y231737D02*
X221310Y231368D01*
G01X208276Y214640D02*
X208529Y215009D01*
G01X208262Y215615D02*
X208484Y215937D01*
G01X217645Y230762D02*
X217424Y230441D01*
G01X217632Y231737D02*
X217378Y231368D01*
G01X204343Y214640D02*
X204597Y215009D01*
G01X204330Y215615D02*
X204551Y215937D01*
G01X213703Y230762D02*
X213482Y230441D01*
G01X213690Y231737D02*
X213436Y231368D01*
G01X200402Y214640D02*
X200655Y215009D01*
G01X200388Y215615D02*
X200610Y215937D01*
G01X209771Y230762D02*
X209550Y230441D01*
G01X209758Y231737D02*
X209504Y231368D01*
G01X196469Y214640D02*
X196723Y215009D01*
G01X196456Y215615D02*
X196677Y215937D01*
G01X205829Y230762D02*
X205608Y230441D01*
G01X205816Y231737D02*
X205562Y231368D01*
G01X192528Y214640D02*
X192781Y215009D01*
G01X192514Y215615D02*
X192736Y215937D01*
G01X201897Y230762D02*
X201676Y230441D01*
G01X201884Y231737D02*
X201630Y231368D01*
G01X188595Y214640D02*
X188849Y215009D01*
G01X188803Y215937D02*
X188584Y215617D01*
G01X197955Y230762D02*
X197734Y230441D01*
G01X197942Y231737D02*
X197688Y231368D01*
G01X194023Y230762D02*
X193802Y230441D01*
G01X194010Y231737D02*
X193756Y231368D01*
G01X189860Y230441D02*
X190080Y230760D01*
G01X190068Y231737D02*
X189814Y231368D01*
G01X209529Y533700D02*
G03X210316Y534488I0J787D01*
G01Y563228D02*
Y534488D01*
G01X212284Y565196D02*
X210316Y563228D01*
G01X426536Y565196D02*
X212284D01*
G01X207086Y772395D02*
X207556Y771660D01*
X208182Y771240D01*
X208887Y771135D01*
X209514Y771240D01*
X210141Y771765D01*
X210532Y772395D01*
X210611Y773025D01*
X210454Y773760D01*
X209906Y774285D01*
X209357Y774495D01*
X208652D01*
G01X209357D02*
X209827Y774810D01*
X210219Y775335D01*
X210376Y775965D01*
X210219Y776595D01*
X209827Y777120D01*
X209122Y777435D01*
X208417Y777330D01*
X207712Y776910D01*
G01X288074Y-578426D02*
Y-595749D01*
G01X346792Y-58386D02*
Y-69410D01*
G01X345808D02*
Y-58386D01*
G01X343643D02*
Y-69410D01*
G01X342658D02*
Y-58386D01*
G01X340493D02*
Y-69410D01*
G01X339509D02*
Y-58386D01*
G01X337343D02*
Y-69410D01*
G01X336359D02*
Y-58386D01*
G01X334194D02*
Y-69410D01*
G01X333210D02*
Y-58386D01*
G01X331044D02*
Y-69410D01*
G01X330060D02*
Y-58386D01*
G01X327895D02*
Y-69410D01*
G01X326910D02*
Y-58386D01*
G01X324745D02*
Y-69410D01*
G01X323761D02*
Y-58386D01*
G01X321595D02*
Y-69410D01*
G01X320611D02*
Y-58386D01*
G01X318446D02*
Y-69410D01*
G01X317462D02*
Y-58386D01*
G01X315296D02*
Y-69410D01*
G01X314312D02*
Y-58386D01*
G01X312147D02*
Y-69410D01*
G01X311162D02*
Y-58386D01*
G01X308997D02*
Y-69410D01*
G01X308013D02*
Y-58386D01*
G01X305847D02*
Y-69410D01*
G01X304863D02*
Y-58386D01*
G01X302698D02*
Y-69410D01*
G01X301714D02*
Y-58386D01*
G01X299548D02*
Y-69410D01*
G01X298564D02*
Y-58386D01*
G01X296399D02*
Y-69410D01*
G01X295414D02*
Y-58386D01*
G01X293249D02*
Y-69410D01*
G01X292265D02*
Y-58386D01*
G01X290099D02*
Y-69410D01*
G01X289115D02*
Y-58386D01*
G01X286950D02*
Y-69410D01*
G01X285966D02*
Y-58386D01*
G01X283800D02*
Y-69410D01*
G01X282816D02*
Y-58386D01*
G01X280651D02*
Y-69410D01*
G01X279666D02*
Y-58386D01*
G01X277501D02*
Y-69410D01*
G01X276517D02*
Y-58386D01*
G01X274351D02*
Y-69410D01*
G01X273367D02*
Y-58386D01*
G01X271202D02*
Y-69410D01*
G01X270217D02*
Y-58386D01*
G01X268052D02*
Y-69410D01*
G01X267068D02*
Y-58386D01*
G01X346792Y-69410D02*
X348958D01*
G01X343643D02*
X345808D01*
G01X340493D02*
X342658D01*
G01X337343D02*
X339509D01*
G01X334194D02*
X336359D01*
G01X331044D02*
X333210D01*
G01X327895D02*
X330060D01*
G01X324745D02*
X326910D01*
G01X321595D02*
X323761D01*
G01X318446D02*
X320611D01*
G01X315296D02*
X317462D01*
G01X312147D02*
X314312D01*
G01X308997D02*
X311162D01*
G01X305847D02*
X308013D01*
G01X302698D02*
X304863D01*
G01X299548D02*
X301714D01*
G01X296399D02*
X298564D01*
G01X293249D02*
X295414D01*
G01X290099D02*
X292265D01*
G01X286950D02*
X289115D01*
G01X283800D02*
X285966D01*
G01X280651D02*
X282816D01*
G01X277501D02*
X279666D01*
G01X274351D02*
X276517D01*
G01X271202D02*
X273367D01*
G01X268052D02*
X270217D01*
G01Y-58386D02*
X268052D01*
G01X273367D02*
X271202D01*
G01X276517D02*
X274351D01*
G01X279666D02*
X277501D01*
G01X282816D02*
X280651D01*
G01X285966D02*
X283800D01*
G01X289115D02*
X286950D01*
G01X292265D02*
X290099D01*
G01X295414D02*
X293249D01*
G01X298564D02*
X296399D01*
G01X301714D02*
X299548D01*
G01X304863D02*
X302698D01*
G01X308013D02*
X305847D01*
G01X311162D02*
X308997D01*
G01X314312D02*
X312147D01*
G01X317462D02*
X315296D01*
G01X320611D02*
X318446D01*
G01X323761D02*
X321595D01*
G01X326910D02*
X324745D01*
G01X330060D02*
X327895D01*
G01X333210D02*
X331044D01*
G01X336359D02*
X334194D01*
G01X339509D02*
X337343D01*
G01X342658D02*
X340493D01*
G01X345808D02*
X343643D01*
G01X348958D02*
X346792D01*
G01X345953Y145965D02*
X345964Y146012D01*
G01X345948Y146063D02*
X345953Y145965D01*
G01X345943Y146239D02*
X345948Y146063D01*
G01X346038Y148861D02*
X346040Y149826D01*
G01X346036Y148414D02*
X346038Y148861D01*
G01X346033Y148009D02*
X346036Y148414D01*
G01X346029Y147656D02*
X346033Y148009D01*
G01X346025Y147364D02*
X346029Y147656D01*
G01X346020Y147143D02*
X346025Y147364D01*
G01X346014Y146999D02*
X346020Y147143D01*
G01X346049Y148520D02*
X346051Y149807D01*
G01X346045Y147925D02*
X346049Y148520D01*
G01X346041Y147384D02*
X346045Y147925D01*
G01X346036Y146913D02*
X346041Y147384D01*
G01X346030Y146524D02*
X346036Y146913D01*
G01X346024Y146230D02*
X346030Y146524D01*
G01X346017Y146037D02*
X346024Y146230D01*
G01X345952Y144988D02*
X345966Y145050D01*
G01X345945Y145118D02*
X345952Y144988D01*
G01X345938Y145353D02*
X345945Y145118D01*
G01X345953Y140412D02*
X345943Y140138D01*
G01X345959Y140429D02*
X345953Y140412D01*
G01X345964Y140365D02*
X345959Y140429D01*
G01X345952Y141390D02*
X345938Y141024D01*
G01X345959Y141412D02*
X345952Y141390D01*
G01X345966Y141327D02*
X345959Y141412D01*
G01X346030Y139853D02*
X346017Y140340D01*
G01X346036Y139464D02*
X346030Y139853D01*
G01X346041Y138993D02*
X346036Y139464D01*
G01X346045Y138453D02*
X346041Y138993D01*
G01X346049Y137857D02*
X346045Y138453D01*
G01X346051Y137224D02*
X346049Y137857D01*
G01X346051Y136570D02*
Y137224D01*
G01X346025Y139013D02*
X346014Y139379D01*
G01X346029Y138722D02*
X346025Y139013D01*
G01X346033Y138368D02*
X346029Y138722D01*
G01X346036Y137963D02*
X346033Y138368D01*
G01X346038Y137516D02*
X346036Y137963D01*
G01X346040Y137041D02*
X346038Y137516D01*
G01X346040Y136551D02*
Y137041D01*
G01X343739Y145965D02*
X343749Y146239D01*
G01X343733Y145948D02*
X343739Y145965D01*
G01X343728Y146012D02*
X343733Y145948D01*
G01X343740Y144988D02*
X343754Y145353D01*
G01X343733Y144965D02*
X343740Y144988D01*
G01X343725Y145050D02*
X343733Y144965D01*
G01X343661Y146524D02*
X343675Y146037D01*
G01X343655Y146913D02*
X343661Y146524D01*
G01X343650Y147384D02*
X343655Y146913D01*
G01X343646Y147925D02*
X343650Y147384D01*
G01X343643Y148520D02*
X343646Y147925D01*
G01X343641Y149153D02*
X343643Y148520D01*
G01X343640Y149807D02*
X343641Y149153D01*
G01X343636Y151677D02*
X343628Y151750D01*
G01X343639Y151547D02*
X343636Y151677D01*
G01X343643Y151359D02*
X343639Y151547D01*
G01X343646Y151120D02*
X343643Y151359D01*
G01X343648Y150838D02*
X343646Y151120D01*
G01X343650Y150521D02*
X343648Y150838D01*
G01X343651Y150180D02*
X343650Y150521D01*
G01X343651Y149826D02*
Y150180D01*
G01X343667Y147364D02*
X343677Y146999D01*
G01X343663Y147656D02*
X343667Y147364D01*
G01X343659Y148009D02*
X343663Y147656D01*
G01X343656Y148414D02*
X343659Y148009D01*
G01X343653Y148861D02*
X343656Y148414D01*
G01X343652Y149336D02*
X343653Y148861D01*
G01X343651Y149826D02*
X343652Y149336D01*
G01X342021Y145965D02*
X342032Y146012D01*
G01X342015Y146063D02*
X342021Y145965D01*
G01X342010Y146239D02*
X342015Y146063D01*
G01X342106Y148861D02*
X342108Y149826D01*
G01X342104Y148414D02*
X342106Y148861D01*
G01X342100Y148009D02*
X342104Y148414D01*
G01X342097Y147656D02*
X342100Y148009D01*
G01X342092Y147364D02*
X342097Y147656D01*
G01X342087Y147143D02*
X342092Y147364D01*
G01X342082Y146999D02*
X342087Y147143D01*
G01X342110Y150521D02*
X342108Y149826D01*
G01X342111Y150838D02*
X342110Y150521D01*
G01X342114Y151120D02*
X342111Y150838D01*
G01X342117Y151359D02*
X342114Y151120D01*
G01X342120Y151547D02*
X342117Y151359D01*
G01X342124Y151677D02*
X342120Y151547D01*
G01X342128Y151746D02*
X342124Y151677D01*
G01X342132Y151750D02*
X342128Y151746D01*
G01X342116Y148520D02*
X342119Y149807D01*
G01X342113Y147925D02*
X342116Y148520D01*
G01X342109Y147384D02*
X342113Y147925D01*
G01X342104Y146913D02*
X342109Y147384D01*
G01X342098Y146524D02*
X342104Y146913D01*
G01X342091Y146230D02*
X342098Y146524D01*
G01X342084Y146037D02*
X342091Y146230D01*
G01X342019Y144988D02*
X342034Y145050D01*
G01X342012Y145118D02*
X342019Y144988D01*
G01X342005Y145353D02*
X342012Y145118D01*
G01X342011Y140412D02*
X342001Y140138D01*
G01X342017Y140429D02*
X342011Y140412D01*
G01X342022Y140365D02*
X342017Y140429D01*
G01X342010Y141390D02*
X341996Y141024D01*
G01X342017Y141412D02*
X342010Y141390D01*
G01X342025Y141327D02*
X342017Y141412D01*
G01X342089Y139853D02*
X342075Y140340D01*
G01X342095Y139464D02*
X342089Y139853D01*
G01X342100Y138993D02*
X342095Y139464D01*
G01X342104Y138453D02*
X342100Y138993D01*
G01X342107Y137857D02*
X342104Y138453D01*
G01X342109Y137224D02*
X342107Y137857D01*
G01X342110Y136570D02*
X342109Y137224D01*
G01X342114Y134700D02*
X342122Y134627D01*
G01X342111Y134830D02*
X342114Y134700D01*
G01X342107Y135018D02*
X342111Y134830D01*
G01X342104Y135257D02*
X342107Y135018D01*
G01X342102Y135540D02*
X342104Y135257D01*
G01X342100Y135857D02*
X342102Y135540D01*
G01X342099Y136198D02*
X342100Y135857D01*
G01X342099Y136551D02*
Y136198D01*
G01X342083Y139013D02*
X342073Y139379D01*
G01X342087Y138722D02*
X342083Y139013D01*
G01X342091Y138368D02*
X342087Y138722D01*
G01X342094Y137963D02*
X342091Y138368D01*
G01X342097Y137516D02*
X342094Y137963D01*
G01X342098Y137041D02*
X342097Y137516D01*
G01X342099Y136551D02*
X342098Y137041D01*
G01X343729Y140412D02*
X343718Y140365D01*
G01X343735Y140314D02*
X343729Y140412D01*
G01X343740Y140138D02*
X343735Y140314D01*
G01X343644Y137516D02*
X343642Y136551D01*
G01X343646Y137963D02*
X343644Y137516D01*
G01X343649Y138368D02*
X343646Y137963D01*
G01X343653Y138722D02*
X343649Y138368D01*
G01X343658Y139013D02*
X343653Y138722D01*
G01X343663Y139234D02*
X343658Y139013D01*
G01X343668Y139379D02*
X343663Y139234D01*
G01X343640Y135857D02*
X343642Y136551D01*
G01X343639Y135540D02*
X343640Y135857D01*
G01X343636Y135257D02*
X343639Y135540D01*
G01X343633Y135018D02*
X343636Y135257D01*
G01X343630Y134830D02*
X343633Y135018D01*
G01X343626Y134700D02*
X343630Y134830D01*
G01X343622Y134632D02*
X343626Y134700D01*
G01X343618Y134627D02*
X343622Y134632D01*
G01X343634Y137857D02*
X343631Y136570D01*
G01X343637Y138453D02*
X343634Y137857D01*
G01X343641Y138993D02*
X343637Y138453D01*
G01X343646Y139464D02*
X343641Y138993D01*
G01X343652Y139853D02*
X343646Y139464D01*
G01X343659Y140148D02*
X343652Y139853D01*
G01X343666Y140340D02*
X343659Y140148D01*
G01X343731Y141390D02*
X343716Y141327D01*
G01X343738Y141259D02*
X343731Y141390D01*
G01X343744Y141024D02*
X343738Y141259D01*
G01X338079Y145965D02*
X338090Y146012D01*
G01X338074Y146063D02*
X338079Y145965D01*
G01X338069Y146239D02*
X338074Y146063D01*
G01X338164Y148861D02*
X338166Y149826D01*
G01X338162Y148414D02*
X338164Y148861D01*
G01X338159Y148009D02*
X338162Y148414D01*
G01X338155Y147656D02*
X338159Y148009D01*
G01X338151Y147364D02*
X338155Y147656D01*
G01X338146Y147143D02*
X338151Y147364D01*
G01X338140Y146999D02*
X338146Y147143D01*
G01X338175Y148520D02*
X338177Y149807D01*
G01X338171Y147925D02*
X338175Y148520D01*
G01X338167Y147384D02*
X338171Y147925D01*
G01X338162Y146913D02*
X338167Y147384D01*
G01X338156Y146524D02*
X338162Y146913D01*
G01X338150Y146230D02*
X338156Y146524D01*
G01X338143Y146037D02*
X338150Y146230D01*
G01X338078Y144988D02*
X338092Y145050D01*
G01X338071Y145118D02*
X338078Y144988D01*
G01X338064Y145353D02*
X338071Y145118D01*
G01X339797Y145965D02*
X339807Y146239D01*
G01X339791Y145948D02*
X339797Y145965D01*
G01X339786Y146012D02*
X339791Y145948D01*
G01X339798Y144988D02*
X339812Y145353D01*
G01X339791Y144965D02*
X339798Y144988D01*
G01X339784Y145050D02*
X339791Y144965D01*
G01X339720Y146524D02*
X339733Y146037D01*
G01X339714Y146913D02*
X339720Y146524D01*
G01X339709Y147384D02*
X339714Y146913D01*
G01X339704Y147925D02*
X339709Y147384D01*
G01X339701Y148520D02*
X339704Y147925D01*
G01X339699Y149153D02*
X339701Y148520D01*
G01X339699Y149807D02*
Y149153D01*
G01X339725Y147364D02*
X339736Y146999D01*
G01X339721Y147656D02*
X339725Y147364D01*
G01X339717Y148009D02*
X339721Y147656D01*
G01X339714Y148414D02*
X339717Y148009D01*
G01X339712Y148861D02*
X339714Y148414D01*
G01X339710Y149336D02*
X339712Y148861D01*
G01X339710Y149826D02*
Y149336D01*
G01X339797Y140412D02*
X339786Y140365D01*
G01X339802Y140314D02*
X339797Y140412D01*
G01X339807Y140138D02*
X339802Y140314D01*
G01X339712Y137516D02*
X339710Y136551D01*
G01X339714Y137963D02*
X339712Y137516D01*
G01X339717Y138368D02*
X339714Y137963D01*
G01X339721Y138722D02*
X339717Y138368D01*
G01X339725Y139013D02*
X339721Y138722D01*
G01X339730Y139234D02*
X339725Y139013D01*
G01X339736Y139379D02*
X339730Y139234D01*
G01X339701Y137857D02*
X339699Y136570D01*
G01X339704Y138453D02*
X339701Y137857D01*
G01X339709Y138993D02*
X339704Y138453D01*
G01X339714Y139464D02*
X339709Y138993D01*
G01X339720Y139853D02*
X339714Y139464D01*
G01X339726Y140148D02*
X339720Y139853D01*
G01X339733Y140340D02*
X339726Y140148D01*
G01X339798Y141390D02*
X339784Y141327D01*
G01X339805Y141259D02*
X339798Y141390D01*
G01X339812Y141024D02*
X339805Y141259D01*
G01X338079Y140412D02*
X338069Y140138D01*
G01X338084Y140429D02*
X338079Y140412D01*
G01X338090Y140365D02*
X338084Y140429D01*
G01X338078Y141390D02*
X338064Y141024D01*
G01X338085Y141412D02*
X338078Y141390D01*
G01X338092Y141327D02*
X338085Y141412D01*
G01X338156Y139853D02*
X338143Y140340D01*
G01X338162Y139464D02*
X338156Y139853D01*
G01X338167Y138993D02*
X338162Y139464D01*
G01X338171Y138453D02*
X338167Y138993D01*
G01X338175Y137857D02*
X338171Y138453D01*
G01X338177Y137224D02*
X338175Y137857D01*
G01X338177Y136570D02*
Y137224D01*
G01X338151Y139013D02*
X338140Y139379D01*
G01X338155Y138722D02*
X338151Y139013D01*
G01X338159Y138368D02*
X338155Y138722D01*
G01X338162Y137963D02*
X338159Y138368D01*
G01X338164Y137516D02*
X338162Y137963D01*
G01X338166Y137041D02*
X338164Y137516D01*
G01X338166Y136551D02*
Y137041D01*
G01X335865Y145965D02*
X335875Y146239D01*
G01X335859Y145948D02*
X335865Y145965D01*
G01X335854Y146012D02*
X335859Y145948D01*
G01X335866Y144988D02*
X335880Y145353D01*
G01X335859Y144965D02*
X335866Y144988D01*
G01X335851Y145050D02*
X335859Y144965D01*
G01X335787Y146524D02*
X335801Y146037D01*
G01X335781Y146913D02*
X335787Y146524D01*
G01X335776Y147384D02*
X335781Y146913D01*
G01X335772Y147925D02*
X335776Y147384D01*
G01X335769Y148520D02*
X335772Y147925D01*
G01X335767Y149153D02*
X335769Y148520D01*
G01X335766Y149807D02*
X335767Y149153D01*
G01X335762Y151677D02*
X335754Y151750D01*
G01X335765Y151547D02*
X335762Y151677D01*
G01X335769Y151359D02*
X335765Y151547D01*
G01X335772Y151120D02*
X335769Y151359D01*
G01X335774Y150838D02*
X335772Y151120D01*
G01X335776Y150521D02*
X335774Y150838D01*
G01X335777Y150180D02*
X335776Y150521D01*
G01X335777Y149826D02*
Y150180D01*
G01X335793Y147364D02*
X335803Y146999D01*
G01X335789Y147656D02*
X335793Y147364D01*
G01X335785Y148009D02*
X335789Y147656D01*
G01X335782Y148414D02*
X335785Y148009D01*
G01X335779Y148861D02*
X335782Y148414D01*
G01X335778Y149336D02*
X335779Y148861D01*
G01X335777Y149826D02*
X335778Y149336D01*
G01X334147Y145965D02*
X334158Y146012D01*
G01X334141Y146063D02*
X334147Y145965D01*
G01X334136Y146239D02*
X334141Y146063D01*
G01X334232Y148861D02*
X334234Y149826D01*
G01X334230Y148414D02*
X334232Y148861D01*
G01X334226Y148009D02*
X334230Y148414D01*
G01X334223Y147656D02*
X334226Y148009D01*
G01X334218Y147364D02*
X334223Y147656D01*
G01X334213Y147143D02*
X334218Y147364D01*
G01X334208Y146999D02*
X334213Y147143D01*
G01X334236Y150521D02*
X334234Y149826D01*
G01X334237Y150838D02*
X334236Y150521D01*
G01X334240Y151120D02*
X334237Y150838D01*
G01X334243Y151359D02*
X334240Y151120D01*
G01X334246Y151547D02*
X334243Y151359D01*
G01X334250Y151677D02*
X334246Y151547D01*
G01X334254Y151746D02*
X334250Y151677D01*
G01X334258Y151750D02*
X334254Y151746D01*
G01X334242Y148520D02*
X334245Y149807D01*
G01X334239Y147925D02*
X334242Y148520D01*
G01X334235Y147384D02*
X334239Y147925D01*
G01X334230Y146913D02*
X334235Y147384D01*
G01X334224Y146524D02*
X334230Y146913D01*
G01X334217Y146230D02*
X334224Y146524D01*
G01X334210Y146037D02*
X334217Y146230D01*
G01X334145Y144988D02*
X334160Y145050D01*
G01X334138Y145118D02*
X334145Y144988D01*
G01X334131Y145353D02*
X334138Y145118D01*
G01X334137Y140412D02*
X334127Y140138D01*
G01X334143Y140429D02*
X334137Y140412D01*
G01X334148Y140365D02*
X334143Y140429D01*
G01X334136Y141390D02*
X334122Y141024D01*
G01X334143Y141412D02*
X334136Y141390D01*
G01X334151Y141327D02*
X334143Y141412D01*
G01X334215Y139853D02*
X334201Y140340D01*
G01X334221Y139464D02*
X334215Y139853D01*
G01X334226Y138993D02*
X334221Y139464D01*
G01X334230Y138453D02*
X334226Y138993D01*
G01X334233Y137857D02*
X334230Y138453D01*
G01X334235Y137224D02*
X334233Y137857D01*
G01X334236Y136570D02*
X334235Y137224D01*
G01X334240Y134700D02*
X334248Y134627D01*
G01X334237Y134830D02*
X334240Y134700D01*
G01X334233Y135018D02*
X334237Y134830D01*
G01X334230Y135257D02*
X334233Y135018D01*
G01X334228Y135540D02*
X334230Y135257D01*
G01X334226Y135857D02*
X334228Y135540D01*
G01X334225Y136198D02*
X334226Y135857D01*
G01X334225Y136551D02*
Y136198D01*
G01X334209Y139013D02*
X334199Y139379D01*
G01X334213Y138722D02*
X334209Y139013D01*
G01X334217Y138368D02*
X334213Y138722D01*
G01X334220Y137963D02*
X334217Y138368D01*
G01X334223Y137516D02*
X334220Y137963D01*
G01X334224Y137041D02*
X334223Y137516D01*
G01X334225Y136551D02*
X334224Y137041D01*
G01X335855Y140412D02*
X335844Y140365D01*
G01X335861Y140314D02*
X335855Y140412D01*
G01X335866Y140138D02*
X335861Y140314D01*
G01X335770Y137516D02*
X335768Y136551D01*
G01X335772Y137963D02*
X335770Y137516D01*
G01X335775Y138368D02*
X335772Y137963D01*
G01X335779Y138722D02*
X335775Y138368D01*
G01X335784Y139013D02*
X335779Y138722D01*
G01X335789Y139234D02*
X335784Y139013D01*
G01X335794Y139379D02*
X335789Y139234D01*
G01X335766Y135857D02*
X335768Y136551D01*
G01X335765Y135540D02*
X335766Y135857D01*
G01X335762Y135257D02*
X335765Y135540D01*
G01X335759Y135018D02*
X335762Y135257D01*
G01X335756Y134830D02*
X335759Y135018D01*
G01X335752Y134700D02*
X335756Y134830D01*
G01X335748Y134632D02*
X335752Y134700D01*
G01X335744Y134627D02*
X335748Y134632D01*
G01X335760Y137857D02*
X335757Y136570D01*
G01X335763Y138453D02*
X335760Y137857D01*
G01X335767Y138993D02*
X335763Y138453D01*
G01X335772Y139464D02*
X335767Y138993D01*
G01X335778Y139853D02*
X335772Y139464D01*
G01X335785Y140148D02*
X335778Y139853D01*
G01X335792Y140340D02*
X335785Y140148D01*
G01X335857Y141390D02*
X335842Y141327D01*
G01X335864Y141259D02*
X335857Y141390D01*
G01X335870Y141024D02*
X335864Y141259D01*
G01X330205Y145965D02*
X330216Y146012D01*
G01X330200Y146063D02*
X330205Y145965D01*
G01X330195Y146239D02*
X330200Y146063D01*
G01X330290Y148861D02*
X330292Y149826D01*
G01X330288Y148414D02*
X330290Y148861D01*
G01X330285Y148009D02*
X330288Y148414D01*
G01X330281Y147656D02*
X330285Y148009D01*
G01X330277Y147364D02*
X330281Y147656D01*
G01X330272Y147143D02*
X330277Y147364D01*
G01X330266Y146999D02*
X330272Y147143D01*
G01X330301Y148520D02*
X330303Y149807D01*
G01X330297Y147925D02*
X330301Y148520D01*
G01X330293Y147384D02*
X330297Y147925D01*
G01X330288Y146913D02*
X330293Y147384D01*
G01X330282Y146524D02*
X330288Y146913D01*
G01X330276Y146230D02*
X330282Y146524D01*
G01X330269Y146037D02*
X330276Y146230D01*
G01X330204Y144988D02*
X330218Y145050D01*
G01X330197Y145118D02*
X330204Y144988D01*
G01X330190Y145353D02*
X330197Y145118D01*
G01X331924Y144988D02*
X331938Y145353D01*
G01X331917Y144965D02*
X331924Y144988D01*
G01X331910Y145050D02*
X331917Y144965D01*
G01X331846Y146524D02*
X331859Y146037D01*
G01X331840Y146913D02*
X331846Y146524D01*
G01X331835Y147384D02*
X331840Y146913D01*
G01X331830Y147925D02*
X331835Y147384D01*
G01X331827Y148520D02*
X331830Y147925D01*
G01X331825Y149153D02*
X331827Y148520D01*
G01X331825Y149807D02*
Y149153D01*
G01X331851Y147364D02*
X331862Y146999D01*
G01X331847Y147656D02*
X331851Y147364D01*
G01X331843Y148009D02*
X331847Y147656D01*
G01X331840Y148414D02*
X331843Y148009D01*
G01X331838Y148861D02*
X331840Y148414D01*
G01X331836Y149336D02*
X331838Y148861D01*
G01X331836Y149826D02*
Y149336D01*
G01X331923Y145965D02*
X331933Y146239D01*
G01X331917Y145948D02*
X331923Y145965D01*
G01X331912Y146012D02*
X331917Y145948D01*
G01X331923Y140412D02*
X331912Y140365D01*
G01X331928Y140314D02*
X331923Y140412D01*
G01X331933Y140138D02*
X331928Y140314D01*
G01X331838Y137516D02*
X331836Y136551D01*
G01X331840Y137963D02*
X331838Y137516D01*
G01X331843Y138368D02*
X331840Y137963D01*
G01X331847Y138722D02*
X331843Y138368D01*
G01X331851Y139013D02*
X331847Y138722D01*
G01X331856Y139234D02*
X331851Y139013D01*
G01X331862Y139379D02*
X331856Y139234D01*
G01X331827Y137857D02*
X331825Y136570D01*
G01X331830Y138453D02*
X331827Y137857D01*
G01X331835Y138993D02*
X331830Y138453D01*
G01X331840Y139464D02*
X331835Y138993D01*
G01X331846Y139853D02*
X331840Y139464D01*
G01X331852Y140148D02*
X331846Y139853D01*
G01X331859Y140340D02*
X331852Y140148D01*
G01X331924Y141390D02*
X331910Y141327D01*
G01X331931Y141259D02*
X331924Y141390D01*
G01X331938Y141024D02*
X331931Y141259D01*
G01X330204Y141390D02*
X330190Y141024D01*
G01X330211Y141412D02*
X330204Y141390D01*
G01X330218Y141327D02*
X330211Y141412D01*
G01X330282Y139853D02*
X330269Y140340D01*
G01X330288Y139464D02*
X330282Y139853D01*
G01X330293Y138993D02*
X330288Y139464D01*
G01X330297Y138453D02*
X330293Y138993D01*
G01X330301Y137857D02*
X330297Y138453D01*
G01X330302Y137224D02*
X330301Y137857D01*
G01X330303Y136570D02*
X330302Y137224D01*
G01X330277Y139013D02*
X330266Y139379D01*
G01X330281Y138722D02*
X330277Y139013D01*
G01X330285Y138368D02*
X330281Y138722D01*
G01X330288Y137963D02*
X330285Y138368D01*
G01X330290Y137516D02*
X330288Y137963D01*
G01X330292Y137041D02*
X330290Y137516D01*
G01X330292Y136551D02*
Y137041D01*
G01X330205Y140412D02*
X330195Y140138D01*
G01X330210Y140429D02*
X330205Y140412D01*
G01X330216Y140365D02*
X330210Y140429D01*
G01X326273Y145965D02*
X326284Y146012D01*
G01X326267Y146063D02*
X326273Y145965D01*
G01X326262Y146239D02*
X326267Y146063D01*
G01X326358Y148861D02*
X326360Y149826D01*
G01X326356Y148414D02*
X326358Y148861D01*
G01X326352Y148009D02*
X326356Y148414D01*
G01X326349Y147656D02*
X326352Y148009D01*
G01X326344Y147364D02*
X326349Y147656D01*
G01X326339Y147143D02*
X326344Y147364D01*
G01X326334Y146999D02*
X326339Y147143D01*
G01X326362Y150521D02*
X326360Y149826D01*
G01X326363Y150838D02*
X326362Y150521D01*
G01X326366Y151120D02*
X326363Y150838D01*
G01X326369Y151359D02*
X326366Y151120D01*
G01X326372Y151547D02*
X326369Y151359D01*
G01X326376Y151677D02*
X326372Y151547D01*
G01X326380Y151746D02*
X326376Y151677D01*
G01X326384Y151750D02*
X326380Y151746D01*
G01X326368Y148520D02*
X326371Y149807D01*
G01X326365Y147925D02*
X326368Y148520D01*
G01X326361Y147384D02*
X326365Y147925D01*
G01X326356Y146913D02*
X326361Y147384D01*
G01X326350Y146524D02*
X326356Y146913D01*
G01X326343Y146230D02*
X326350Y146524D01*
G01X326336Y146037D02*
X326343Y146230D01*
G01X326271Y144988D02*
X326286Y145050D01*
G01X326264Y145118D02*
X326271Y144988D01*
G01X326257Y145353D02*
X326264Y145118D01*
G01X327992Y144988D02*
X328006Y145353D01*
G01X327985Y144965D02*
X327992Y144988D01*
G01X327977Y145050D02*
X327985Y144965D01*
G01X327913Y146524D02*
X327927Y146037D01*
G01X327907Y146913D02*
X327913Y146524D01*
G01X327902Y147384D02*
X327907Y146913D01*
G01X327898Y147925D02*
X327902Y147384D01*
G01X327895Y148520D02*
X327898Y147925D01*
G01X327893Y149153D02*
X327895Y148520D01*
G01X327892Y149807D02*
X327893Y149153D01*
G01X327888Y151677D02*
X327880Y151750D01*
G01X327891Y151547D02*
X327888Y151677D01*
G01X327895Y151359D02*
X327891Y151547D01*
G01X327898Y151120D02*
X327895Y151359D01*
G01X327900Y150838D02*
X327898Y151120D01*
G01X327902Y150521D02*
X327900Y150838D01*
G01X327903Y150180D02*
X327902Y150521D01*
G01X327903Y149826D02*
Y150180D01*
G01X327919Y147364D02*
X327929Y146999D01*
G01X327915Y147656D02*
X327919Y147364D01*
G01X327911Y148009D02*
X327915Y147656D01*
G01X327908Y148414D02*
X327911Y148009D01*
G01X327905Y148861D02*
X327908Y148414D01*
G01X327904Y149336D02*
X327905Y148861D01*
G01X327903Y149826D02*
X327904Y149336D01*
G01X327991Y145965D02*
X328001Y146239D01*
G01X327985Y145948D02*
X327991Y145965D01*
G01X327980Y146012D02*
X327985Y145948D01*
G01X327981Y140412D02*
X327970Y140365D01*
G01X327987Y140314D02*
X327981Y140412D01*
G01X327992Y140138D02*
X327987Y140314D01*
G01X327896Y137516D02*
X327894Y136551D01*
G01X327898Y137963D02*
X327896Y137516D01*
G01X327901Y138368D02*
X327898Y137963D01*
G01X327905Y138722D02*
X327901Y138368D01*
G01X327910Y139013D02*
X327905Y138722D01*
G01X327915Y139234D02*
X327910Y139013D01*
G01X327920Y139379D02*
X327915Y139234D01*
G01X327892Y135857D02*
X327894Y136551D01*
G01X327891Y135540D02*
X327892Y135857D01*
G01X327888Y135257D02*
X327891Y135540D01*
G01X327885Y135018D02*
X327888Y135257D01*
G01X327882Y134830D02*
X327885Y135018D01*
G01X327878Y134700D02*
X327882Y134830D01*
G01X327874Y134632D02*
X327878Y134700D01*
G01X327870Y134627D02*
X327874Y134632D01*
G01X327886Y137857D02*
X327883Y136570D01*
G01X327889Y138453D02*
X327886Y137857D01*
G01X327893Y138993D02*
X327889Y138453D01*
G01X327898Y139464D02*
X327893Y138993D01*
G01X327904Y139853D02*
X327898Y139464D01*
G01X327911Y140148D02*
X327904Y139853D01*
G01X327918Y140340D02*
X327911Y140148D01*
G01X327983Y141390D02*
X327968Y141327D01*
G01X327990Y141259D02*
X327983Y141390D01*
G01X327996Y141024D02*
X327990Y141259D01*
G01X326262Y141390D02*
X326248Y141024D01*
G01X326269Y141412D02*
X326262Y141390D01*
G01X326277Y141327D02*
X326269Y141412D01*
G01X326341Y139853D02*
X326327Y140340D01*
G01X326346Y139464D02*
X326341Y139853D01*
G01X326352Y138993D02*
X326346Y139464D01*
G01X326356Y138453D02*
X326352Y138993D01*
G01X326359Y137857D02*
X326356Y138453D01*
G01X326361Y137224D02*
X326359Y137857D01*
G01X326362Y136570D02*
X326361Y137224D01*
G01X326366Y134700D02*
X326374Y134627D01*
G01X326363Y134830D02*
X326366Y134700D01*
G01X326359Y135018D02*
X326363Y134830D01*
G01X326356Y135257D02*
X326359Y135018D01*
G01X326354Y135540D02*
X326356Y135257D01*
G01X326352Y135857D02*
X326354Y135540D01*
G01X326351Y136198D02*
X326352Y135857D01*
G01X326351Y136551D02*
Y136198D01*
G01X326335Y139013D02*
X326325Y139379D01*
G01X326339Y138722D02*
X326335Y139013D01*
G01X326343Y138368D02*
X326339Y138722D01*
G01X326346Y137963D02*
X326343Y138368D01*
G01X326349Y137516D02*
X326346Y137963D01*
G01X326350Y137041D02*
X326349Y137516D01*
G01X326351Y136551D02*
X326350Y137041D01*
G01X326263Y140412D02*
X326253Y140138D01*
G01X326269Y140429D02*
X326263Y140412D01*
G01X326274Y140365D02*
X326269Y140429D01*
G01X322331Y145965D02*
X322342Y146012D01*
G01X322326Y146063D02*
X322331Y145965D01*
G01X322321Y146239D02*
X322326Y146063D01*
G01X322416Y148861D02*
X322418Y149826D01*
G01X322414Y148414D02*
X322416Y148861D01*
G01X322411Y148009D02*
X322414Y148414D01*
G01X322407Y147656D02*
X322411Y148009D01*
G01X322403Y147364D02*
X322407Y147656D01*
G01X322398Y147143D02*
X322403Y147364D01*
G01X322392Y146999D02*
X322398Y147143D01*
G01X322427Y148520D02*
X322429Y149807D01*
G01X322423Y147925D02*
X322427Y148520D01*
G01X322419Y147384D02*
X322423Y147925D01*
G01X322414Y146913D02*
X322419Y147384D01*
G01X322408Y146524D02*
X322414Y146913D01*
G01X322402Y146230D02*
X322408Y146524D01*
G01X322395Y146037D02*
X322402Y146230D01*
G01X322330Y144988D02*
X322344Y145050D01*
G01X322323Y145118D02*
X322330Y144988D01*
G01X322316Y145353D02*
X322323Y145118D01*
G01X324050Y144988D02*
X324064Y145353D01*
G01X324043Y144965D02*
X324050Y144988D01*
G01X324036Y145050D02*
X324043Y144965D01*
G01X323972Y146524D02*
X323985Y146037D01*
G01X323966Y146913D02*
X323972Y146524D01*
G01X323961Y147384D02*
X323966Y146913D01*
G01X323956Y147925D02*
X323961Y147384D01*
G01X323953Y148520D02*
X323956Y147925D01*
G01X323951Y149153D02*
X323953Y148520D01*
G01X323951Y149807D02*
Y149153D01*
G01X323977Y147364D02*
X323988Y146999D01*
G01X323973Y147656D02*
X323977Y147364D01*
G01X323969Y148009D02*
X323973Y147656D01*
G01X323966Y148414D02*
X323969Y148009D01*
G01X323964Y148861D02*
X323966Y148414D01*
G01X323962Y149336D02*
X323964Y148861D01*
G01X323962Y149826D02*
Y149336D01*
G01X324049Y145965D02*
X324059Y146239D01*
G01X324043Y145948D02*
X324049Y145965D01*
G01X324038Y146012D02*
X324043Y145948D01*
G01X324049Y140412D02*
X324038Y140365D01*
G01X324054Y140314D02*
X324049Y140412D01*
G01X324059Y140138D02*
X324054Y140314D01*
G01X323964Y137516D02*
X323962Y136551D01*
G01X323966Y137963D02*
X323964Y137516D01*
G01X323969Y138368D02*
X323966Y137963D01*
G01X323973Y138722D02*
X323969Y138368D01*
G01X323977Y139013D02*
X323973Y138722D01*
G01X323982Y139234D02*
X323977Y139013D01*
G01X323988Y139379D02*
X323982Y139234D01*
G01X323953Y137857D02*
X323951Y136570D01*
G01X323956Y138453D02*
X323953Y137857D01*
G01X323961Y138993D02*
X323956Y138453D01*
G01X323966Y139464D02*
X323961Y138993D01*
G01X323972Y139853D02*
X323966Y139464D01*
G01X323978Y140148D02*
X323972Y139853D01*
G01X323985Y140340D02*
X323978Y140148D01*
G01X324050Y141390D02*
X324036Y141327D01*
G01X324057Y141259D02*
X324050Y141390D01*
G01X324064Y141024D02*
X324057Y141259D01*
G01X322330Y141390D02*
X322316Y141024D01*
G01X322337Y141412D02*
X322330Y141390D01*
G01X322344Y141327D02*
X322337Y141412D01*
G01X322408Y139853D02*
X322395Y140340D01*
G01X322414Y139464D02*
X322408Y139853D01*
G01X322419Y138993D02*
X322414Y139464D01*
G01X322423Y138453D02*
X322419Y138993D01*
G01X322427Y137857D02*
X322423Y138453D01*
G01X322428Y137224D02*
X322427Y137857D01*
G01X322429Y136570D02*
X322428Y137224D01*
G01X322403Y139013D02*
X322392Y139379D01*
G01X322407Y138722D02*
X322403Y139013D01*
G01X322411Y138368D02*
X322407Y138722D01*
G01X322414Y137963D02*
X322411Y138368D01*
G01X322416Y137516D02*
X322414Y137963D01*
G01X322418Y137041D02*
X322416Y137516D01*
G01X322418Y136551D02*
Y137041D01*
G01X322331Y140412D02*
X322321Y140138D01*
G01X322336Y140429D02*
X322331Y140412D01*
G01X322342Y140365D02*
X322336Y140429D01*
G01X318399Y145965D02*
X318410Y146012D01*
G01X318393Y146063D02*
X318399Y145965D01*
G01X318388Y146239D02*
X318393Y146063D01*
G01X318484Y148861D02*
X318486Y149826D01*
G01X318482Y148414D02*
X318484Y148861D01*
G01X318478Y148009D02*
X318482Y148414D01*
G01X318475Y147656D02*
X318478Y148009D01*
G01X318470Y147364D02*
X318475Y147656D01*
G01X318465Y147143D02*
X318470Y147364D01*
G01X318460Y146999D02*
X318465Y147143D01*
G01X318487Y150521D02*
X318486Y149826D01*
G01X318489Y150838D02*
X318487Y150521D01*
G01X318492Y151120D02*
X318489Y150838D01*
G01X318495Y151359D02*
X318492Y151120D01*
G01X318498Y151547D02*
X318495Y151359D01*
G01X318502Y151677D02*
X318498Y151547D01*
G01X318506Y151746D02*
X318502Y151677D01*
G01X318510Y151750D02*
X318506Y151746D01*
G01X318494Y148520D02*
X318497Y149807D01*
G01X318491Y147925D02*
X318494Y148520D01*
G01X318487Y147384D02*
X318491Y147925D01*
G01X318482Y146913D02*
X318487Y147384D01*
G01X318476Y146524D02*
X318482Y146913D01*
G01X318469Y146230D02*
X318476Y146524D01*
G01X318462Y146037D02*
X318469Y146230D01*
G01X318397Y144988D02*
X318412Y145050D01*
G01X318390Y145118D02*
X318397Y144988D01*
G01X318383Y145353D02*
X318390Y145118D01*
G01X320118Y144988D02*
X320132Y145353D01*
G01X320111Y144965D02*
X320118Y144988D01*
G01X320103Y145050D02*
X320111Y144965D01*
G01X320039Y146524D02*
X320053Y146037D01*
G01X320033Y146913D02*
X320039Y146524D01*
G01X320028Y147384D02*
X320033Y146913D01*
G01X320024Y147925D02*
X320028Y147384D01*
G01X320021Y148520D02*
X320024Y147925D01*
G01X320019Y149153D02*
X320021Y148520D01*
G01X320018Y149807D02*
X320019Y149153D01*
G01X320013Y151677D02*
X320006Y151750D01*
G01X320017Y151547D02*
X320013Y151677D01*
G01X320021Y151359D02*
X320017Y151547D01*
G01X320023Y151120D02*
X320021Y151359D01*
G01X320026Y150838D02*
X320023Y151120D01*
G01X320028Y150521D02*
X320026Y150838D01*
G01X320029Y150180D02*
X320028Y150521D01*
G01X320029Y149826D02*
Y150180D01*
G01X320045Y147364D02*
X320055Y146999D01*
G01X320041Y147656D02*
X320045Y147364D01*
G01X320037Y148009D02*
X320041Y147656D01*
G01X320034Y148414D02*
X320037Y148009D01*
G01X320031Y148861D02*
X320034Y148414D01*
G01X320030Y149336D02*
X320031Y148861D01*
G01X320029Y149826D02*
X320030Y149336D01*
G01X320117Y145965D02*
X320127Y146239D01*
G01X320111Y145948D02*
X320117Y145965D01*
G01X320106Y146012D02*
X320111Y145948D01*
G01X320107Y140412D02*
X320096Y140365D01*
G01X320113Y140314D02*
X320107Y140412D01*
G01X320118Y140138D02*
X320113Y140314D01*
G01X320022Y137516D02*
X320020Y136551D01*
G01X320024Y137963D02*
X320022Y137516D01*
G01X320027Y138368D02*
X320024Y137963D01*
G01X320031Y138722D02*
X320027Y138368D01*
G01X320036Y139013D02*
X320031Y138722D01*
G01X320041Y139234D02*
X320036Y139013D01*
G01X320046Y139379D02*
X320041Y139234D01*
G01X320018Y135857D02*
X320020Y136551D01*
G01X320017Y135540D02*
X320018Y135857D01*
G01X320014Y135257D02*
X320017Y135540D01*
G01X320011Y135018D02*
X320014Y135257D01*
G01X320008Y134830D02*
X320011Y135018D01*
G01X320004Y134700D02*
X320008Y134830D01*
G01X320000Y134632D02*
X320004Y134700D01*
G01X319996Y134627D02*
X320000Y134632D01*
G01X320012Y137857D02*
X320009Y136570D01*
G01X320015Y138453D02*
X320012Y137857D01*
G01X320019Y138993D02*
X320015Y138453D01*
G01X320024Y139464D02*
X320019Y138993D01*
G01X320030Y139853D02*
X320024Y139464D01*
G01X320037Y140148D02*
X320030Y139853D01*
G01X320044Y140340D02*
X320037Y140148D01*
G01X320109Y141390D02*
X320094Y141327D01*
G01X320116Y141259D02*
X320109Y141390D01*
G01X320122Y141024D02*
X320116Y141259D01*
G01X318388Y141390D02*
X318374Y141024D01*
G01X318395Y141412D02*
X318388Y141390D01*
G01X318403Y141327D02*
X318395Y141412D01*
G01X318467Y139853D02*
X318453Y140340D01*
G01X318472Y139464D02*
X318467Y139853D01*
G01X318478Y138993D02*
X318472Y139464D01*
G01X318482Y138453D02*
X318478Y138993D01*
G01X318485Y137857D02*
X318482Y138453D01*
G01X318487Y137224D02*
X318485Y137857D01*
G01X318488Y136570D02*
X318487Y137224D01*
G01X318492Y134700D02*
X318500Y134627D01*
G01X318489Y134830D02*
X318492Y134700D01*
G01X318485Y135018D02*
X318489Y134830D01*
G01X318482Y135257D02*
X318485Y135018D01*
G01X318480Y135540D02*
X318482Y135257D01*
G01X318478Y135857D02*
X318480Y135540D01*
G01X318477Y136198D02*
X318478Y135857D01*
G01X318477Y136551D02*
Y136198D01*
G01X318461Y139013D02*
X318451Y139379D01*
G01X318465Y138722D02*
X318461Y139013D01*
G01X318469Y138368D02*
X318465Y138722D01*
G01X318472Y137963D02*
X318469Y138368D01*
G01X318475Y137516D02*
X318472Y137963D01*
G01X318476Y137041D02*
X318475Y137516D01*
G01X318477Y136551D02*
X318476Y137041D01*
G01X318389Y140412D02*
X318379Y140138D01*
G01X318395Y140429D02*
X318389Y140412D01*
G01X318400Y140365D02*
X318395Y140429D01*
G01X314457Y145965D02*
X314468Y146012D01*
G01X314452Y146063D02*
X314457Y145965D01*
G01X314447Y146239D02*
X314452Y146063D01*
G01X314542Y148861D02*
X314544Y149826D01*
G01X314540Y148414D02*
X314542Y148861D01*
G01X314537Y148009D02*
X314540Y148414D01*
G01X314533Y147656D02*
X314537Y148009D01*
G01X314529Y147364D02*
X314533Y147656D01*
G01X314524Y147143D02*
X314529Y147364D01*
G01X314518Y146999D02*
X314524Y147143D01*
G01X314553Y148520D02*
X314555Y149807D01*
G01X314549Y147925D02*
X314553Y148520D01*
G01X314545Y147384D02*
X314549Y147925D01*
G01X314540Y146913D02*
X314545Y147384D01*
G01X314534Y146524D02*
X314540Y146913D01*
G01X314528Y146230D02*
X314534Y146524D01*
G01X314521Y146037D02*
X314528Y146230D01*
G01X314456Y144988D02*
X314470Y145050D01*
G01X314449Y145118D02*
X314456Y144988D01*
G01X314442Y145353D02*
X314449Y145118D01*
G01X316175Y145965D02*
X316185Y146239D01*
G01X316169Y145948D02*
X316175Y145965D01*
G01X316164Y146012D02*
X316169Y145948D01*
G01X316176Y144988D02*
X316190Y145353D01*
G01X316169Y144965D02*
X316176Y144988D01*
G01X316162Y145050D02*
X316169Y144965D01*
G01X316098Y146524D02*
X316111Y146037D01*
G01X316092Y146913D02*
X316098Y146524D01*
G01X316087Y147384D02*
X316092Y146913D01*
G01X316082Y147925D02*
X316087Y147384D01*
G01X316079Y148520D02*
X316082Y147925D01*
G01X316077Y149153D02*
X316079Y148520D01*
G01X316077Y149807D02*
Y149153D01*
G01X316103Y147364D02*
X316114Y146999D01*
G01X316099Y147656D02*
X316103Y147364D01*
G01X316095Y148009D02*
X316099Y147656D01*
G01X316092Y148414D02*
X316095Y148009D01*
G01X316090Y148861D02*
X316092Y148414D01*
G01X316088Y149336D02*
X316090Y148861D01*
G01X316088Y149826D02*
Y149336D01*
G01X316175Y140412D02*
X316164Y140365D01*
G01X316180Y140314D02*
X316175Y140412D01*
G01X316185Y140138D02*
X316180Y140314D01*
G01X316090Y137516D02*
X316088Y136551D01*
G01X316092Y137963D02*
X316090Y137516D01*
G01X316095Y138368D02*
X316092Y137963D01*
G01X316099Y138722D02*
X316095Y138368D01*
G01X316103Y139013D02*
X316099Y138722D01*
G01X316108Y139234D02*
X316103Y139013D01*
G01X316114Y139379D02*
X316108Y139234D01*
G01X316079Y137857D02*
X316077Y136570D01*
G01X316082Y138453D02*
X316079Y137857D01*
G01X316087Y138993D02*
X316082Y138453D01*
G01X316092Y139464D02*
X316087Y138993D01*
G01X316098Y139853D02*
X316092Y139464D01*
G01X316104Y140148D02*
X316098Y139853D01*
G01X316111Y140340D02*
X316104Y140148D01*
G01X316176Y141390D02*
X316162Y141327D01*
G01X316183Y141259D02*
X316176Y141390D01*
G01X316190Y141024D02*
X316183Y141259D01*
G01X314457Y140412D02*
X314447Y140138D01*
G01X314462Y140429D02*
X314457Y140412D01*
G01X314468Y140365D02*
X314462Y140429D01*
G01X314456Y141390D02*
X314442Y141024D01*
G01X314463Y141412D02*
X314456Y141390D01*
G01X314470Y141327D02*
X314463Y141412D01*
G01X314534Y139853D02*
X314521Y140340D01*
G01X314540Y139464D02*
X314534Y139853D01*
G01X314545Y138993D02*
X314540Y139464D01*
G01X314549Y138453D02*
X314545Y138993D01*
G01X314553Y137857D02*
X314549Y138453D01*
G01X314554Y137224D02*
X314553Y137857D01*
G01X314555Y136570D02*
X314554Y137224D01*
G01X314529Y139013D02*
X314518Y139379D01*
G01X314533Y138722D02*
X314529Y139013D01*
G01X314537Y138368D02*
X314533Y138722D01*
G01X314540Y137963D02*
X314537Y138368D01*
G01X314542Y137516D02*
X314540Y137963D01*
G01X314544Y137041D02*
X314542Y137516D01*
G01X314544Y136551D02*
Y137041D01*
G01X312243Y145965D02*
X312253Y146239D01*
G01X312237Y145948D02*
X312243Y145965D01*
G01X312232Y146012D02*
X312237Y145948D01*
G01X312244Y144988D02*
X312258Y145353D01*
G01X312237Y144965D02*
X312244Y144988D01*
G01X312229Y145050D02*
X312237Y144965D01*
G01X312165Y146524D02*
X312179Y146037D01*
G01X312159Y146913D02*
X312165Y146524D01*
G01X312154Y147384D02*
X312159Y146913D01*
G01X312150Y147925D02*
X312154Y147384D01*
G01X312147Y148520D02*
X312150Y147925D01*
G01X312145Y149153D02*
X312147Y148520D01*
G01X312144Y149807D02*
X312145Y149153D01*
G01X312139Y151677D02*
X312132Y151750D01*
G01X312143Y151547D02*
X312139Y151677D01*
G01X312147Y151359D02*
X312143Y151547D01*
G01X312149Y151120D02*
X312147Y151359D01*
G01X312152Y150838D02*
X312149Y151120D01*
G01X312154Y150521D02*
X312152Y150838D01*
G01X312155Y150180D02*
X312154Y150521D01*
G01X312155Y149826D02*
Y150180D01*
G01X312171Y147364D02*
X312181Y146999D01*
G01X312167Y147656D02*
X312171Y147364D01*
G01X312163Y148009D02*
X312167Y147656D01*
G01X312160Y148414D02*
X312163Y148009D01*
G01X312157Y148861D02*
X312160Y148414D01*
G01X312156Y149336D02*
X312157Y148861D01*
G01X312155Y149826D02*
X312156Y149336D01*
G01X310525Y145965D02*
X310536Y146012D01*
G01X310519Y146063D02*
X310525Y145965D01*
G01X310514Y146239D02*
X310519Y146063D01*
G01X310610Y148861D02*
X310612Y149826D01*
G01X310608Y148414D02*
X310610Y148861D01*
G01X310604Y148009D02*
X310608Y148414D01*
G01X310601Y147656D02*
X310604Y148009D01*
G01X310596Y147364D02*
X310601Y147656D01*
G01X310591Y147143D02*
X310596Y147364D01*
G01X310586Y146999D02*
X310591Y147143D01*
G01X310613Y150521D02*
X310612Y149826D01*
G01X310615Y150838D02*
X310613Y150521D01*
G01X310618Y151120D02*
X310615Y150838D01*
G01X310621Y151359D02*
X310618Y151120D01*
G01X310624Y151547D02*
X310621Y151359D01*
G01X310628Y151677D02*
X310624Y151547D01*
G01X310632Y151746D02*
X310628Y151677D01*
G01X310636Y151750D02*
X310632Y151746D01*
G01X310620Y148520D02*
X310623Y149807D01*
G01X310617Y147925D02*
X310620Y148520D01*
G01X310613Y147384D02*
X310617Y147925D01*
G01X310608Y146913D02*
X310613Y147384D01*
G01X310602Y146524D02*
X310608Y146913D01*
G01X310595Y146230D02*
X310602Y146524D01*
G01X310588Y146037D02*
X310595Y146230D01*
G01X310523Y144988D02*
X310538Y145050D01*
G01X310516Y145118D02*
X310523Y144988D01*
G01X310509Y145353D02*
X310516Y145118D01*
G01X310515Y140412D02*
X310505Y140138D01*
G01X310521Y140429D02*
X310515Y140412D01*
G01X310526Y140365D02*
X310521Y140429D01*
G01X310514Y141390D02*
X310500Y141024D01*
G01X310521Y141412D02*
X310514Y141390D01*
G01X310529Y141327D02*
X310521Y141412D01*
G01X310593Y139853D02*
X310579Y140340D01*
G01X310598Y139464D02*
X310593Y139853D01*
G01X310604Y138993D02*
X310598Y139464D01*
G01X310608Y138453D02*
X310604Y138993D01*
G01X310611Y137857D02*
X310608Y138453D01*
G01X310613Y137224D02*
X310611Y137857D01*
G01X310614Y136570D02*
X310613Y137224D01*
G01X310618Y134700D02*
X310626Y134627D01*
G01X310615Y134830D02*
X310618Y134700D01*
G01X310611Y135018D02*
X310615Y134830D01*
G01X310608Y135257D02*
X310611Y135018D01*
G01X310606Y135540D02*
X310608Y135257D01*
G01X310604Y135857D02*
X310606Y135540D01*
G01X310603Y136198D02*
X310604Y135857D01*
G01X310603Y136551D02*
Y136198D01*
G01X310587Y139013D02*
X310577Y139379D01*
G01X310591Y138722D02*
X310587Y139013D01*
G01X310595Y138368D02*
X310591Y138722D01*
G01X310598Y137963D02*
X310595Y138368D01*
G01X310601Y137516D02*
X310598Y137963D01*
G01X310602Y137041D02*
X310601Y137516D01*
G01X310603Y136551D02*
X310602Y137041D01*
G01X312233Y140412D02*
X312222Y140365D01*
G01X312239Y140314D02*
X312233Y140412D01*
G01X312244Y140138D02*
X312239Y140314D01*
G01X312148Y137516D02*
X312146Y136551D01*
G01X312150Y137963D02*
X312148Y137516D01*
G01X312153Y138368D02*
X312150Y137963D01*
G01X312157Y138722D02*
X312153Y138368D01*
G01X312162Y139013D02*
X312157Y138722D01*
G01X312167Y139234D02*
X312162Y139013D01*
G01X312172Y139379D02*
X312167Y139234D01*
G01X312144Y135857D02*
X312146Y136551D01*
G01X312143Y135540D02*
X312144Y135857D01*
G01X312140Y135257D02*
X312143Y135540D01*
G01X312137Y135018D02*
X312140Y135257D01*
G01X312134Y134830D02*
X312137Y135018D01*
G01X312130Y134700D02*
X312134Y134830D01*
G01X312126Y134632D02*
X312130Y134700D01*
G01X312122Y134627D02*
X312126Y134632D01*
G01X312138Y137857D02*
X312135Y136570D01*
G01X312141Y138453D02*
X312138Y137857D01*
G01X312145Y138993D02*
X312141Y138453D01*
G01X312150Y139464D02*
X312145Y138993D01*
G01X312156Y139853D02*
X312150Y139464D01*
G01X312162Y140148D02*
X312156Y139853D01*
G01X312169Y140340D02*
X312162Y140148D01*
G01X312234Y141390D02*
X312220Y141327D01*
G01X312242Y141259D02*
X312234Y141390D01*
G01X312248Y141024D02*
X312242Y141259D01*
G01X306583Y145965D02*
X306594Y146012D01*
G01X306578Y146063D02*
X306583Y145965D01*
G01X306573Y146239D02*
X306578Y146063D01*
G01X306668Y148861D02*
X306670Y149826D01*
G01X306666Y148414D02*
X306668Y148861D01*
G01X306663Y148009D02*
X306666Y148414D01*
G01X306659Y147656D02*
X306663Y148009D01*
G01X306654Y147364D02*
X306659Y147656D01*
G01X306650Y147143D02*
X306654Y147364D01*
G01X306644Y146999D02*
X306650Y147143D01*
G01X306678Y148520D02*
X306681Y149807D01*
G01X306675Y147925D02*
X306678Y148520D01*
G01X306671Y147384D02*
X306675Y147925D01*
G01X306666Y146913D02*
X306671Y147384D01*
G01X306660Y146524D02*
X306666Y146913D01*
G01X306654Y146230D02*
X306660Y146524D01*
G01X306647Y146037D02*
X306654Y146230D01*
G01X306582Y144988D02*
X306596Y145050D01*
G01X306575Y145118D02*
X306582Y144988D01*
G01X306568Y145353D02*
X306575Y145118D01*
G01X308301Y145965D02*
X308311Y146239D01*
G01X308295Y145948D02*
X308301Y145965D01*
G01X308290Y146012D02*
X308295Y145948D01*
G01X308302Y144988D02*
X308316Y145353D01*
G01X308295Y144965D02*
X308302Y144988D01*
G01X308288Y145050D02*
X308295Y144965D01*
G01X308224Y146524D02*
X308237Y146037D01*
G01X308218Y146913D02*
X308224Y146524D01*
G01X308213Y147384D02*
X308218Y146913D01*
G01X308208Y147925D02*
X308213Y147384D01*
G01X308205Y148520D02*
X308208Y147925D01*
G01X308203Y149153D02*
X308205Y148520D01*
G01X308203Y149807D02*
Y149153D01*
G01X308229Y147364D02*
X308239Y146999D01*
G01X308225Y147656D02*
X308229Y147364D01*
G01X308221Y148009D02*
X308225Y147656D01*
G01X308218Y148414D02*
X308221Y148009D01*
G01X308216Y148861D02*
X308218Y148414D01*
G01X308214Y149336D02*
X308216Y148861D01*
G01X308214Y149826D02*
Y149336D01*
G01X308301Y140412D02*
X308290Y140365D01*
G01X308306Y140314D02*
X308301Y140412D01*
G01X308311Y140138D02*
X308306Y140314D01*
G01X308216Y137516D02*
X308214Y136551D01*
G01X308218Y137963D02*
X308216Y137516D01*
G01X308221Y138368D02*
X308218Y137963D01*
G01X308225Y138722D02*
X308221Y138368D01*
G01X308229Y139013D02*
X308225Y138722D01*
G01X308234Y139234D02*
X308229Y139013D01*
G01X308239Y139379D02*
X308234Y139234D01*
G01X308205Y137857D02*
X308203Y136570D01*
G01X308208Y138453D02*
X308205Y137857D01*
G01X308213Y138993D02*
X308208Y138453D01*
G01X308218Y139464D02*
X308213Y138993D01*
G01X308224Y139853D02*
X308218Y139464D01*
G01X308230Y140148D02*
X308224Y139853D01*
G01X308237Y140340D02*
X308230Y140148D01*
G01X308302Y141390D02*
X308288Y141327D01*
G01X308309Y141259D02*
X308302Y141390D01*
G01X308316Y141024D02*
X308309Y141259D01*
G01X306583Y140412D02*
X306573Y140138D01*
G01X306588Y140429D02*
X306583Y140412D01*
G01X306594Y140365D02*
X306588Y140429D01*
G01X306582Y141390D02*
X306568Y141024D01*
G01X306589Y141412D02*
X306582Y141390D01*
G01X306596Y141327D02*
X306589Y141412D01*
G01X306660Y139853D02*
X306647Y140340D01*
G01X306666Y139464D02*
X306660Y139853D01*
G01X306671Y138993D02*
X306666Y139464D01*
G01X306675Y138453D02*
X306671Y138993D01*
G01X306678Y137857D02*
X306675Y138453D01*
G01X306680Y137224D02*
X306678Y137857D01*
G01X306681Y136570D02*
X306680Y137224D01*
G01X306654Y139013D02*
X306644Y139379D01*
G01X306659Y138722D02*
X306654Y139013D01*
G01X306663Y138368D02*
X306659Y138722D01*
G01X306666Y137963D02*
X306663Y138368D01*
G01X306668Y137516D02*
X306666Y137963D01*
G01X306670Y137041D02*
X306668Y137516D01*
G01X306670Y136551D02*
Y137041D01*
G01X304369Y145965D02*
X304379Y146239D01*
G01X304363Y145948D02*
X304369Y145965D01*
G01X304358Y146012D02*
X304363Y145948D01*
G01X304370Y144988D02*
X304384Y145353D01*
G01X304363Y144965D02*
X304370Y144988D01*
G01X304355Y145050D02*
X304363Y144965D01*
G01X304291Y146524D02*
X304305Y146037D01*
G01X304285Y146913D02*
X304291Y146524D01*
G01X304280Y147384D02*
X304285Y146913D01*
G01X304276Y147925D02*
X304280Y147384D01*
G01X304273Y148520D02*
X304276Y147925D01*
G01X304271Y149153D02*
X304273Y148520D01*
G01X304270Y149807D02*
X304271Y149153D01*
G01X304265Y151677D02*
X304258Y151750D01*
G01X304269Y151547D02*
X304265Y151677D01*
G01X304273Y151359D02*
X304269Y151547D01*
G01X304275Y151120D02*
X304273Y151359D01*
G01X304278Y150838D02*
X304275Y151120D01*
G01X304280Y150521D02*
X304278Y150838D01*
G01X304281Y150180D02*
X304280Y150521D01*
G01X304281Y149826D02*
Y150180D01*
G01X304297Y147364D02*
X304307Y146999D01*
G01X304293Y147656D02*
X304297Y147364D01*
G01X304289Y148009D02*
X304293Y147656D01*
G01X304286Y148414D02*
X304289Y148009D01*
G01X304283Y148861D02*
X304286Y148414D01*
G01X304282Y149336D02*
X304283Y148861D01*
G01X304281Y149826D02*
X304282Y149336D01*
G01X302651Y145965D02*
X302661Y146012D01*
G01X302645Y146063D02*
X302651Y145965D01*
G01X302640Y146239D02*
X302645Y146063D01*
G01X302736Y148861D02*
X302738Y149826D01*
G01X302734Y148414D02*
X302736Y148861D01*
G01X302730Y148009D02*
X302734Y148414D01*
G01X302727Y147656D02*
X302730Y148009D01*
G01X302722Y147364D02*
X302727Y147656D01*
G01X302717Y147143D02*
X302722Y147364D01*
G01X302712Y146999D02*
X302717Y147143D01*
G01X302739Y150521D02*
X302738Y149826D01*
G01X302741Y150838D02*
X302739Y150521D01*
G01X302744Y151120D02*
X302741Y150838D01*
G01X302747Y151359D02*
X302744Y151120D01*
G01X302750Y151547D02*
X302747Y151359D01*
G01X302754Y151677D02*
X302750Y151547D01*
G01X302758Y151746D02*
X302754Y151677D01*
G01X302762Y151750D02*
X302758Y151746D01*
G01X302746Y148520D02*
X302749Y149807D01*
G01X302743Y147925D02*
X302746Y148520D01*
G01X302739Y147384D02*
X302743Y147925D01*
G01X302734Y146913D02*
X302739Y147384D01*
G01X302728Y146524D02*
X302734Y146913D01*
G01X302721Y146230D02*
X302728Y146524D01*
G01X302714Y146037D02*
X302721Y146230D01*
G01X302649Y144988D02*
X302664Y145050D01*
G01X302642Y145118D02*
X302649Y144988D01*
G01X302635Y145353D02*
X302642Y145118D01*
G01X302641Y140412D02*
X302631Y140138D01*
G01X302647Y140429D02*
X302641Y140412D01*
G01X302652Y140365D02*
X302647Y140429D01*
G01X302640Y141390D02*
X302626Y141024D01*
G01X302647Y141412D02*
X302640Y141390D01*
G01X302654Y141327D02*
X302647Y141412D01*
G01X302719Y139853D02*
X302705Y140340D01*
G01X302724Y139464D02*
X302719Y139853D01*
G01X302730Y138993D02*
X302724Y139464D01*
G01X302734Y138453D02*
X302730Y138993D01*
G01X302737Y137857D02*
X302734Y138453D01*
G01X302739Y137224D02*
X302737Y137857D01*
G01X302740Y136570D02*
X302739Y137224D01*
G01X302744Y134700D02*
X302752Y134627D01*
G01X302741Y134830D02*
X302744Y134700D01*
G01X302737Y135018D02*
X302741Y134830D01*
G01X302734Y135257D02*
X302737Y135018D01*
G01X302732Y135540D02*
X302734Y135257D01*
G01X302730Y135857D02*
X302732Y135540D01*
G01X302729Y136198D02*
X302730Y135857D01*
G01X302729Y136551D02*
Y136198D01*
G01X302713Y139013D02*
X302703Y139379D01*
G01X302717Y138722D02*
X302713Y139013D01*
G01X302721Y138368D02*
X302717Y138722D01*
G01X302724Y137963D02*
X302721Y138368D01*
G01X302727Y137516D02*
X302724Y137963D01*
G01X302728Y137041D02*
X302727Y137516D01*
G01X302729Y136551D02*
X302728Y137041D01*
G01X304359Y140412D02*
X304348Y140365D01*
G01X304365Y140314D02*
X304359Y140412D01*
G01X304370Y140138D02*
X304365Y140314D01*
G01X304274Y137516D02*
X304272Y136551D01*
G01X304276Y137963D02*
X304274Y137516D01*
G01X304279Y138368D02*
X304276Y137963D01*
G01X304283Y138722D02*
X304279Y138368D01*
G01X304288Y139013D02*
X304283Y138722D01*
G01X304293Y139234D02*
X304288Y139013D01*
G01X304298Y139379D02*
X304293Y139234D01*
G01X304270Y135857D02*
X304272Y136551D01*
G01X304269Y135540D02*
X304270Y135857D01*
G01X304266Y135257D02*
X304269Y135540D01*
G01X304263Y135018D02*
X304266Y135257D01*
G01X304260Y134830D02*
X304263Y135018D01*
G01X304256Y134700D02*
X304260Y134830D01*
G01X304252Y134632D02*
X304256Y134700D01*
G01X304248Y134627D02*
X304252Y134632D01*
G01X304264Y137857D02*
X304261Y136570D01*
G01X304267Y138453D02*
X304264Y137857D01*
G01X304271Y138993D02*
X304267Y138453D01*
G01X304276Y139464D02*
X304271Y138993D01*
G01X304282Y139853D02*
X304276Y139464D01*
G01X304288Y140148D02*
X304282Y139853D01*
G01X304295Y140340D02*
X304288Y140148D01*
G01X304360Y141390D02*
X304346Y141327D01*
G01X304368Y141259D02*
X304360Y141390D01*
G01X304374Y141024D02*
X304368Y141259D01*
G01X298709Y145965D02*
X298720Y146012D01*
G01X298704Y146063D02*
X298709Y145965D01*
G01X298698Y146239D02*
X298704Y146063D01*
G01X298794Y148861D02*
X298796Y149826D01*
G01X298792Y148414D02*
X298794Y148861D01*
G01X298789Y148009D02*
X298792Y148414D01*
G01X298785Y147656D02*
X298789Y148009D01*
G01X298780Y147364D02*
X298785Y147656D01*
G01X298776Y147143D02*
X298780Y147364D01*
G01X298770Y146999D02*
X298776Y147143D01*
G01X298804Y148520D02*
X298807Y149807D01*
G01X298801Y147925D02*
X298804Y148520D01*
G01X298797Y147384D02*
X298801Y147925D01*
G01X298792Y146913D02*
X298797Y147384D01*
G01X298786Y146524D02*
X298792Y146913D01*
G01X298780Y146230D02*
X298786Y146524D01*
G01X298773Y146037D02*
X298780Y146230D01*
G01X298708Y144988D02*
X298722Y145050D01*
G01X298701Y145118D02*
X298708Y144988D01*
G01X298694Y145353D02*
X298701Y145118D01*
G01X300427Y145965D02*
X300437Y146239D01*
G01X300421Y145948D02*
X300427Y145965D01*
G01X300416Y146012D02*
X300421Y145948D01*
G01X300428Y144988D02*
X300442Y145353D01*
G01X300421Y144965D02*
X300428Y144988D01*
G01X300414Y145050D02*
X300421Y144965D01*
G01X300350Y146524D02*
X300363Y146037D01*
G01X300344Y146913D02*
X300350Y146524D01*
G01X300339Y147384D02*
X300344Y146913D01*
G01X300334Y147925D02*
X300339Y147384D01*
G01X300331Y148520D02*
X300334Y147925D01*
G01X300329Y149153D02*
X300331Y148520D01*
G01X300329Y149807D02*
Y149153D01*
G01X300355Y147364D02*
X300365Y146999D01*
G01X300351Y147656D02*
X300355Y147364D01*
G01X300347Y148009D02*
X300351Y147656D01*
G01X300344Y148414D02*
X300347Y148009D01*
G01X300342Y148861D02*
X300344Y148414D01*
G01X300340Y149336D02*
X300342Y148861D01*
G01X300340Y149826D02*
Y149336D01*
G01X300427Y140412D02*
X300416Y140365D01*
G01X300432Y140314D02*
X300427Y140412D01*
G01X300437Y140138D02*
X300432Y140314D01*
G01X300342Y137516D02*
X300340Y136551D01*
G01X300344Y137963D02*
X300342Y137516D01*
G01X300347Y138368D02*
X300344Y137963D01*
G01X300351Y138722D02*
X300347Y138368D01*
G01X300355Y139013D02*
X300351Y138722D01*
G01X300360Y139234D02*
X300355Y139013D01*
G01X300365Y139379D02*
X300360Y139234D01*
G01X300331Y137857D02*
X300329Y136570D01*
G01X300334Y138453D02*
X300331Y137857D01*
G01X300339Y138993D02*
X300334Y138453D01*
G01X300344Y139464D02*
X300339Y138993D01*
G01X300350Y139853D02*
X300344Y139464D01*
G01X300356Y140148D02*
X300350Y139853D01*
G01X300363Y140340D02*
X300356Y140148D01*
G01X300428Y141390D02*
X300414Y141327D01*
G01X300435Y141259D02*
X300428Y141390D01*
G01X300442Y141024D02*
X300435Y141259D01*
G01X298709Y140412D02*
X298698Y140138D01*
G01X298714Y140429D02*
X298709Y140412D01*
G01X298720Y140365D02*
X298714Y140429D01*
G01X298708Y141390D02*
X298694Y141024D01*
G01X298715Y141412D02*
X298708Y141390D01*
G01X298722Y141327D02*
X298715Y141412D01*
G01X298786Y139853D02*
X298773Y140340D01*
G01X298792Y139464D02*
X298786Y139853D01*
G01X298797Y138993D02*
X298792Y139464D01*
G01X298801Y138453D02*
X298797Y138993D01*
G01X298804Y137857D02*
X298801Y138453D01*
G01X298806Y137224D02*
X298804Y137857D01*
G01X298807Y136570D02*
X298806Y137224D01*
G01X298780Y139013D02*
X298770Y139379D01*
G01X298785Y138722D02*
X298780Y139013D01*
G01X298789Y138368D02*
X298785Y138722D01*
G01X298792Y137963D02*
X298789Y138368D01*
G01X298794Y137516D02*
X298792Y137963D01*
G01X298796Y137041D02*
X298794Y137516D01*
G01X298796Y136551D02*
Y137041D01*
G01X296495Y145965D02*
X296505Y146239D01*
G01X296489Y145948D02*
X296495Y145965D01*
G01X296484Y146012D02*
X296489Y145948D01*
G01X296496Y144988D02*
X296510Y145353D01*
G01X296489Y144965D02*
X296496Y144988D01*
G01X296481Y145050D02*
X296489Y144965D01*
G01X296417Y146524D02*
X296431Y146037D01*
G01X296411Y146913D02*
X296417Y146524D01*
G01X296406Y147384D02*
X296411Y146913D01*
G01X296402Y147925D02*
X296406Y147384D01*
G01X296399Y148520D02*
X296402Y147925D01*
G01X296397Y149153D02*
X296399Y148520D01*
G01X296396Y149807D02*
X296397Y149153D01*
G01X296391Y151677D02*
X296384Y151750D01*
G01X296395Y151547D02*
X296391Y151677D01*
G01X296399Y151359D02*
X296395Y151547D01*
G01X296401Y151120D02*
X296399Y151359D01*
G01X296404Y150838D02*
X296401Y151120D01*
G01X296406Y150521D02*
X296404Y150838D01*
G01X296407Y150180D02*
X296406Y150521D01*
G01X296407Y149826D02*
Y150180D01*
G01X296423Y147364D02*
X296433Y146999D01*
G01X296419Y147656D02*
X296423Y147364D01*
G01X296415Y148009D02*
X296419Y147656D01*
G01X296412Y148414D02*
X296415Y148009D01*
G01X296409Y148861D02*
X296412Y148414D01*
G01X296408Y149336D02*
X296409Y148861D01*
G01X296407Y149826D02*
X296408Y149336D01*
G01X294777Y145965D02*
X294787Y146012D01*
G01X294771Y146063D02*
X294777Y145965D01*
G01X294766Y146239D02*
X294771Y146063D01*
G01X294862Y148861D02*
X294864Y149826D01*
G01X294860Y148414D02*
X294862Y148861D01*
G01X294856Y148009D02*
X294860Y148414D01*
G01X294853Y147656D02*
X294856Y148009D01*
G01X294848Y147364D02*
X294853Y147656D01*
G01X294843Y147143D02*
X294848Y147364D01*
G01X294838Y146999D02*
X294843Y147143D01*
G01X294865Y150521D02*
X294864Y149826D01*
G01X294867Y150838D02*
X294865Y150521D01*
G01X294870Y151120D02*
X294867Y150838D01*
G01X294873Y151359D02*
X294870Y151120D01*
G01X294876Y151547D02*
X294873Y151359D01*
G01X294880Y151677D02*
X294876Y151547D01*
G01X294884Y151746D02*
X294880Y151677D01*
G01X294888Y151750D02*
X294884Y151746D01*
G01X294872Y148520D02*
X294875Y149807D01*
G01X294869Y147925D02*
X294872Y148520D01*
G01X294865Y147384D02*
X294869Y147925D01*
G01X294860Y146913D02*
X294865Y147384D01*
G01X294854Y146524D02*
X294860Y146913D01*
G01X294847Y146230D02*
X294854Y146524D01*
G01X294840Y146037D02*
X294847Y146230D01*
G01X294775Y144988D02*
X294790Y145050D01*
G01X294768Y145118D02*
X294775Y144988D01*
G01X294761Y145353D02*
X294768Y145118D01*
G01X294767Y140412D02*
X294757Y140138D01*
G01X294773Y140429D02*
X294767Y140412D01*
G01X294778Y140365D02*
X294773Y140429D01*
G01X294766Y141390D02*
X294752Y141024D01*
G01X294773Y141412D02*
X294766Y141390D01*
G01X294780Y141327D02*
X294773Y141412D01*
G01X294845Y139853D02*
X294831Y140340D01*
G01X294850Y139464D02*
X294845Y139853D01*
G01X294856Y138993D02*
X294850Y139464D01*
G01X294860Y138453D02*
X294856Y138993D01*
G01X294863Y137857D02*
X294860Y138453D01*
G01X294865Y137224D02*
X294863Y137857D01*
G01X294865Y136570D02*
Y137224D01*
G01X294870Y134700D02*
X294878Y134627D01*
G01X294867Y134830D02*
X294870Y134700D01*
G01X294863Y135018D02*
X294867Y134830D01*
G01X294860Y135257D02*
X294863Y135018D01*
G01X294858Y135540D02*
X294860Y135257D01*
G01X294856Y135857D02*
X294858Y135540D01*
G01X294855Y136198D02*
X294856Y135857D01*
G01X294855Y136551D02*
Y136198D01*
G01X294839Y139013D02*
X294829Y139379D01*
G01X294843Y138722D02*
X294839Y139013D01*
G01X294847Y138368D02*
X294843Y138722D01*
G01X294850Y137963D02*
X294847Y138368D01*
G01X294853Y137516D02*
X294850Y137963D01*
G01X294854Y137041D02*
X294853Y137516D01*
G01X294855Y136551D02*
X294854Y137041D01*
G01X296485Y140412D02*
X296474Y140365D01*
G01X296491Y140314D02*
X296485Y140412D01*
G01X296496Y140138D02*
X296491Y140314D01*
G01X296400Y137516D02*
X296398Y136551D01*
G01X296402Y137963D02*
X296400Y137516D01*
G01X296405Y138368D02*
X296402Y137963D01*
G01X296409Y138722D02*
X296405Y138368D01*
G01X296414Y139013D02*
X296409Y138722D01*
G01X296419Y139234D02*
X296414Y139013D01*
G01X296424Y139379D02*
X296419Y139234D01*
G01X296396Y135857D02*
X296398Y136551D01*
G01X296395Y135540D02*
X296396Y135857D01*
G01X296392Y135257D02*
X296395Y135540D01*
G01X296389Y135018D02*
X296392Y135257D01*
G01X296386Y134830D02*
X296389Y135018D01*
G01X296382Y134700D02*
X296386Y134830D01*
G01X296378Y134632D02*
X296382Y134700D01*
G01X296374Y134627D02*
X296378Y134632D01*
G01X296390Y137857D02*
X296387Y136570D01*
G01X296393Y138453D02*
X296390Y137857D01*
G01X296397Y138993D02*
X296393Y138453D01*
G01X296402Y139464D02*
X296397Y138993D01*
G01X296408Y139853D02*
X296402Y139464D01*
G01X296414Y140148D02*
X296408Y139853D01*
G01X296421Y140340D02*
X296414Y140148D01*
G01X296486Y141390D02*
X296472Y141327D01*
G01X296494Y141259D02*
X296486Y141390D01*
G01X296500Y141024D02*
X296494Y141259D01*
G01X290835Y145965D02*
X290846Y146012D01*
G01X290830Y146063D02*
X290835Y145965D01*
G01X290824Y146239D02*
X290830Y146063D01*
G01X290920Y148861D02*
X290922Y149826D01*
G01X290918Y148414D02*
X290920Y148861D01*
G01X290915Y148009D02*
X290918Y148414D01*
G01X290911Y147656D02*
X290915Y148009D01*
G01X290906Y147364D02*
X290911Y147656D01*
G01X290902Y147143D02*
X290906Y147364D01*
G01X290896Y146999D02*
X290902Y147143D01*
G01X290930Y148520D02*
X290933Y149807D01*
G01X290927Y147925D02*
X290930Y148520D01*
G01X290923Y147384D02*
X290927Y147925D01*
G01X290918Y146913D02*
X290923Y147384D01*
G01X290912Y146524D02*
X290918Y146913D01*
G01X290906Y146230D02*
X290912Y146524D01*
G01X290899Y146037D02*
X290906Y146230D01*
G01X290834Y144988D02*
X290848Y145050D01*
G01X290826Y145118D02*
X290834Y144988D01*
G01X290820Y145353D02*
X290826Y145118D01*
G01X292553Y145965D02*
X292563Y146239D01*
G01X292547Y145948D02*
X292553Y145965D01*
G01X292542Y146012D02*
X292547Y145948D01*
G01X292554Y144988D02*
X292568Y145353D01*
G01X292547Y144965D02*
X292554Y144988D01*
G01X292540Y145050D02*
X292547Y144965D01*
G01X292476Y146524D02*
X292489Y146037D01*
G01X292470Y146913D02*
X292476Y146524D01*
G01X292465Y147384D02*
X292470Y146913D01*
G01X292460Y147925D02*
X292465Y147384D01*
G01X292457Y148520D02*
X292460Y147925D01*
G01X292455Y149153D02*
X292457Y148520D01*
G01X292455Y149807D02*
Y149153D01*
G01X292481Y147364D02*
X292491Y146999D01*
G01X292477Y147656D02*
X292481Y147364D01*
G01X292473Y148009D02*
X292477Y147656D01*
G01X292470Y148414D02*
X292473Y148009D01*
G01X292468Y148861D02*
X292470Y148414D01*
G01X292466Y149336D02*
X292468Y148861D01*
G01X292466Y149826D02*
Y149336D01*
G01X292553Y140412D02*
X292542Y140365D01*
G01X292558Y140314D02*
X292553Y140412D01*
G01X292563Y140138D02*
X292558Y140314D01*
G01X292468Y137516D02*
X292466Y136551D01*
G01X292470Y137963D02*
X292468Y137516D01*
G01X292473Y138368D02*
X292470Y137963D01*
G01X292477Y138722D02*
X292473Y138368D01*
G01X292481Y139013D02*
X292477Y138722D01*
G01X292486Y139234D02*
X292481Y139013D01*
G01X292491Y139379D02*
X292486Y139234D01*
G01X292457Y137857D02*
X292455Y136570D01*
G01X292460Y138453D02*
X292457Y137857D01*
G01X292465Y138993D02*
X292460Y138453D01*
G01X292470Y139464D02*
X292465Y138993D01*
G01X292476Y139853D02*
X292470Y139464D01*
G01X292482Y140148D02*
X292476Y139853D01*
G01X292489Y140340D02*
X292482Y140148D01*
G01X292554Y141390D02*
X292540Y141327D01*
G01X292561Y141259D02*
X292554Y141390D01*
G01X292568Y141024D02*
X292561Y141259D01*
G01X290835Y140412D02*
X290824Y140138D01*
G01X290840Y140429D02*
X290835Y140412D01*
G01X290846Y140365D02*
X290840Y140429D01*
G01X290834Y141390D02*
X290820Y141024D01*
G01X290841Y141412D02*
X290834Y141390D01*
G01X290848Y141327D02*
X290841Y141412D01*
G01X290912Y139853D02*
X290899Y140340D01*
G01X290918Y139464D02*
X290912Y139853D01*
G01X290923Y138993D02*
X290918Y139464D01*
G01X290927Y138453D02*
X290923Y138993D01*
G01X290930Y137857D02*
X290927Y138453D01*
G01X290932Y137224D02*
X290930Y137857D01*
G01X290933Y136570D02*
X290932Y137224D01*
G01X290906Y139013D02*
X290896Y139379D01*
G01X290911Y138722D02*
X290906Y139013D01*
G01X290915Y138368D02*
X290911Y138722D01*
G01X290918Y137963D02*
X290915Y138368D01*
G01X290920Y137516D02*
X290918Y137963D01*
G01X290922Y137041D02*
X290920Y137516D01*
G01X290922Y136551D02*
Y137041D01*
G01X288620Y145965D02*
X288631Y146239D01*
G01X288615Y145948D02*
X288620Y145965D01*
G01X288610Y146012D02*
X288615Y145948D01*
G01X288622Y144988D02*
X288636Y145353D01*
G01X288615Y144965D02*
X288622Y144988D01*
G01X288607Y145050D02*
X288615Y144965D01*
G01X288543Y146524D02*
X288557Y146037D01*
G01X288537Y146913D02*
X288543Y146524D01*
G01X288532Y147384D02*
X288537Y146913D01*
G01X288528Y147925D02*
X288532Y147384D01*
G01X288525Y148520D02*
X288528Y147925D01*
G01X288523Y149153D02*
X288525Y148520D01*
G01X288522Y149807D02*
X288523Y149153D01*
G01X288517Y151677D02*
X288510Y151750D01*
G01X288521Y151547D02*
X288517Y151677D01*
G01X288524Y151359D02*
X288521Y151547D01*
G01X288527Y151120D02*
X288524Y151359D01*
G01X288530Y150838D02*
X288527Y151120D01*
G01X288532Y150521D02*
X288530Y150838D01*
G01X288533Y150180D02*
X288532Y150521D01*
G01X288533Y149826D02*
Y150180D01*
G01X288549Y147364D02*
X288559Y146999D01*
G01X288545Y147656D02*
X288549Y147364D01*
G01X288541Y148009D02*
X288545Y147656D01*
G01X288538Y148414D02*
X288541Y148009D01*
G01X288535Y148861D02*
X288538Y148414D01*
G01X288534Y149336D02*
X288535Y148861D01*
G01X288533Y149826D02*
X288534Y149336D01*
G01X286903Y145965D02*
X286913Y146012D01*
G01X286897Y146063D02*
X286903Y145965D01*
G01X286892Y146239D02*
X286897Y146063D01*
G01X286988Y148861D02*
X286990Y149826D01*
G01X286985Y148414D02*
X286988Y148861D01*
G01X286982Y148009D02*
X286985Y148414D01*
G01X286979Y147656D02*
X286982Y148009D01*
G01X286974Y147364D02*
X286979Y147656D01*
G01X286969Y147143D02*
X286974Y147364D01*
G01X286964Y146999D02*
X286969Y147143D01*
G01X286991Y150521D02*
X286990Y149826D01*
G01X286993Y150838D02*
X286991Y150521D01*
G01X286996Y151120D02*
X286993Y150838D01*
G01X286999Y151359D02*
X286996Y151120D01*
G01X287002Y151547D02*
X286999Y151359D01*
G01X287006Y151677D02*
X287002Y151547D01*
G01X287010Y151746D02*
X287006Y151677D01*
G01X287014Y151750D02*
X287010Y151746D01*
G01X286998Y148520D02*
X287001Y149807D01*
G01X286995Y147925D02*
X286998Y148520D01*
G01X286991Y147384D02*
X286995Y147925D01*
G01X286986Y146913D02*
X286991Y147384D01*
G01X286980Y146524D02*
X286986Y146913D01*
G01X286973Y146230D02*
X286980Y146524D01*
G01X286966Y146037D02*
X286973Y146230D01*
G01X286901Y144988D02*
X286916Y145050D01*
G01X286894Y145118D02*
X286901Y144988D01*
G01X286887Y145353D02*
X286894Y145118D01*
G01X286893Y140412D02*
X286883Y140138D01*
G01X286899Y140429D02*
X286893Y140412D01*
G01X286904Y140365D02*
X286899Y140429D01*
G01X286892Y141390D02*
X286878Y141024D01*
G01X286899Y141412D02*
X286892Y141390D01*
G01X286906Y141327D02*
X286899Y141412D01*
G01X286971Y139853D02*
X286957Y140340D01*
G01X286976Y139464D02*
X286971Y139853D01*
G01X286982Y138993D02*
X286976Y139464D01*
G01X286986Y138453D02*
X286982Y138993D01*
G01X286989Y137857D02*
X286986Y138453D01*
G01X286991Y137224D02*
X286989Y137857D01*
G01X286991Y136570D02*
Y137224D01*
G01X286996Y134700D02*
X287004Y134627D01*
G01X286993Y134830D02*
X286996Y134700D01*
G01X286989Y135018D02*
X286993Y134830D01*
G01X286986Y135257D02*
X286989Y135018D01*
G01X286984Y135540D02*
X286986Y135257D01*
G01X286982Y135857D02*
X286984Y135540D01*
G01X286981Y136198D02*
X286982Y135857D01*
G01X286981Y136551D02*
Y136198D01*
G01X286965Y139013D02*
X286955Y139379D01*
G01X286969Y138722D02*
X286965Y139013D01*
G01X286973Y138368D02*
X286969Y138722D01*
G01X286976Y137963D02*
X286973Y138368D01*
G01X286978Y137516D02*
X286976Y137963D01*
G01X286980Y137041D02*
X286978Y137516D01*
G01X286981Y136551D02*
X286980Y137041D01*
G01X288611Y140412D02*
X288600Y140365D01*
G01X288617Y140314D02*
X288611Y140412D01*
G01X288622Y140138D02*
X288617Y140314D01*
G01X288526Y137516D02*
X288524Y136551D01*
G01X288528Y137963D02*
X288526Y137516D01*
G01X288531Y138368D02*
X288528Y137963D01*
G01X288535Y138722D02*
X288531Y138368D01*
G01X288540Y139013D02*
X288535Y138722D01*
G01X288545Y139234D02*
X288540Y139013D01*
G01X288550Y139379D02*
X288545Y139234D01*
G01X288522Y135857D02*
X288524Y136551D01*
G01X288521Y135540D02*
X288522Y135857D01*
G01X288518Y135257D02*
X288521Y135540D01*
G01X288515Y135018D02*
X288518Y135257D01*
G01X288512Y134830D02*
X288515Y135018D01*
G01X288508Y134700D02*
X288512Y134830D01*
G01X288504Y134632D02*
X288508Y134700D01*
G01X288500Y134627D02*
X288504Y134632D01*
G01X288516Y137857D02*
X288513Y136570D01*
G01X288519Y138453D02*
X288516Y137857D01*
G01X288523Y138993D02*
X288519Y138453D01*
G01X288528Y139464D02*
X288523Y138993D01*
G01X288534Y139853D02*
X288528Y139464D01*
G01X288540Y140148D02*
X288534Y139853D01*
G01X288547Y140340D02*
X288540Y140148D01*
G01X288612Y141390D02*
X288598Y141327D01*
G01X288620Y141259D02*
X288612Y141390D01*
G01X288626Y141024D02*
X288620Y141259D01*
G01X282961Y145965D02*
X282972Y146012D01*
G01X282956Y146063D02*
X282961Y145965D01*
G01X282950Y146239D02*
X282956Y146063D01*
G01X283046Y148861D02*
X283048Y149826D01*
G01X283044Y148414D02*
X283046Y148861D01*
G01X283041Y148009D02*
X283044Y148414D01*
G01X283037Y147656D02*
X283041Y148009D01*
G01X283032Y147364D02*
X283037Y147656D01*
G01X283028Y147143D02*
X283032Y147364D01*
G01X283022Y146999D02*
X283028Y147143D01*
G01X283056Y148520D02*
X283059Y149807D01*
G01X283053Y147925D02*
X283056Y148520D01*
G01X283049Y147384D02*
X283053Y147925D01*
G01X283044Y146913D02*
X283049Y147384D01*
G01X283038Y146524D02*
X283044Y146913D01*
G01X283032Y146230D02*
X283038Y146524D01*
G01X283025Y146037D02*
X283032Y146230D01*
G01X282960Y144988D02*
X282974Y145050D01*
G01X282952Y145118D02*
X282960Y144988D01*
G01X282946Y145353D02*
X282952Y145118D01*
G01X284679Y145965D02*
X284689Y146239D01*
G01X284673Y145948D02*
X284679Y145965D01*
G01X284668Y146012D02*
X284673Y145948D01*
G01X284680Y144988D02*
X284694Y145353D01*
G01X284673Y144965D02*
X284680Y144988D01*
G01X284666Y145050D02*
X284673Y144965D01*
G01X284602Y146524D02*
X284615Y146037D01*
G01X284596Y146913D02*
X284602Y146524D01*
G01X284591Y147384D02*
X284596Y146913D01*
G01X284586Y147925D02*
X284591Y147384D01*
G01X284583Y148520D02*
X284586Y147925D01*
G01X284581Y149153D02*
X284583Y148520D01*
G01X284581Y149807D02*
Y149153D01*
G01X284607Y147364D02*
X284617Y146999D01*
G01X284603Y147656D02*
X284607Y147364D01*
G01X284599Y148009D02*
X284603Y147656D01*
G01X284596Y148414D02*
X284599Y148009D01*
G01X284594Y148861D02*
X284596Y148414D01*
G01X284592Y149336D02*
X284594Y148861D01*
G01X284592Y149826D02*
Y149336D01*
G01X284679Y140412D02*
X284668Y140365D01*
G01X284684Y140314D02*
X284679Y140412D01*
G01X284689Y140138D02*
X284684Y140314D01*
G01X284594Y137516D02*
X284592Y136551D01*
G01X284596Y137963D02*
X284594Y137516D01*
G01X284599Y138368D02*
X284596Y137963D01*
G01X284603Y138722D02*
X284599Y138368D01*
G01X284607Y139013D02*
X284603Y138722D01*
G01X284612Y139234D02*
X284607Y139013D01*
G01X284617Y139379D02*
X284612Y139234D01*
G01X284583Y137857D02*
X284581Y136570D01*
G01X284586Y138453D02*
X284583Y137857D01*
G01X284591Y138993D02*
X284586Y138453D01*
G01X284596Y139464D02*
X284591Y138993D01*
G01X284602Y139853D02*
X284596Y139464D01*
G01X284608Y140148D02*
X284602Y139853D01*
G01X284615Y140340D02*
X284608Y140148D01*
G01X284680Y141390D02*
X284666Y141327D01*
G01X284687Y141259D02*
X284680Y141390D01*
G01X284694Y141024D02*
X284687Y141259D01*
G01X282961Y140412D02*
X282950Y140138D01*
G01X282966Y140429D02*
X282961Y140412D01*
G01X282972Y140365D02*
X282966Y140429D01*
G01X282960Y141390D02*
X282946Y141024D01*
G01X282967Y141412D02*
X282960Y141390D01*
G01X282974Y141327D02*
X282967Y141412D01*
G01X283038Y139853D02*
X283025Y140340D01*
G01X283044Y139464D02*
X283038Y139853D01*
G01X283049Y138993D02*
X283044Y139464D01*
G01X283053Y138453D02*
X283049Y138993D01*
G01X283056Y137857D02*
X283053Y138453D01*
G01X283058Y137224D02*
X283056Y137857D01*
G01X283059Y136570D02*
X283058Y137224D01*
G01X283032Y139013D02*
X283022Y139379D01*
G01X283037Y138722D02*
X283032Y139013D01*
G01X283041Y138368D02*
X283037Y138722D01*
G01X283044Y137963D02*
X283041Y138368D01*
G01X283046Y137516D02*
X283044Y137963D01*
G01X283048Y137041D02*
X283046Y137516D01*
G01X283048Y136551D02*
Y137041D01*
G01X280746Y145965D02*
X280757Y146239D01*
G01X280741Y145948D02*
X280746Y145965D01*
G01X280736Y146012D02*
X280741Y145948D01*
G01X280748Y144988D02*
X280762Y145353D01*
G01X280740Y144965D02*
X280748Y144988D01*
G01X280733Y145050D02*
X280740Y144965D01*
G01X280669Y146524D02*
X280683Y146037D01*
G01X280663Y146913D02*
X280669Y146524D01*
G01X280658Y147384D02*
X280663Y146913D01*
G01X280654Y147925D02*
X280658Y147384D01*
G01X280651Y148520D02*
X280654Y147925D01*
G01X280649Y149153D02*
X280651Y148520D01*
G01X280648Y149807D02*
X280649Y149153D01*
G01X280643Y151677D02*
X280636Y151750D01*
G01X280647Y151547D02*
X280643Y151677D01*
G01X280650Y151359D02*
X280647Y151547D01*
G01X280653Y151120D02*
X280650Y151359D01*
G01X280656Y150838D02*
X280653Y151120D01*
G01X280658Y150521D02*
X280656Y150838D01*
G01X280659Y150180D02*
X280658Y150521D01*
G01X280659Y149826D02*
Y150180D01*
G01X280675Y147364D02*
X280685Y146999D01*
G01X280671Y147656D02*
X280675Y147364D01*
G01X280667Y148009D02*
X280671Y147656D01*
G01X280664Y148414D02*
X280667Y148009D01*
G01X280661Y148861D02*
X280664Y148414D01*
G01X280660Y149336D02*
X280661Y148861D01*
G01X280659Y149826D02*
X280660Y149336D01*
G01X279029Y145965D02*
X279039Y146012D01*
G01X279023Y146063D02*
X279029Y145965D01*
G01X279018Y146239D02*
X279023Y146063D01*
G01X279114Y148861D02*
X279116Y149826D01*
G01X279111Y148414D02*
X279114Y148861D01*
G01X279108Y148009D02*
X279111Y148414D01*
G01X279105Y147656D02*
X279108Y148009D01*
G01X279100Y147364D02*
X279105Y147656D01*
G01X279095Y147143D02*
X279100Y147364D01*
G01X279090Y146999D02*
X279095Y147143D01*
G01X279117Y150521D02*
X279116Y149826D01*
G01X279119Y150838D02*
X279117Y150521D01*
G01X279122Y151120D02*
X279119Y150838D01*
G01X279125Y151359D02*
X279122Y151120D01*
G01X279128Y151547D02*
X279125Y151359D01*
G01X279132Y151677D02*
X279128Y151547D01*
G01X279136Y151746D02*
X279132Y151677D01*
G01X279139Y151750D02*
X279136Y151746D01*
G01X279124Y148520D02*
X279127Y149807D01*
G01X279121Y147925D02*
X279124Y148520D01*
G01X279117Y147384D02*
X279121Y147925D01*
G01X279112Y146913D02*
X279117Y147384D01*
G01X279106Y146524D02*
X279112Y146913D01*
G01X279099Y146230D02*
X279106Y146524D01*
G01X279092Y146037D02*
X279099Y146230D01*
G01X279027Y144988D02*
X279042Y145050D01*
G01X279020Y145118D02*
X279027Y144988D01*
G01X279013Y145353D02*
X279020Y145118D01*
G01X279019Y140412D02*
X279009Y140138D01*
G01X279025Y140429D02*
X279019Y140412D01*
G01X279030Y140365D02*
X279025Y140429D01*
G01X279018Y141390D02*
X279004Y141024D01*
G01X279025Y141412D02*
X279018Y141390D01*
G01X279032Y141327D02*
X279025Y141412D01*
G01X279096Y139853D02*
X279083Y140340D01*
G01X279102Y139464D02*
X279096Y139853D01*
G01X279107Y138993D02*
X279102Y139464D01*
G01X279112Y138453D02*
X279107Y138993D01*
G01X279115Y137857D02*
X279112Y138453D01*
G01X279117Y137224D02*
X279115Y137857D01*
G01X279117Y136570D02*
Y137224D01*
G01X279122Y134700D02*
X279130Y134627D01*
G01X279119Y134830D02*
X279122Y134700D01*
G01X279115Y135018D02*
X279119Y134830D01*
G01X279112Y135257D02*
X279115Y135018D01*
G01X279110Y135540D02*
X279112Y135257D01*
G01X279108Y135857D02*
X279110Y135540D01*
G01X279107Y136198D02*
X279108Y135857D01*
G01X279107Y136551D02*
Y136198D01*
G01X279091Y139013D02*
X279081Y139379D01*
G01X279095Y138722D02*
X279091Y139013D01*
G01X279099Y138368D02*
X279095Y138722D01*
G01X279102Y137963D02*
X279099Y138368D01*
G01X279104Y137516D02*
X279102Y137963D01*
G01X279106Y137041D02*
X279104Y137516D01*
G01X279107Y136551D02*
X279106Y137041D01*
G01X280737Y140412D02*
X280726Y140365D01*
G01X280742Y140314D02*
X280737Y140412D01*
G01X280748Y140138D02*
X280742Y140314D01*
G01X280652Y137516D02*
X280650Y136551D01*
G01X280654Y137963D02*
X280652Y137516D01*
G01X280657Y138368D02*
X280654Y137963D01*
G01X280661Y138722D02*
X280657Y138368D01*
G01X280666Y139013D02*
X280661Y138722D01*
G01X280671Y139234D02*
X280666Y139013D01*
G01X280676Y139379D02*
X280671Y139234D01*
G01X280648Y135857D02*
X280650Y136551D01*
G01X280646Y135540D02*
X280648Y135857D01*
G01X280644Y135257D02*
X280646Y135540D01*
G01X280641Y135018D02*
X280644Y135257D01*
G01X280638Y134830D02*
X280641Y135018D01*
G01X280634Y134700D02*
X280638Y134830D01*
G01X280630Y134632D02*
X280634Y134700D01*
G01X280626Y134627D02*
X280630Y134632D01*
G01X280642Y137857D02*
X280639Y136570D01*
G01X280645Y138453D02*
X280642Y137857D01*
G01X280649Y138993D02*
X280645Y138453D01*
G01X280654Y139464D02*
X280649Y138993D01*
G01X280660Y139853D02*
X280654Y139464D01*
G01X280666Y140148D02*
X280660Y139853D01*
G01X280673Y140340D02*
X280666Y140148D01*
G01X280738Y141390D02*
X280724Y141327D01*
G01X280746Y141259D02*
X280738Y141390D01*
G01X280752Y141024D02*
X280746Y141259D01*
G01X275087Y145965D02*
X275098Y146012D01*
G01X275082Y146063D02*
X275087Y145965D01*
G01X275076Y146239D02*
X275082Y146063D01*
G01X275172Y148861D02*
X275174Y149826D01*
G01X275170Y148414D02*
X275172Y148861D01*
G01X275167Y148009D02*
X275170Y148414D01*
G01X275163Y147656D02*
X275167Y148009D01*
G01X275158Y147364D02*
X275163Y147656D01*
G01X275154Y147143D02*
X275158Y147364D01*
G01X275148Y146999D02*
X275154Y147143D01*
G01X275182Y148520D02*
X275185Y149807D01*
G01X275179Y147925D02*
X275182Y148520D01*
G01X275175Y147384D02*
X275179Y147925D01*
G01X275170Y146913D02*
X275175Y147384D01*
G01X275164Y146524D02*
X275170Y146913D01*
G01X275158Y146230D02*
X275164Y146524D01*
G01X275151Y146037D02*
X275158Y146230D01*
G01X275086Y144988D02*
X275100Y145050D01*
G01X275078Y145118D02*
X275086Y144988D01*
G01X275072Y145353D02*
X275078Y145118D01*
G01X276805Y145965D02*
X276815Y146239D01*
G01X276799Y145948D02*
X276805Y145965D01*
G01X276794Y146012D02*
X276799Y145948D01*
G01X276806Y144988D02*
X276820Y145353D01*
G01X276799Y144965D02*
X276806Y144988D01*
G01X276792Y145050D02*
X276799Y144965D01*
G01X276728Y146524D02*
X276741Y146037D01*
G01X276722Y146913D02*
X276728Y146524D01*
G01X276717Y147384D02*
X276722Y146913D01*
G01X276712Y147925D02*
X276717Y147384D01*
G01X276709Y148520D02*
X276712Y147925D01*
G01X276707Y149153D02*
X276709Y148520D01*
G01X276707Y149807D02*
Y149153D01*
G01X276733Y147364D02*
X276743Y146999D01*
G01X276729Y147656D02*
X276733Y147364D01*
G01X276725Y148009D02*
X276729Y147656D01*
G01X276722Y148414D02*
X276725Y148009D01*
G01X276720Y148861D02*
X276722Y148414D01*
G01X276718Y149336D02*
X276720Y148861D01*
G01X276718Y149826D02*
Y149336D01*
G01X276805Y140412D02*
X276794Y140365D01*
G01X276810Y140314D02*
X276805Y140412D01*
G01X276815Y140138D02*
X276810Y140314D01*
G01X276720Y137516D02*
X276718Y136551D01*
G01X276722Y137963D02*
X276720Y137516D01*
G01X276725Y138368D02*
X276722Y137963D01*
G01X276729Y138722D02*
X276725Y138368D01*
G01X276733Y139013D02*
X276729Y138722D01*
G01X276738Y139234D02*
X276733Y139013D01*
G01X276743Y139379D02*
X276738Y139234D01*
G01X276709Y137857D02*
X276707Y136570D01*
G01X276712Y138453D02*
X276709Y137857D01*
G01X276717Y138993D02*
X276712Y138453D01*
G01X276722Y139464D02*
X276717Y138993D01*
G01X276728Y139853D02*
X276722Y139464D01*
G01X276734Y140148D02*
X276728Y139853D01*
G01X276741Y140340D02*
X276734Y140148D01*
G01X276806Y141390D02*
X276792Y141327D01*
G01X276813Y141259D02*
X276806Y141390D01*
G01X276820Y141024D02*
X276813Y141259D01*
G01X275087Y140412D02*
X275076Y140138D01*
G01X275092Y140429D02*
X275087Y140412D01*
G01X275098Y140365D02*
X275092Y140429D01*
G01X275086Y141390D02*
X275072Y141024D01*
G01X275093Y141412D02*
X275086Y141390D01*
G01X275100Y141327D02*
X275093Y141412D01*
G01X275164Y139853D02*
X275151Y140340D01*
G01X275170Y139464D02*
X275164Y139853D01*
G01X275175Y138993D02*
X275170Y139464D01*
G01X275179Y138453D02*
X275175Y138993D01*
G01X275182Y137857D02*
X275179Y138453D01*
G01X275184Y137224D02*
X275182Y137857D01*
G01X275185Y136570D02*
X275184Y137224D01*
G01X275158Y139013D02*
X275148Y139379D01*
G01X275163Y138722D02*
X275158Y139013D01*
G01X275167Y138368D02*
X275163Y138722D01*
G01X275170Y137963D02*
X275167Y138368D01*
G01X275172Y137516D02*
X275170Y137963D01*
G01X275174Y137041D02*
X275172Y137516D01*
G01X275174Y136551D02*
Y137041D01*
G01X272872Y145965D02*
X272883Y146239D01*
G01X272867Y145948D02*
X272872Y145965D01*
G01X272862Y146012D02*
X272867Y145948D01*
G01X272874Y144988D02*
X272888Y145353D01*
G01X272866Y144965D02*
X272874Y144988D01*
G01X272859Y145050D02*
X272866Y144965D01*
G01X272795Y146524D02*
X272809Y146037D01*
G01X272789Y146913D02*
X272795Y146524D01*
G01X272784Y147384D02*
X272789Y146913D01*
G01X272780Y147925D02*
X272784Y147384D01*
G01X272777Y148520D02*
X272780Y147925D01*
G01X272775Y149153D02*
X272777Y148520D01*
G01X272774Y149807D02*
X272775Y149153D01*
G01X272769Y151677D02*
X272762Y151750D01*
G01X272773Y151547D02*
X272769Y151677D01*
G01X272776Y151359D02*
X272773Y151547D01*
G01X272779Y151120D02*
X272776Y151359D01*
G01X272782Y150838D02*
X272779Y151120D01*
G01X272784Y150521D02*
X272782Y150838D01*
G01X272785Y150180D02*
X272784Y150521D01*
G01X272785Y149826D02*
Y150180D01*
G01X272801Y147364D02*
X272811Y146999D01*
G01X272797Y147656D02*
X272801Y147364D01*
G01X272793Y148009D02*
X272797Y147656D01*
G01X272790Y148414D02*
X272793Y148009D01*
G01X272787Y148861D02*
X272790Y148414D01*
G01X272786Y149336D02*
X272787Y148861D01*
G01X272785Y149826D02*
X272786Y149336D01*
G01X271155Y145965D02*
X271165Y146012D01*
G01X271149Y146063D02*
X271155Y145965D01*
G01X271144Y146239D02*
X271149Y146063D01*
G01X271240Y148861D02*
X271242Y149826D01*
G01X271237Y148414D02*
X271240Y148861D01*
G01X271234Y148009D02*
X271237Y148414D01*
G01X271231Y147656D02*
X271234Y148009D01*
G01X271226Y147364D02*
X271231Y147656D01*
G01X271221Y147143D02*
X271226Y147364D01*
G01X271216Y146999D02*
X271221Y147143D01*
G01X271243Y150521D02*
X271242Y149826D01*
G01X271245Y150838D02*
X271243Y150521D01*
G01X271248Y151120D02*
X271245Y150838D01*
G01X271251Y151359D02*
X271248Y151120D01*
G01X271254Y151547D02*
X271251Y151359D01*
G01X271258Y151677D02*
X271254Y151547D01*
G01X271262Y151746D02*
X271258Y151677D01*
G01X271265Y151750D02*
X271262Y151746D01*
G01X271250Y148520D02*
X271253Y149807D01*
G01X271247Y147925D02*
X271250Y148520D01*
G01X271243Y147384D02*
X271247Y147925D01*
G01X271238Y146913D02*
X271243Y147384D01*
G01X271232Y146524D02*
X271238Y146913D01*
G01X271225Y146230D02*
X271232Y146524D01*
G01X271218Y146037D02*
X271225Y146230D01*
G01X271153Y144988D02*
X271168Y145050D01*
G01X271146Y145118D02*
X271153Y144988D01*
G01X271139Y145353D02*
X271146Y145118D01*
G01X271145Y140412D02*
X271135Y140138D01*
G01X271151Y140429D02*
X271145Y140412D01*
G01X271156Y140365D02*
X271151Y140429D01*
G01X271144Y141390D02*
X271130Y141024D01*
G01X271151Y141412D02*
X271144Y141390D01*
G01X271158Y141327D02*
X271151Y141412D01*
G01X271222Y139853D02*
X271209Y140340D01*
G01X271228Y139464D02*
X271222Y139853D01*
G01X271233Y138993D02*
X271228Y139464D01*
G01X271238Y138453D02*
X271233Y138993D01*
G01X271241Y137857D02*
X271238Y138453D01*
G01X271243Y137224D02*
X271241Y137857D01*
G01X271243Y136570D02*
Y137224D01*
G01X271248Y134700D02*
X271256Y134627D01*
G01X271245Y134830D02*
X271248Y134700D01*
G01X271241Y135018D02*
X271245Y134830D01*
G01X271238Y135257D02*
X271241Y135018D01*
G01X271236Y135540D02*
X271238Y135257D01*
G01X271234Y135857D02*
X271236Y135540D01*
G01X271233Y136198D02*
X271234Y135857D01*
G01X271232Y136551D02*
X271233Y136198D01*
G01X271217Y139013D02*
X271207Y139379D01*
G01X271221Y138722D02*
X271217Y139013D01*
G01X271225Y138368D02*
X271221Y138722D01*
G01X271228Y137963D02*
X271225Y138368D01*
G01X271230Y137516D02*
X271228Y137963D01*
G01X271232Y137041D02*
X271230Y137516D01*
G01X271232Y136551D02*
Y137041D01*
G01X272863Y140412D02*
X272852Y140365D01*
G01X272868Y140314D02*
X272863Y140412D01*
G01X272874Y140138D02*
X272868Y140314D01*
G01X272778Y137516D02*
X272776Y136551D01*
G01X272780Y137963D02*
X272778Y137516D01*
G01X272783Y138368D02*
X272780Y137963D01*
G01X272787Y138722D02*
X272783Y138368D01*
G01X272792Y139013D02*
X272787Y138722D01*
G01X272797Y139234D02*
X272792Y139013D01*
G01X272802Y139379D02*
X272797Y139234D01*
G01X272774Y135857D02*
X272776Y136551D01*
G01X272772Y135540D02*
X272774Y135857D01*
G01X272770Y135257D02*
X272772Y135540D01*
G01X272767Y135018D02*
X272770Y135257D01*
G01X272764Y134830D02*
X272767Y135018D01*
G01X272760Y134700D02*
X272764Y134830D01*
G01X272756Y134632D02*
X272760Y134700D01*
G01X272752Y134627D02*
X272756Y134632D01*
G01X272768Y137857D02*
X272765Y136570D01*
G01X272771Y138453D02*
X272768Y137857D01*
G01X272775Y138993D02*
X272771Y138453D01*
G01X272780Y139464D02*
X272775Y138993D01*
G01X272786Y139853D02*
X272780Y139464D01*
G01X272792Y140148D02*
X272786Y139853D01*
G01X272799Y140340D02*
X272792Y140148D01*
G01X272864Y141390D02*
X272850Y141327D01*
G01X272872Y141259D02*
X272864Y141390D01*
G01X272878Y141024D02*
X272872Y141259D01*
G01X267213Y145965D02*
X267224Y146012D01*
G01X267208Y146063D02*
X267213Y145965D01*
G01X267202Y146239D02*
X267208Y146063D01*
G01X267298Y148861D02*
X267300Y149826D01*
G01X267296Y148414D02*
X267298Y148861D01*
G01X267293Y148009D02*
X267296Y148414D01*
G01X267289Y147656D02*
X267293Y148009D01*
G01X267284Y147364D02*
X267289Y147656D01*
G01X267279Y147143D02*
X267284Y147364D01*
G01X267274Y146999D02*
X267279Y147143D01*
G01X267308Y148520D02*
X267311Y149807D01*
G01X267305Y147925D02*
X267308Y148520D01*
G01X267301Y147384D02*
X267305Y147925D01*
G01X267296Y146913D02*
X267301Y147384D01*
G01X267290Y146524D02*
X267296Y146913D01*
G01X267284Y146230D02*
X267290Y146524D01*
G01X267277Y146037D02*
X267284Y146230D01*
G01X267212Y144988D02*
X267226Y145050D01*
G01X267204Y145118D02*
X267212Y144988D01*
G01X267198Y145353D02*
X267204Y145118D01*
G01X268931Y145965D02*
X268941Y146239D01*
G01X268925Y145948D02*
X268931Y145965D01*
G01X268920Y146012D02*
X268925Y145948D01*
G01X268932Y144988D02*
X268946Y145353D01*
G01X268925Y144965D02*
X268932Y144988D01*
G01X268918Y145050D02*
X268925Y144965D01*
G01X268854Y146524D02*
X268867Y146037D01*
G01X268848Y146913D02*
X268854Y146524D01*
G01X268843Y147384D02*
X268848Y146913D01*
G01X268838Y147925D02*
X268843Y147384D01*
G01X268835Y148520D02*
X268838Y147925D01*
G01X268833Y149153D02*
X268835Y148520D01*
G01X268833Y149807D02*
Y149153D01*
G01X268859Y147364D02*
X268869Y146999D01*
G01X268855Y147656D02*
X268859Y147364D01*
G01X268851Y148009D02*
X268855Y147656D01*
G01X268848Y148414D02*
X268851Y148009D01*
G01X268846Y148861D02*
X268848Y148414D01*
G01X268844Y149336D02*
X268846Y148861D01*
G01X268844Y149826D02*
Y149336D01*
G01X268931Y140412D02*
X268920Y140365D01*
G01X268936Y140314D02*
X268931Y140412D01*
G01X268941Y140138D02*
X268936Y140314D01*
G01X268846Y137516D02*
X268844Y136551D01*
G01X268848Y137963D02*
X268846Y137516D01*
G01X268851Y138368D02*
X268848Y137963D01*
G01X268855Y138722D02*
X268851Y138368D01*
G01X268859Y139013D02*
X268855Y138722D01*
G01X268864Y139234D02*
X268859Y139013D01*
G01X268869Y139379D02*
X268864Y139234D01*
G01X268835Y137857D02*
X268833Y136570D01*
G01X268838Y138453D02*
X268835Y137857D01*
G01X268843Y138993D02*
X268838Y138453D01*
G01X268848Y139464D02*
X268843Y138993D01*
G01X268854Y139853D02*
X268848Y139464D01*
G01X268860Y140148D02*
X268854Y139853D01*
G01X268867Y140340D02*
X268860Y140148D01*
G01X268932Y141390D02*
X268918Y141327D01*
G01X268939Y141259D02*
X268932Y141390D01*
G01X268946Y141024D02*
X268939Y141259D01*
G01X267213Y140412D02*
X267202Y140138D01*
G01X267218Y140429D02*
X267213Y140412D01*
G01X267224Y140365D02*
X267218Y140429D01*
G01X267212Y141390D02*
X267198Y141024D01*
G01X267219Y141412D02*
X267212Y141390D01*
G01X267226Y141327D02*
X267219Y141412D01*
G01X267290Y139853D02*
X267277Y140340D01*
G01X267296Y139464D02*
X267290Y139853D01*
G01X267301Y138993D02*
X267296Y139464D01*
G01X267305Y138453D02*
X267301Y138993D01*
G01X267308Y137857D02*
X267305Y138453D01*
G01X267310Y137224D02*
X267308Y137857D01*
G01X267311Y136570D02*
X267310Y137224D01*
G01X267284Y139013D02*
X267274Y139379D01*
G01X267289Y138722D02*
X267284Y139013D01*
G01X267293Y138368D02*
X267289Y138722D01*
G01X267296Y137963D02*
X267293Y138368D01*
G01X267298Y137516D02*
X267296Y137963D01*
G01X267300Y137041D02*
X267298Y137516D01*
G01X267300Y136551D02*
Y137041D01*
G01X268821Y150768D02*
X268820Y150762D01*
G01X268821Y150771D02*
Y150768D01*
G01X268822Y150772D02*
X268821Y150771D01*
G01X267323Y135610D02*
X267324Y135615D01*
G01X267323Y135606D02*
Y135610D01*
G01X267322Y135605D02*
X267323Y135606D01*
G01X276695Y150768D02*
X276694Y150762D01*
G01X276695Y150771D02*
Y150768D01*
G01X276696Y150772D02*
X276695Y150771D01*
G01X268820Y151754D02*
Y151750D01*
G01X268821Y151756D02*
X268820Y151754D01*
G01X268822Y151756D02*
X268821D01*
G01X276694Y151754D02*
Y151750D01*
G01X276695Y151756D02*
X276694Y151754D01*
G01X276696Y151756D02*
X276695D01*
G01X267323Y134624D02*
X267324Y134627D01*
G01X267323Y134622D02*
Y134624D01*
G01X267322Y134621D02*
X267323Y134622D01*
G01X284568Y151754D02*
Y151750D01*
G01X284569Y151756D02*
X284568Y151754D01*
G01X284570Y151756D02*
X284569D01*
G01X275197Y134624D02*
X275198Y134627D01*
G01X275197Y134622D02*
Y134624D01*
G01X275196Y134621D02*
X275197Y134622D01*
G01X267323Y150771D02*
X267322Y150772D01*
G01X267323Y150768D02*
Y150771D01*
G01X267324Y150762D02*
X267323Y150768D01*
G01X268821Y135606D02*
X268822Y135605D01*
G01X268821Y135610D02*
Y135606D01*
G01X268820Y135615D02*
X268821Y135610D01*
G01X267054Y152484D02*
X267048Y152538D01*
G01X267060Y152353D02*
X267054Y152484D01*
G01X267066Y152147D02*
X267060Y152353D01*
G01X269089Y133893D02*
X269095Y133840D01*
G01X269083Y134024D02*
X269089Y133893D01*
G01X269077Y134231D02*
X269083Y134024D01*
G01X270996Y152484D02*
X270990Y152538D01*
G01X271002Y152353D02*
X270996Y152484D01*
G01X271008Y152147D02*
X271002Y152353D01*
G01X273022Y133893D02*
X273028Y133840D01*
G01X273016Y134024D02*
X273022Y133893D01*
G01X273010Y134231D02*
X273016Y134024D01*
G01X274928Y152484D02*
X274922Y152538D01*
G01X274934Y152353D02*
X274928Y152484D01*
G01X274940Y152147D02*
X274934Y152353D01*
G01X276963Y133893D02*
X276969Y133840D01*
G01X276957Y134024D02*
X276963Y133893D01*
G01X276951Y134231D02*
X276957Y134024D01*
G01X278870Y152484D02*
X278864Y152538D01*
G01X278876Y152353D02*
X278870Y152484D01*
G01X278882Y152147D02*
X278876Y152353D01*
G01X267053Y151511D02*
X267048Y151553D01*
G01X267057Y151413D02*
X267053Y151511D01*
G01X267061Y151260D02*
X267057Y151413D01*
G01X269091Y134866D02*
X269095Y134824D01*
G01X269086Y134965D02*
X269091Y134866D01*
G01X269082Y135117D02*
X269086Y134965D01*
G01X270994Y151511D02*
X270990Y151553D01*
G01X270999Y151413D02*
X270994Y151511D01*
G01X271003Y151260D02*
X270999Y151413D01*
G01X273023Y134866D02*
X273028Y134824D01*
G01X273019Y134965D02*
X273023Y134866D01*
G01X273015Y135117D02*
X273019Y134965D01*
G01X274927Y151511D02*
X274922Y151553D01*
G01X274931Y151413D02*
X274927Y151511D01*
G01X274935Y151260D02*
X274931Y151413D01*
G01X276965Y134866D02*
X276969Y134824D01*
G01X276960Y134965D02*
X276965Y134866D01*
G01X276956Y135117D02*
X276960Y134965D01*
G01X278868Y151511D02*
X278864Y151553D01*
G01X278873Y151413D02*
X278868Y151511D01*
G01X278877Y151260D02*
X278873Y151413D01*
G01X271251Y135645D02*
X271256Y135615D01*
G01X271247Y135841D02*
X271251Y135645D01*
G01X271245Y136168D02*
X271247Y135841D01*
G01X271243Y136570D02*
X271245Y136168D01*
G01X272766Y150733D02*
X272762Y150762D01*
G01X272770Y150537D02*
X272766Y150733D01*
G01X272773Y150209D02*
X272770Y150537D01*
G01X272774Y149807D02*
X272773Y150209D01*
G01X279125Y135645D02*
X279130Y135615D01*
G01X279121Y135841D02*
X279125Y135645D01*
G01X279119Y136168D02*
X279121Y135841D01*
G01X279117Y136570D02*
X279119Y136168D01*
G01X280640Y150733D02*
X280636Y150762D01*
G01X280644Y150537D02*
X280640Y150733D01*
G01X280647Y150209D02*
X280644Y150537D01*
G01X280648Y149807D02*
X280647Y150209D01*
G01X267314Y134770D02*
X267322Y134621D01*
G01X267307Y135184D02*
X267314Y134770D01*
G01X267302Y135804D02*
X267307Y135184D01*
G01X267300Y136551D02*
X267302Y135804D01*
G01X267318Y135678D02*
X267322Y135605D01*
G01X267314Y135887D02*
X267318Y135678D01*
G01X267312Y136200D02*
X267314Y135887D01*
G01X267311Y136570D02*
X267312Y136200D01*
G01X268826Y150699D02*
X268822Y150772D01*
G01X268829Y150490D02*
X268826Y150699D01*
G01X268832Y150178D02*
X268829Y150490D01*
G01X268833Y149807D02*
X268832Y150178D01*
G01X268830Y151608D02*
X268822Y151756D01*
G01X268837Y151193D02*
X268830Y151608D01*
G01X268842Y150573D02*
X268837Y151193D01*
G01X268844Y149826D02*
X268842Y150573D01*
G01X275188Y134770D02*
X275196Y134621D01*
G01X275181Y135184D02*
X275188Y134770D01*
G01X275176Y135804D02*
X275181Y135184D01*
G01X275174Y136551D02*
X275176Y135804D01*
G01X275192Y135678D02*
X275196Y135605D01*
G01X275188Y135887D02*
X275192Y135678D01*
G01X275186Y136200D02*
X275188Y135887D01*
G01X275185Y136570D02*
X275186Y136200D01*
G01X276700Y150699D02*
X276696Y150772D01*
G01X276703Y150490D02*
X276700Y150699D01*
G01X276706Y150178D02*
X276703Y150490D01*
G01X276707Y149807D02*
X276706Y150178D01*
G01X276704Y151608D02*
X276696Y151756D01*
G01X276711Y151193D02*
X276704Y151608D01*
G01X276716Y150573D02*
X276711Y151193D01*
G01X276718Y149826D02*
X276716Y150573D01*
G01X267302D02*
X267300Y149826D01*
G01X267307Y151193D02*
X267302Y150573D01*
G01X267314Y151608D02*
X267307Y151193D01*
G01X267322Y151756D02*
X267314Y151608D01*
G01X268842Y135804D02*
X268844Y136551D01*
G01X268837Y135184D02*
X268842Y135804D01*
G01X268830Y134770D02*
X268837Y135184D01*
G01X268822Y134621D02*
X268830Y134770D01*
G01X275176Y150573D02*
X275174Y149826D01*
G01X275181Y151193D02*
X275176Y150573D01*
G01X275188Y151608D02*
X275181Y151193D01*
G01X275196Y151756D02*
X275188Y151608D01*
G01X276716Y135804D02*
X276718Y136551D01*
G01X276711Y135184D02*
X276716Y135804D01*
G01X276704Y134770D02*
X276711Y135184D01*
G01X276696Y134621D02*
X276704Y134770D01*
G01X283050Y150573D02*
X283048Y149826D01*
G01X283055Y151193D02*
X283050Y150573D01*
G01X283062Y151608D02*
X283055Y151193D01*
G01X283070Y151756D02*
X283062Y151608D01*
G01X267312Y150178D02*
X267311Y149807D01*
G01X267314Y150490D02*
X267312Y150178D01*
G01X267318Y150699D02*
X267314Y150490D01*
G01X267322Y150772D02*
X267318Y150699D01*
G01X268832Y136200D02*
X268833Y136570D01*
G01X268829Y135887D02*
X268832Y136200D01*
G01X268826Y135678D02*
X268829Y135887D01*
G01X268822Y135605D02*
X268826Y135678D01*
G01X275186Y150178D02*
X275185Y149807D01*
G01X275188Y150490D02*
X275186Y150178D01*
G01X275192Y150699D02*
X275188Y150490D01*
G01X275196Y150772D02*
X275192Y150699D01*
G01X276706Y136200D02*
X276707Y136570D01*
G01X276703Y135887D02*
X276706Y136200D01*
G01X276700Y135678D02*
X276703Y135887D01*
G01X276696Y135605D02*
X276700Y135678D01*
G01X283060Y150178D02*
X283059Y149807D01*
G01X283062Y150490D02*
X283060Y150178D01*
G01X283066Y150699D02*
X283062Y150490D01*
G01X283070Y150772D02*
X283066Y150699D01*
G01X267057Y134965D02*
X267061Y135117D01*
G01X267053Y134866D02*
X267057Y134965D01*
G01X267048Y134824D02*
X267053Y134866D01*
G01X269086Y151413D02*
X269082Y151260D01*
G01X269091Y151511D02*
X269086Y151413D01*
G01X269095Y151553D02*
X269091Y151511D01*
G01X270990Y134965D02*
X270994Y135117D01*
G01X270985Y134866D02*
X270990Y134965D01*
G01X270981Y134824D02*
X270985Y134866D01*
G01X273028Y151413D02*
X273024Y151260D01*
G01X273033Y151511D02*
X273028Y151413D01*
G01X273037Y151553D02*
X273033Y151511D01*
G01X274931Y134965D02*
X274935Y135117D01*
G01X274927Y134866D02*
X274931Y134965D01*
G01X274922Y134824D02*
X274927Y134866D01*
G01X276960Y151413D02*
X276956Y151260D01*
G01X276965Y151511D02*
X276960Y151413D01*
G01X276969Y151553D02*
X276965Y151511D01*
G01X278864Y134965D02*
X278868Y135117D01*
G01X278859Y134866D02*
X278864Y134965D01*
G01X278855Y134824D02*
X278859Y134866D01*
G01X280902Y151413D02*
X280898Y151260D01*
G01X280907Y151511D02*
X280902Y151413D01*
G01X280911Y151553D02*
X280907Y151511D01*
G01X282805Y134965D02*
X282809Y135117D01*
G01X282801Y134866D02*
X282805Y134965D01*
G01X282796Y134824D02*
X282801Y134866D01*
G01X284835Y151413D02*
X284830Y151260D01*
G01X284839Y151511D02*
X284835Y151413D01*
G01X284843Y151553D02*
X284839Y151511D01*
G01X286738Y134965D02*
X286742Y135117D01*
G01X286733Y134866D02*
X286738Y134965D01*
G01X286729Y134824D02*
X286733Y134866D01*
G01X269083Y152353D02*
X269077Y152147D01*
G01X269089Y152484D02*
X269083Y152353D01*
G01X269095Y152538D02*
X269089Y152484D01*
G01X267060Y134024D02*
X267066Y134231D01*
G01X267054Y133893D02*
X267060Y134024D01*
G01X267048Y133840D02*
X267054Y133893D01*
G01X273025Y152353D02*
X273019Y152147D01*
G01X273031Y152484D02*
X273025Y152353D01*
G01X273037Y152538D02*
X273031Y152484D01*
G01X270993Y134024D02*
X270999Y134231D01*
G01X270987Y133893D02*
X270993Y134024D01*
G01X270981Y133840D02*
X270987Y133893D01*
G01X276957Y152353D02*
X276951Y152147D01*
G01X276963Y152484D02*
X276957Y152353D01*
G01X276969Y152538D02*
X276963Y152484D01*
G01X274934Y134024D02*
X274940Y134231D01*
G01X274928Y133893D02*
X274934Y134024D01*
G01X274922Y133840D02*
X274928Y133893D01*
G01X280899Y152353D02*
X280893Y152147D01*
G01X280905Y152484D02*
X280899Y152353D01*
G01X280911Y152538D02*
X280905Y152484D01*
G01X278867Y134024D02*
X278873Y134231D01*
G01X278861Y133893D02*
X278867Y134024D01*
G01X278855Y133840D02*
X278861Y133893D01*
G01X284831Y152353D02*
X284825Y152147D01*
G01X284837Y152484D02*
X284831Y152353D01*
G01X284843Y152538D02*
X284837Y152484D01*
G01X282808Y134024D02*
X282814Y134231D01*
G01X282802Y133893D02*
X282808Y134024D01*
G01X282796Y133840D02*
X282802Y133893D01*
G01X288773Y152353D02*
X288767Y152147D01*
G01X288779Y152484D02*
X288773Y152353D01*
G01X288785Y152538D02*
X288779Y152484D01*
G01X286741Y134024D02*
X286747Y134231D01*
G01X286735Y133893D02*
X286741Y134024D01*
G01X286729Y133840D02*
X286735Y133893D01*
G01X271254Y150209D02*
X271253Y149807D01*
G01X271257Y150537D02*
X271254Y150209D01*
G01X271261Y150733D02*
X271257Y150537D01*
G01X271265Y150762D02*
X271261Y150733D01*
G01X272764Y136168D02*
X272765Y136570D01*
G01X272761Y135841D02*
X272764Y136168D01*
G01X272757Y135645D02*
X272761Y135841D01*
G01X272752Y135615D02*
X272757Y135645D01*
G01X279128Y150209D02*
X279127Y149807D01*
G01X279131Y150537D02*
X279128Y150209D01*
G01X279135Y150733D02*
X279131Y150537D01*
G01X279139Y150762D02*
X279135Y150733D01*
G01X280638Y136168D02*
X280639Y136570D01*
G01X280635Y135841D02*
X280638Y136168D01*
G01X280631Y135645D02*
X280635Y135841D01*
G01X280626Y135615D02*
X280631Y135645D01*
G01X287002Y150209D02*
X287001Y149807D01*
G01X287005Y150537D02*
X287002Y150209D01*
G01X287009Y150733D02*
X287005Y150537D01*
G01X287013Y150762D02*
X287009Y150733D01*
G01X288512Y136168D02*
X288513Y136570D01*
G01X288509Y135841D02*
X288512Y136168D01*
G01X288505Y135645D02*
X288509Y135841D01*
G01X288500Y135615D02*
X288505Y135645D01*
G01X275197Y135610D02*
X275198Y135615D01*
G01X275197Y135606D02*
Y135610D01*
G01X275196Y135605D02*
X275197Y135606D01*
G01X284569Y150768D02*
X284568Y150762D01*
G01X284569Y150771D02*
Y150768D01*
G01X284570Y150772D02*
X284569Y150771D01*
G01X283071Y135610D02*
X283072Y135615D01*
G01X283071Y135606D02*
Y135610D01*
G01X283070Y135605D02*
X283071Y135606D01*
G01X292443Y150768D02*
X292442Y150762D01*
G01X292443Y150771D02*
Y150768D01*
G01X292444Y150772D02*
X292443Y150771D01*
G01X290945Y135610D02*
X290946Y135615D01*
G01X290945Y135606D02*
Y135610D01*
G01X290944Y135605D02*
X290945Y135606D01*
G01X300317Y150768D02*
X300316Y150762D01*
G01X300317Y150771D02*
Y150768D01*
G01X300318Y150772D02*
X300317Y150771D01*
G01X298819Y135610D02*
X298820Y135615D01*
G01X298819Y135606D02*
Y135610D01*
G01X298818Y135605D02*
X298819Y135606D01*
G01X308191Y150768D02*
X308190Y150762D01*
G01X308191Y150771D02*
Y150768D01*
G01X308192Y150772D02*
X308191Y150771D01*
G01X292442Y151754D02*
Y151750D01*
G01X292443Y151756D02*
X292442Y151754D01*
G01X292444Y151756D02*
X292443D01*
G01X283071Y134624D02*
X283072Y134627D01*
G01X283071Y134622D02*
Y134624D01*
G01X283070Y134621D02*
X283071Y134622D01*
G01X300316Y151754D02*
Y151750D01*
G01X300317Y151756D02*
X300316Y151754D01*
G01X300318Y151756D02*
X300317D01*
G01X290945Y134624D02*
X290946Y134627D01*
G01X290945Y134622D02*
Y134624D01*
G01X290944Y134621D02*
X290945Y134622D01*
G01X308191Y151754D02*
X308190Y151750D01*
G01X308191Y151756D02*
Y151754D01*
G01X308192Y151756D02*
X308191D01*
G01X298819Y134624D02*
X298820Y134627D01*
G01X298819Y134622D02*
Y134624D01*
G01X298818Y134621D02*
X298819Y134622D01*
G01X316065Y151754D02*
X316064Y151750D01*
G01X316065Y151756D02*
Y151754D01*
G01X316066Y151756D02*
X316065D01*
G01X306693Y134624D02*
X306694Y134627D01*
G01X306693Y134622D02*
Y134624D01*
G01X306692Y134621D02*
X306693Y134622D01*
G01X323939Y151754D02*
X323938Y151750D01*
G01X323939Y151756D02*
Y151754D01*
G01X323940Y151756D02*
X323939D01*
G01X268821Y134622D02*
X268822Y134621D01*
G01X268820Y134624D02*
X268821Y134622D01*
G01X268820Y134627D02*
Y134624D01*
G01X267323Y151756D02*
X267322D01*
G01X267323Y151754D02*
Y151756D01*
G01X267324Y151750D02*
X267323Y151754D01*
G01X275197Y150771D02*
X275196Y150772D01*
G01X275197Y150768D02*
Y150771D01*
G01X275198Y150762D02*
X275197Y150768D01*
G01X276695Y135606D02*
X276696Y135605D01*
G01X276695Y135610D02*
Y135606D01*
G01X276694Y135615D02*
X276695Y135610D01*
G01X283071Y150771D02*
X283070Y150772D01*
G01X283071Y150768D02*
Y150771D01*
G01X283072Y150762D02*
X283071Y150768D01*
G01X284569Y135606D02*
X284570Y135605D01*
G01X284569Y135610D02*
Y135606D01*
G01X284568Y135615D02*
X284569Y135610D01*
G01X290945Y150771D02*
X290944Y150772D01*
G01X290945Y150768D02*
Y150771D01*
G01X290946Y150762D02*
X290945Y150768D01*
G01X292443Y135606D02*
X292444Y135605D01*
G01X292443Y135610D02*
Y135606D01*
G01X292442Y135615D02*
X292443Y135610D01*
G01X298819Y150771D02*
X298818Y150772D01*
G01X298819Y150768D02*
Y150771D01*
G01X298820Y150762D02*
X298819Y150768D01*
G01X300317Y135606D02*
X300318Y135605D01*
G01X300317Y135610D02*
Y135606D01*
G01X300316Y135615D02*
X300317Y135610D01*
G01X280896Y133893D02*
X280902Y133840D01*
G01X280890Y134024D02*
X280896Y133893D01*
G01X280884Y134231D02*
X280890Y134024D01*
G01X282802Y152484D02*
X282796Y152538D01*
G01X282808Y152353D02*
X282802Y152484D01*
G01X282814Y152147D02*
X282808Y152353D01*
G01X284837Y133893D02*
X284843Y133840D01*
G01X284831Y134024D02*
X284837Y133893D01*
G01X284825Y134231D02*
X284831Y134024D01*
G01X286744Y152484D02*
X286738Y152538D01*
G01X286750Y152353D02*
X286744Y152484D01*
G01X286756Y152147D02*
X286750Y152353D01*
G01X288770Y133893D02*
X288776Y133840D01*
G01X288764Y134024D02*
X288770Y133893D01*
G01X288758Y134231D02*
X288764Y134024D01*
G01X290676Y152484D02*
X290670Y152538D01*
G01X290682Y152353D02*
X290676Y152484D01*
G01X290688Y152147D02*
X290682Y152353D01*
G01X292711Y133893D02*
X292717Y133840D01*
G01X292705Y134024D02*
X292711Y133893D01*
G01X292700Y134231D02*
X292705Y134024D01*
G01X294618Y152484D02*
X294612Y152538D01*
G01X294624Y152353D02*
X294618Y152484D01*
G01X294630Y152147D02*
X294624Y152353D01*
G01X296644Y133893D02*
X296650Y133840D01*
G01X296638Y134024D02*
X296644Y133893D01*
G01X296632Y134231D02*
X296638Y134024D01*
G01X298550Y152484D02*
X298544Y152538D01*
G01X298556Y152353D02*
X298550Y152484D01*
G01X298562Y152147D02*
X298556Y152353D01*
G01X300585Y133893D02*
X300592Y133840D01*
G01X300579Y134024D02*
X300585Y133893D01*
G01X300574Y134231D02*
X300579Y134024D01*
G01X302492Y152484D02*
X302486Y152538D01*
G01X302498Y152353D02*
X302492Y152484D01*
G01X302504Y152147D02*
X302498Y152353D01*
G01X304518Y133893D02*
X304524Y133840D01*
G01X304512Y134024D02*
X304518Y133893D01*
G01X304506Y134231D02*
X304512Y134024D01*
G01X280897Y134866D02*
X280902Y134824D01*
G01X280893Y134965D02*
X280897Y134866D01*
G01X280889Y135117D02*
X280893Y134965D01*
G01X282801Y151511D02*
X282796Y151553D01*
G01X282805Y151413D02*
X282801Y151511D01*
G01X282809Y151260D02*
X282805Y151413D01*
G01X284839Y134866D02*
X284843Y134824D01*
G01X284835Y134965D02*
X284839Y134866D01*
G01X284830Y135117D02*
X284835Y134965D01*
G01X286742Y151511D02*
X286738Y151553D01*
G01X286747Y151413D02*
X286742Y151511D01*
G01X286751Y151260D02*
X286747Y151413D01*
G01X288771Y134866D02*
X288776Y134824D01*
G01X288767Y134965D02*
X288771Y134866D01*
G01X288763Y135117D02*
X288767Y134965D01*
G01X290675Y151511D02*
X290670Y151553D01*
G01X290679Y151413D02*
X290675Y151511D01*
G01X290683Y151260D02*
X290679Y151413D01*
G01X292713Y134866D02*
X292717Y134824D01*
G01X292709Y134965D02*
X292713Y134866D01*
G01X292704Y135117D02*
X292709Y134965D01*
G01X294616Y151511D02*
X294612Y151553D01*
G01X294621Y151413D02*
X294616Y151511D01*
G01X294625Y151260D02*
X294621Y151413D01*
G01X296645Y134866D02*
X296650Y134824D01*
G01X296641Y134965D02*
X296645Y134866D01*
G01X296637Y135117D02*
X296641Y134965D01*
G01X298549Y151511D02*
X298544Y151553D01*
G01X298553Y151413D02*
X298549Y151511D01*
G01X298557Y151260D02*
X298553Y151413D01*
G01X300587Y134866D02*
X300592Y134824D01*
G01X300583Y134965D02*
X300587Y134866D01*
G01X300578Y135117D02*
X300583Y134965D01*
G01X302490Y151511D02*
X302486Y151553D01*
G01X302495Y151413D02*
X302490Y151511D01*
G01X302499Y151260D02*
X302495Y151413D01*
G01X304519Y134866D02*
X304524Y134824D01*
G01X304515Y134965D02*
X304519Y134866D01*
G01X304511Y135117D02*
X304515Y134965D01*
G01X286999Y135645D02*
X287004Y135615D01*
G01X286995Y135841D02*
X286999Y135645D01*
G01X286993Y136168D02*
X286995Y135841D01*
G01X286991Y136570D02*
X286993Y136168D01*
G01X288514Y150733D02*
X288510Y150762D01*
G01X288518Y150537D02*
X288514Y150733D01*
G01X288521Y150209D02*
X288518Y150537D01*
G01X288522Y149807D02*
X288521Y150209D01*
G01X294873Y135645D02*
X294878Y135615D01*
G01X294869Y135841D02*
X294873Y135645D01*
G01X294867Y136168D02*
X294869Y135841D01*
G01X294865Y136570D02*
X294867Y136168D01*
G01X296388Y150733D02*
X296384Y150762D01*
G01X296392Y150537D02*
X296388Y150733D01*
G01X296395Y150209D02*
X296392Y150537D01*
G01X296396Y149807D02*
X296395Y150209D01*
G01X302747Y135645D02*
X302752Y135615D01*
G01X302743Y135841D02*
X302747Y135645D01*
G01X302741Y136168D02*
X302743Y135841D01*
G01X302740Y136570D02*
X302741Y136168D01*
G01X304262Y150733D02*
X304258Y150762D01*
G01X304266Y150537D02*
X304262Y150733D01*
G01X304269Y150209D02*
X304266Y150537D01*
G01X304270Y149807D02*
X304269Y150209D01*
G01X283062Y134770D02*
X283070Y134621D01*
G01X283055Y135184D02*
X283062Y134770D01*
G01X283050Y135804D02*
X283055Y135184D01*
G01X283048Y136551D02*
X283050Y135804D01*
G01X283066Y135678D02*
X283070Y135605D01*
G01X283062Y135887D02*
X283066Y135678D01*
G01X283060Y136200D02*
X283062Y135887D01*
G01X283059Y136570D02*
X283060Y136200D01*
G01X284574Y150699D02*
X284570Y150772D01*
G01X284577Y150490D02*
X284574Y150699D01*
G01X284580Y150178D02*
X284577Y150490D01*
G01X284581Y149807D02*
X284580Y150178D01*
G01X284578Y151608D02*
X284570Y151756D01*
G01X284585Y151193D02*
X284578Y151608D01*
G01X284590Y150573D02*
X284585Y151193D01*
G01X284592Y149826D02*
X284590Y150573D01*
G01X290936Y134770D02*
X290944Y134621D01*
G01X290929Y135184D02*
X290936Y134770D01*
G01X290924Y135804D02*
X290929Y135184D01*
G01X290922Y136551D02*
X290924Y135804D01*
G01X290940Y135678D02*
X290944Y135605D01*
G01X290936Y135887D02*
X290940Y135678D01*
G01X290934Y136200D02*
X290936Y135887D01*
G01X290933Y136570D02*
X290934Y136200D01*
G01X292448Y150699D02*
X292444Y150772D01*
G01X292451Y150490D02*
X292448Y150699D01*
G01X292454Y150178D02*
X292451Y150490D01*
G01X292455Y149807D02*
X292454Y150178D01*
G01X292452Y151608D02*
X292444Y151756D01*
G01X292459Y151193D02*
X292452Y151608D01*
G01X292464Y150573D02*
X292459Y151193D01*
G01X292466Y149826D02*
X292464Y150573D01*
G01X298810Y134770D02*
X298818Y134621D01*
G01X298803Y135184D02*
X298810Y134770D01*
G01X298798Y135804D02*
X298803Y135184D01*
G01X298796Y136551D02*
X298798Y135804D01*
G01X298814Y135678D02*
X298818Y135605D01*
G01X298810Y135887D02*
X298814Y135678D01*
G01X298808Y136200D02*
X298810Y135887D01*
G01X298807Y136570D02*
X298808Y136200D01*
G01X300322Y150699D02*
X300318Y150772D01*
G01X300325Y150490D02*
X300322Y150699D01*
G01X300328Y150178D02*
X300325Y150490D01*
G01X300329Y149807D02*
X300328Y150178D01*
G01X300326Y151608D02*
X300318Y151756D01*
G01X300333Y151193D02*
X300326Y151608D01*
G01X300338Y150573D02*
X300333Y151193D01*
G01X300340Y149826D02*
X300338Y150573D01*
G01X284590Y135804D02*
X284592Y136551D01*
G01X284585Y135184D02*
X284590Y135804D01*
G01X284578Y134770D02*
X284585Y135184D01*
G01X284570Y134621D02*
X284578Y134770D01*
G01X290924Y150573D02*
X290922Y149826D01*
G01X290929Y151193D02*
X290924Y150573D01*
G01X290936Y151608D02*
X290929Y151193D01*
G01X290944Y151756D02*
X290936Y151608D01*
G01X292464Y135804D02*
X292466Y136551D01*
G01X292459Y135184D02*
X292464Y135804D01*
G01X292452Y134770D02*
X292459Y135184D01*
G01X292444Y134621D02*
X292452Y134770D01*
G01X298798Y150573D02*
X298796Y149826D01*
G01X298803Y151193D02*
X298798Y150573D01*
G01X298810Y151608D02*
X298803Y151193D01*
G01X298818Y151756D02*
X298810Y151608D01*
G01X300338Y135804D02*
X300340Y136551D01*
G01X300333Y135184D02*
X300338Y135804D01*
G01X300326Y134770D02*
X300333Y135184D01*
G01X300318Y134621D02*
X300326Y134770D01*
G01X306672Y150573D02*
X306670Y149826D01*
G01X306677Y151193D02*
X306672Y150573D01*
G01X306684Y151608D02*
X306677Y151193D01*
G01X306692Y151756D02*
X306684Y151608D01*
G01X308212Y135804D02*
X308214Y136551D01*
G01X308207Y135184D02*
X308212Y135804D01*
G01X308200Y134770D02*
X308207Y135184D01*
G01X308192Y134621D02*
X308200Y134770D01*
G01X284580Y136200D02*
X284581Y136570D01*
G01X284577Y135887D02*
X284580Y136200D01*
G01X284574Y135678D02*
X284577Y135887D01*
G01X284570Y135605D02*
X284574Y135678D01*
G01X290934Y150178D02*
X290933Y149807D01*
G01X290936Y150490D02*
X290934Y150178D01*
G01X290940Y150699D02*
X290936Y150490D01*
G01X290944Y150772D02*
X290940Y150699D01*
G01X292454Y136200D02*
X292455Y136570D01*
G01X292451Y135887D02*
X292454Y136200D01*
G01X292448Y135678D02*
X292451Y135887D01*
G01X292444Y135605D02*
X292448Y135678D01*
G01X298808Y150178D02*
X298807Y149807D01*
G01X298810Y150490D02*
X298808Y150178D01*
G01X298814Y150699D02*
X298810Y150490D01*
G01X298818Y150772D02*
X298814Y150699D01*
G01X300328Y136200D02*
X300329Y136570D01*
G01X300325Y135887D02*
X300328Y136200D01*
G01X300322Y135678D02*
X300325Y135887D01*
G01X300318Y135605D02*
X300322Y135678D01*
G01X306682Y150178D02*
X306681Y149807D01*
G01X306684Y150490D02*
X306682Y150178D01*
G01X306688Y150699D02*
X306684Y150490D01*
G01X306692Y150772D02*
X306688Y150699D01*
G01X308202Y136200D02*
X308203Y136570D01*
G01X308199Y135887D02*
X308202Y136200D01*
G01X308196Y135678D02*
X308199Y135887D01*
G01X308192Y135605D02*
X308196Y135678D01*
G01X288776Y151413D02*
X288772Y151260D01*
G01X288781Y151511D02*
X288776Y151413D01*
G01X288785Y151553D02*
X288781Y151511D01*
G01X290679Y134965D02*
X290683Y135117D01*
G01X290675Y134866D02*
X290679Y134965D01*
G01X290670Y134824D02*
X290675Y134866D01*
G01X292709Y151413D02*
X292704Y151260D01*
G01X292713Y151511D02*
X292709Y151413D01*
G01X292717Y151553D02*
X292713Y151511D01*
G01X294612Y134965D02*
X294616Y135117D01*
G01X294607Y134866D02*
X294612Y134965D01*
G01X294603Y134824D02*
X294607Y134866D01*
G01X296650Y151413D02*
X296646Y151260D01*
G01X296655Y151511D02*
X296650Y151413D01*
G01X296659Y151553D02*
X296655Y151511D01*
G01X298553Y134965D02*
X298557Y135117D01*
G01X298549Y134866D02*
X298553Y134965D01*
G01X298544Y134824D02*
X298549Y134866D01*
G01X300583Y151413D02*
X300578Y151260D01*
G01X300587Y151511D02*
X300583Y151413D01*
G01X300592Y151553D02*
X300587Y151511D01*
G01X302486Y134965D02*
X302490Y135117D01*
G01X302481Y134866D02*
X302486Y134965D01*
G01X302477Y134824D02*
X302481Y134866D01*
G01X304524Y151413D02*
X304520Y151260D01*
G01X304529Y151511D02*
X304524Y151413D01*
G01X304533Y151553D02*
X304529Y151511D01*
G01X306427Y134965D02*
X306431Y135117D01*
G01X306423Y134866D02*
X306427Y134965D01*
G01X306418Y134824D02*
X306423Y134866D01*
G01X308457Y151413D02*
X308452Y151260D01*
G01X308461Y151511D02*
X308457Y151413D01*
G01X308466Y151553D02*
X308461Y151511D01*
G01X310360Y134965D02*
X310364Y135117D01*
G01X310355Y134866D02*
X310360Y134965D01*
G01X310351Y134824D02*
X310355Y134866D01*
G01X312398Y151413D02*
X312394Y151260D01*
G01X312403Y151511D02*
X312398Y151413D01*
G01X312407Y151553D02*
X312403Y151511D01*
G01X292705Y152353D02*
X292700Y152147D01*
G01X292711Y152484D02*
X292705Y152353D01*
G01X292717Y152538D02*
X292711Y152484D01*
G01X290682Y134024D02*
X290688Y134231D01*
G01X290676Y133893D02*
X290682Y134024D01*
G01X290670Y133840D02*
X290676Y133893D01*
G01X296647Y152353D02*
X296641Y152147D01*
G01X296653Y152484D02*
X296647Y152353D01*
G01X296659Y152538D02*
X296653Y152484D01*
G01X294615Y134024D02*
X294621Y134231D01*
G01X294609Y133893D02*
X294615Y134024D01*
G01X294603Y133840D02*
X294609Y133893D01*
G01X300579Y152353D02*
X300574Y152147D01*
G01X300585Y152484D02*
X300579Y152353D01*
G01X300592Y152538D02*
X300585Y152484D01*
G01X298556Y134024D02*
X298562Y134231D01*
G01X298550Y133893D02*
X298556Y134024D01*
G01X298544Y133840D02*
X298550Y133893D01*
G01X304521Y152353D02*
X304515Y152147D01*
G01X304527Y152484D02*
X304521Y152353D01*
G01X304533Y152538D02*
X304527Y152484D01*
G01X302489Y134024D02*
X302495Y134231D01*
G01X302483Y133893D02*
X302489Y134024D01*
G01X302477Y133840D02*
X302483Y133893D01*
G01X308453Y152353D02*
X308448Y152147D01*
G01X308459Y152484D02*
X308453Y152353D01*
G01X308466Y152538D02*
X308459Y152484D01*
G01X306431Y134024D02*
X306436Y134231D01*
G01X306424Y133893D02*
X306431Y134024D01*
G01X306418Y133840D02*
X306424Y133893D01*
G01X312395Y152353D02*
X312389Y152147D01*
G01X312401Y152484D02*
X312395Y152353D01*
G01X312407Y152538D02*
X312401Y152484D01*
G01X310363Y134024D02*
X310369Y134231D01*
G01X310357Y133893D02*
X310363Y134024D01*
G01X310351Y133840D02*
X310357Y133893D01*
G01X294876Y150209D02*
X294875Y149807D01*
G01X294879Y150537D02*
X294876Y150209D01*
G01X294883Y150733D02*
X294879Y150537D01*
G01X294887Y150762D02*
X294883Y150733D01*
G01X296386Y136168D02*
X296387Y136570D01*
G01X296383Y135841D02*
X296386Y136168D01*
G01X296379Y135645D02*
X296383Y135841D01*
G01X296374Y135615D02*
X296379Y135645D01*
G01X302750Y150209D02*
X302749Y149807D01*
G01X302753Y150537D02*
X302750Y150209D01*
G01X302757Y150733D02*
X302753Y150537D01*
G01X302761Y150762D02*
X302757Y150733D01*
G01X304260Y136168D02*
X304261Y136570D01*
G01X304257Y135841D02*
X304260Y136168D01*
G01X304253Y135645D02*
X304257Y135841D01*
G01X304248Y135615D02*
X304253Y135645D01*
G01X310624Y150209D02*
X310623Y149807D01*
G01X310627Y150537D02*
X310624Y150209D01*
G01X310631Y150733D02*
X310627Y150537D01*
G01X310635Y150762D02*
X310631Y150733D01*
G01X312134Y136168D02*
X312135Y136570D01*
G01X312131Y135841D02*
X312134Y136168D01*
G01X312127Y135645D02*
X312131Y135841D01*
G01X312122Y135615D02*
X312127Y135645D01*
G01X306693Y135610D02*
X306694Y135615D01*
G01X306693Y135606D02*
Y135610D01*
G01X306692Y135605D02*
X306693Y135606D01*
G01X316065Y150768D02*
X316064Y150762D01*
G01X316065Y150771D02*
Y150768D01*
G01X316066Y150772D02*
X316065Y150771D01*
G01X314567Y135610D02*
X314568Y135615D01*
G01X314567Y135606D02*
Y135610D01*
G01X314566Y135605D02*
X314567Y135606D01*
G01Y134624D02*
X314568Y134627D01*
G01X314567Y134622D02*
Y134624D01*
G01X314566Y134621D02*
X314567Y134622D01*
G01X331813Y151754D02*
X331812Y151750D01*
G01X331813Y151756D02*
Y151754D01*
G01X331814Y151756D02*
X331813D01*
G01X322441Y134624D02*
X322442Y134627D01*
G01X322441Y134622D02*
Y134624D01*
G01X322440Y134621D02*
X322441Y134622D01*
G01X339687Y151754D02*
X339686Y151750D01*
G01X339687Y151756D02*
Y151754D01*
G01X339688Y151756D02*
X339687D01*
G01X330315Y134624D02*
X330316Y134627D01*
G01X330315Y134622D02*
Y134624D01*
G01X330314Y134621D02*
X330315Y134622D01*
G01X338189Y134624D02*
X338190Y134627D01*
G01X338189Y134622D02*
Y134624D01*
G01X338188Y134621D02*
X338189Y134622D01*
G01X276695D02*
X276696Y134621D01*
G01X276694Y134624D02*
X276695Y134622D01*
G01X276694Y134627D02*
Y134624D01*
G01X275197Y151756D02*
X275196D01*
G01X275197Y151754D02*
Y151756D01*
G01X275198Y151750D02*
X275197Y151754D01*
G01X284569Y134622D02*
X284570Y134621D01*
G01X284568Y134624D02*
X284569Y134622D01*
G01X284568Y134627D02*
Y134624D01*
G01X283071Y151756D02*
X283070D01*
G01X283071Y151754D02*
Y151756D01*
G01X283072Y151750D02*
X283071Y151754D01*
G01X292443Y134622D02*
X292444Y134621D01*
G01X292442Y134624D02*
X292443Y134622D01*
G01X292442Y134627D02*
Y134624D01*
G01X290945Y151756D02*
X290944D01*
G01X290945Y151754D02*
Y151756D01*
G01X290946Y151750D02*
X290945Y151754D01*
G01X306693Y150771D02*
X306692Y150772D01*
G01X306693Y150768D02*
Y150771D01*
G01X306694Y150762D02*
X306693Y150768D01*
G01X308191Y135606D02*
X308192Y135605D01*
G01X308191Y135610D02*
Y135606D01*
G01X308190Y135615D02*
X308191Y135610D01*
G01X314567Y150771D02*
X314566Y150772D01*
G01X314567Y150768D02*
Y150771D01*
G01X314568Y150762D02*
X314567Y150768D01*
G01X316065Y135606D02*
X316066Y135605D01*
G01X316065Y135610D02*
Y135606D01*
G01X316064Y135615D02*
X316065Y135610D01*
G01X322430Y136197D02*
X322429Y136570D01*
G01X322433Y135887D02*
X322430Y136197D01*
G01X322436Y135680D02*
X322433Y135887D01*
G01X322440Y135605D02*
X322436Y135680D01*
G01X323950Y150180D02*
X323951Y149807D01*
G01X323947Y150490D02*
X323950Y150180D01*
G01X323944Y150698D02*
X323947Y150490D01*
G01X323940Y150772D02*
X323944Y150698D01*
G01X306424Y152484D02*
X306418Y152538D01*
G01X306431Y152353D02*
X306424Y152484D01*
G01X306436Y152147D02*
X306431Y152353D01*
G01X308459Y133893D02*
X308466Y133840D01*
G01X308453Y134024D02*
X308459Y133893D01*
G01X308448Y134231D02*
X308453Y134024D01*
G01X310366Y152484D02*
X310360Y152538D01*
G01X310372Y152353D02*
X310366Y152484D01*
G01X310378Y152147D02*
X310372Y152353D01*
G01X312392Y133893D02*
X312398Y133840D01*
G01X312386Y134024D02*
X312392Y133893D01*
G01X312380Y134231D02*
X312386Y134024D01*
G01X314298Y152484D02*
X314292Y152538D01*
G01X314305Y152353D02*
X314298Y152484D01*
G01X314310Y152147D02*
X314305Y152353D01*
G01X316333Y133893D02*
X316340Y133840D01*
G01X316327Y134024D02*
X316333Y133893D01*
G01X316322Y134231D02*
X316327Y134024D01*
G01X318240Y152484D02*
X318234Y152538D01*
G01X318246Y152353D02*
X318240Y152484D01*
G01X318252Y152147D02*
X318246Y152353D01*
G01X320266Y133893D02*
X320272Y133840D01*
G01X320260Y134024D02*
X320266Y133893D01*
G01X320254Y134231D02*
X320260Y134024D01*
G01X322173Y152484D02*
X322166Y152538D01*
G01X322179Y152353D02*
X322173Y152484D01*
G01X322184Y152147D02*
X322179Y152353D01*
G01X324207Y133893D02*
X324214Y133840D01*
G01X324201Y134024D02*
X324207Y133893D01*
G01X324196Y134231D02*
X324201Y134024D01*
G01X326114Y152484D02*
X326108Y152538D01*
G01X326120Y152353D02*
X326114Y152484D01*
G01X326126Y152147D02*
X326120Y152353D01*
G01X328140Y133893D02*
X328146Y133840D01*
G01X328134Y134024D02*
X328140Y133893D01*
G01X328128Y134231D02*
X328134Y134024D01*
G01X306423Y151511D02*
X306418Y151553D01*
G01X306427Y151413D02*
X306423Y151511D01*
G01X306431Y151260D02*
X306427Y151413D01*
G01X308461Y134866D02*
X308466Y134824D01*
G01X308457Y134965D02*
X308461Y134866D01*
G01X308452Y135117D02*
X308457Y134965D01*
G01X310365Y151511D02*
X310360Y151553D01*
G01X310369Y151413D02*
X310365Y151511D01*
G01X310373Y151260D02*
X310369Y151413D01*
G01X312393Y134866D02*
X312398Y134824D01*
G01X312389Y134965D02*
X312393Y134866D01*
G01X312385Y135117D02*
X312389Y134965D01*
G01X314297Y151511D02*
X314292Y151553D01*
G01X314301Y151413D02*
X314297Y151511D01*
G01X314306Y151260D02*
X314301Y151413D01*
G01X316335Y134866D02*
X316340Y134824D01*
G01X316331Y134965D02*
X316335Y134866D01*
G01X316326Y135117D02*
X316331Y134965D01*
G01X318239Y151511D02*
X318234Y151553D01*
G01X318243Y151413D02*
X318239Y151511D01*
G01X318247Y151260D02*
X318243Y151413D01*
G01X320267Y134866D02*
X320272Y134824D01*
G01X320263Y134965D02*
X320267Y134866D01*
G01X320259Y135117D02*
X320263Y134965D01*
G01X322171Y151511D02*
X322166Y151553D01*
G01X322175Y151413D02*
X322171Y151511D01*
G01X322180Y151260D02*
X322175Y151413D01*
G01X324209Y134866D02*
X324214Y134824D01*
G01X324205Y134965D02*
X324209Y134866D01*
G01X324200Y135117D02*
X324205Y134965D01*
G01X326113Y151511D02*
X326108Y151553D01*
G01X326117Y151413D02*
X326113Y151511D01*
G01X326121Y151260D02*
X326117Y151413D01*
G01X328141Y134866D02*
X328146Y134824D01*
G01X328137Y134965D02*
X328141Y134866D01*
G01X328133Y135117D02*
X328137Y134965D01*
G01X310621Y135645D02*
X310626Y135615D01*
G01X310617Y135841D02*
X310621Y135645D01*
G01X310615Y136168D02*
X310617Y135841D01*
G01X310614Y136570D02*
X310615Y136168D01*
G01X312136Y150733D02*
X312132Y150762D01*
G01X312140Y150537D02*
X312136Y150733D01*
G01X312143Y150209D02*
X312140Y150537D01*
G01X312144Y149807D02*
X312143Y150209D01*
G01X318495Y135645D02*
X318500Y135615D01*
G01X318491Y135841D02*
X318495Y135645D01*
G01X318489Y136168D02*
X318491Y135841D01*
G01X318488Y136570D02*
X318489Y136168D01*
G01X320010Y150733D02*
X320006Y150762D01*
G01X320014Y150537D02*
X320010Y150733D01*
G01X320017Y150209D02*
X320014Y150537D01*
G01X320018Y149807D02*
X320017Y150209D01*
G01X326369Y135645D02*
X326374Y135615D01*
G01X326365Y135841D02*
X326369Y135645D01*
G01X326363Y136168D02*
X326365Y135841D01*
G01X326362Y136570D02*
X326363Y136168D01*
G01X327884Y150733D02*
X327880Y150762D01*
G01X327888Y150537D02*
X327884Y150733D01*
G01X327891Y150209D02*
X327888Y150537D01*
G01X327892Y149807D02*
X327891Y150209D01*
G01X306684Y134770D02*
X306692Y134621D01*
G01X306677Y135184D02*
X306684Y134770D01*
G01X306672Y135804D02*
X306677Y135184D01*
G01X306670Y136551D02*
X306672Y135804D01*
G01X306688Y135678D02*
X306692Y135605D01*
G01X306684Y135887D02*
X306688Y135678D01*
G01X306682Y136200D02*
X306684Y135887D01*
G01X306681Y136570D02*
X306682Y136200D01*
G01X308196Y150699D02*
X308192Y150772D01*
G01X308199Y150490D02*
X308196Y150699D01*
G01X308202Y150178D02*
X308199Y150490D01*
G01X308203Y149807D02*
X308202Y150178D01*
G01X308200Y151608D02*
X308192Y151756D01*
G01X308207Y151193D02*
X308200Y151608D01*
G01X308212Y150573D02*
X308207Y151193D01*
G01X308214Y149826D02*
X308212Y150573D01*
G01X314558Y134770D02*
X314566Y134621D01*
G01X314551Y135184D02*
X314558Y134770D01*
G01X314546Y135804D02*
X314551Y135184D01*
G01X314544Y136551D02*
X314546Y135804D01*
G01X314562Y135678D02*
X314566Y135605D01*
G01X314559Y135887D02*
X314562Y135678D01*
G01X314556Y136200D02*
X314559Y135887D01*
G01X314555Y136570D02*
X314556Y136200D01*
G01X316070Y150699D02*
X316066Y150772D01*
G01X316073Y150490D02*
X316070Y150699D01*
G01X316076Y150178D02*
X316073Y150490D01*
G01X316077Y149807D02*
X316076Y150178D01*
G01X316074Y151608D02*
X316066Y151756D01*
G01X316081Y151193D02*
X316074Y151608D01*
G01X316086Y150573D02*
X316081Y151193D01*
G01X316088Y149826D02*
X316086Y150573D01*
G01X322432Y134770D02*
X322440Y134621D01*
G01X322425Y135184D02*
X322432Y134770D01*
G01X322420Y135804D02*
X322425Y135184D01*
G01X322418Y136551D02*
X322420Y135804D01*
G01X323948Y151608D02*
X323940Y151756D01*
G01X323955Y151193D02*
X323948Y151608D01*
G01X323960Y150573D02*
X323955Y151193D01*
G01X323962Y149826D02*
X323960Y150573D01*
G01X330306Y134770D02*
X330314Y134621D01*
G01X330299Y135184D02*
X330306Y134770D01*
G01X330294Y135804D02*
X330299Y135184D01*
G01X330292Y136551D02*
X330294Y135804D01*
G01X322436Y150698D02*
X322440Y150772D01*
G01X322433Y150490D02*
X322436Y150698D01*
G01X322430Y150180D02*
X322433Y150490D01*
G01X322429Y149807D02*
X322430Y150180D01*
G01X323944Y135680D02*
X323940Y135605D01*
G01X323947Y135887D02*
X323944Y135680D01*
G01X323950Y136197D02*
X323947Y135887D01*
G01X323951Y136570D02*
X323950Y136197D01*
G01X330310Y150698D02*
X330314Y150772D01*
G01X330307Y150490D02*
X330310Y150698D01*
G01X330304Y150180D02*
X330307Y150490D01*
G01X330303Y149807D02*
X330304Y150180D01*
G01X314546Y150573D02*
X314544Y149826D01*
G01X314551Y151193D02*
X314546Y150573D01*
G01X314558Y151608D02*
X314551Y151193D01*
G01X314566Y151756D02*
X314558Y151608D01*
G01X316086Y135804D02*
X316088Y136551D01*
G01X316081Y135184D02*
X316086Y135804D01*
G01X316074Y134770D02*
X316081Y135184D01*
G01X316066Y134621D02*
X316074Y134770D01*
G01X322420Y150573D02*
X322418Y149826D01*
G01X322425Y151193D02*
X322420Y150573D01*
G01X322432Y151608D02*
X322425Y151193D01*
G01X322440Y151756D02*
X322432Y151608D01*
G01X323960Y135804D02*
X323962Y136551D01*
G01X323955Y135184D02*
X323960Y135804D01*
G01X323948Y134770D02*
X323955Y135184D01*
G01X323940Y134621D02*
X323948Y134770D01*
G01X330294Y150573D02*
X330292Y149826D01*
G01X330299Y151193D02*
X330294Y150573D01*
G01X330306Y151608D02*
X330299Y151193D01*
G01X330314Y151756D02*
X330306Y151608D01*
G01X331834Y135804D02*
X331836Y136551D01*
G01X331829Y135184D02*
X331834Y135804D01*
G01X331822Y134770D02*
X331829Y135184D01*
G01X331814Y134621D02*
X331822Y134770D01*
G01X314556Y150178D02*
X314555Y149807D01*
G01X314559Y150490D02*
X314556Y150178D01*
G01X314562Y150699D02*
X314559Y150490D01*
G01X314566Y150772D02*
X314562Y150699D01*
G01X316076Y136200D02*
X316077Y136570D01*
G01X316073Y135887D02*
X316076Y136200D01*
G01X316070Y135678D02*
X316073Y135887D01*
G01X316066Y135605D02*
X316070Y135678D01*
G01X322441Y135606D02*
X322440Y135605D01*
G01X322441Y135610D02*
Y135606D01*
G01X322442Y135617D02*
X322441Y135610D01*
G01X323939Y150771D02*
X323940Y150772D01*
G01X323939Y150768D02*
Y150771D01*
G01X323938Y150760D02*
X323939Y150768D01*
G01X330315Y135606D02*
X330314Y135605D01*
G01X330315Y135610D02*
Y135606D01*
G01X330316Y135617D02*
X330315Y135610D01*
G01X331813Y150771D02*
X331814Y150772D01*
G01X331813Y150768D02*
Y150771D01*
G01X331812Y150760D02*
X331813Y150768D01*
G01X314301Y134965D02*
X314306Y135117D01*
G01X314297Y134866D02*
X314301Y134965D01*
G01X314292Y134824D02*
X314297Y134866D01*
G01X316331Y151413D02*
X316326Y151260D01*
G01X316335Y151511D02*
X316331Y151413D01*
G01X316340Y151553D02*
X316335Y151511D01*
G01X318234Y134965D02*
X318238Y135117D01*
G01X318229Y134866D02*
X318234Y134965D01*
G01X318225Y134824D02*
X318229Y134866D01*
G01X320272Y151413D02*
X320268Y151260D01*
G01X320277Y151511D02*
X320272Y151413D01*
G01X320281Y151553D02*
X320277Y151511D01*
G01X322175Y134965D02*
X322180Y135117D01*
G01X322171Y134866D02*
X322175Y134965D01*
G01X322166Y134824D02*
X322171Y134866D01*
G01X324205Y151413D02*
X324200Y151260D01*
G01X324209Y151511D02*
X324205Y151413D01*
G01X324214Y151553D02*
X324209Y151511D01*
G01X326108Y134965D02*
X326112Y135117D01*
G01X326103Y134866D02*
X326108Y134965D01*
G01X326099Y134824D02*
X326103Y134866D01*
G01X328146Y151413D02*
X328142Y151260D01*
G01X328151Y151511D02*
X328146Y151413D01*
G01X328155Y151553D02*
X328151Y151511D01*
G01X330049Y134965D02*
X330054Y135117D01*
G01X330045Y134866D02*
X330049Y134965D01*
G01X330040Y134824D02*
X330045Y134866D01*
G01X332079Y151413D02*
X332074Y151260D01*
G01X332083Y151511D02*
X332079Y151413D01*
G01X332088Y151553D02*
X332083Y151511D01*
G01X333982Y134965D02*
X333986Y135117D01*
G01X333977Y134866D02*
X333982Y134965D01*
G01X333973Y134824D02*
X333977Y134866D01*
G01X336020Y151413D02*
X336016Y151260D01*
G01X336025Y151511D02*
X336020Y151413D01*
G01X336029Y151553D02*
X336025Y151511D01*
G01X316327Y152353D02*
X316322Y152147D01*
G01X316333Y152484D02*
X316327Y152353D01*
G01X316340Y152538D02*
X316333Y152484D01*
G01X314305Y134024D02*
X314310Y134231D01*
G01X314298Y133893D02*
X314305Y134024D01*
G01X314292Y133840D02*
X314298Y133893D01*
G01X320269Y152353D02*
X320263Y152147D01*
G01X320275Y152484D02*
X320269Y152353D01*
G01X320281Y152538D02*
X320275Y152484D01*
G01X318237Y134024D02*
X318243Y134231D01*
G01X318231Y133893D02*
X318237Y134024D01*
G01X318225Y133840D02*
X318231Y133893D01*
G01X324201Y152353D02*
X324196Y152147D01*
G01X324207Y152484D02*
X324201Y152353D01*
G01X324214Y152538D02*
X324207Y152484D01*
G01X322179Y134024D02*
X322184Y134231D01*
G01X322173Y133893D02*
X322179Y134024D01*
G01X322166Y133840D02*
X322173Y133893D01*
G01X328143Y152353D02*
X328137Y152147D01*
G01X328149Y152484D02*
X328143Y152353D01*
G01X328155Y152538D02*
X328149Y152484D01*
G01X326111Y134024D02*
X326117Y134231D01*
G01X326105Y133893D02*
X326111Y134024D01*
G01X326099Y133840D02*
X326105Y133893D01*
G01X332075Y152353D02*
X332070Y152147D01*
G01X332081Y152484D02*
X332075Y152353D01*
G01X332088Y152538D02*
X332081Y152484D01*
G01X330053Y134024D02*
X330058Y134231D01*
G01X330047Y133893D02*
X330053Y134024D01*
G01X330040Y133840D02*
X330047Y133893D01*
G01X336017Y152353D02*
X336011Y152147D01*
G01X336023Y152484D02*
X336017Y152353D01*
G01X336029Y152538D02*
X336023Y152484D01*
G01X333985Y134024D02*
X333991Y134231D01*
G01X333979Y133893D02*
X333985Y134024D01*
G01X333973Y133840D02*
X333979Y133893D01*
G01X318498Y150209D02*
X318497Y149807D01*
G01X318501Y150537D02*
X318498Y150209D01*
G01X318505Y150733D02*
X318501Y150537D01*
G01X318509Y150762D02*
X318505Y150733D01*
G01X320008Y136168D02*
X320009Y136570D01*
G01X320005Y135841D02*
X320008Y136168D01*
G01X320001Y135645D02*
X320005Y135841D01*
G01X319996Y135615D02*
X320001Y135645D01*
G01X326372Y150209D02*
X326371Y149807D01*
G01X326375Y150537D02*
X326372Y150209D01*
G01X326379Y150733D02*
X326375Y150537D01*
G01X326383Y150762D02*
X326379Y150733D01*
G01X327882Y136168D02*
X327883Y136570D01*
G01X327879Y135841D02*
X327882Y136168D01*
G01X327875Y135645D02*
X327879Y135841D01*
G01X327870Y135615D02*
X327875Y135645D01*
G01X334246Y150209D02*
X334245Y149807D01*
G01X334249Y150537D02*
X334246Y150209D01*
G01X334253Y150733D02*
X334249Y150537D01*
G01X334257Y150762D02*
X334253Y150733D01*
G01X335756Y136168D02*
X335757Y136570D01*
G01X335753Y135841D02*
X335756Y136168D01*
G01X335749Y135645D02*
X335753Y135841D01*
G01X335745Y135615D02*
X335749Y135645D01*
G01X339687Y150768D02*
X339686Y150762D01*
G01X339687Y150771D02*
Y150768D01*
G01X339688Y150772D02*
X339687Y150771D01*
G01X338189Y135610D02*
X338190Y135615D01*
G01X338189Y135606D02*
Y135610D01*
G01X338188Y135605D02*
X338189Y135606D01*
G01X346063Y135610D02*
X346064Y135615D01*
G01X346063Y135606D02*
Y135610D01*
G01X346062Y135605D02*
X346063Y135606D01*
G01Y134624D02*
X346064Y134627D01*
G01X346063Y134622D02*
Y134624D01*
G01X346062Y134621D02*
X346063Y134622D01*
G01X300317D02*
X300318Y134621D01*
G01X300316Y134624D02*
X300317Y134622D01*
G01X300316Y134627D02*
Y134624D01*
G01X298819Y151756D02*
X298818D01*
G01X298819Y151754D02*
Y151756D01*
G01X298820Y151750D02*
X298819Y151754D01*
G01X308191Y134622D02*
X308192Y134621D01*
G01X308191Y134624D02*
Y134622D01*
G01X308190Y134627D02*
X308191Y134624D01*
G01X306693Y151756D02*
X306692D01*
G01X306693Y151754D02*
Y151756D01*
G01X306694Y151750D02*
X306693Y151754D01*
G01X316065Y134622D02*
X316066Y134621D01*
G01X316065Y134624D02*
Y134622D01*
G01X316064Y134627D02*
X316065Y134624D01*
G01X314567Y151756D02*
X314566D01*
G01X314567Y151754D02*
Y151756D01*
G01X314568Y151750D02*
X314567Y151754D01*
G01X338189Y150771D02*
X338188Y150772D01*
G01X338189Y150768D02*
Y150771D01*
G01X338190Y150762D02*
X338189Y150768D01*
G01X339687Y135606D02*
X339688Y135605D01*
G01X339687Y135610D02*
Y135606D01*
G01X339686Y135615D02*
X339687Y135610D01*
G01X346063Y150771D02*
X346062Y150772D01*
G01X346063Y150768D02*
Y150771D01*
G01X346064Y150762D02*
X346063Y150768D01*
G01X330304Y136197D02*
X330303Y136570D01*
G01X330307Y135887D02*
X330304Y136197D01*
G01X330310Y135680D02*
X330307Y135887D01*
G01X330314Y135605D02*
X330310Y135680D01*
G01X331824Y150180D02*
X331825Y149807D01*
G01X331821Y150490D02*
X331824Y150180D01*
G01X331818Y150698D02*
X331821Y150490D01*
G01X331814Y150772D02*
X331818Y150698D01*
G01X330047Y152484D02*
X330040Y152538D01*
G01X330053Y152353D02*
X330047Y152484D01*
G01X330058Y152147D02*
X330053Y152353D01*
G01X332081Y133893D02*
X332088Y133840D01*
G01X332075Y134024D02*
X332081Y133893D01*
G01X332070Y134231D02*
X332075Y134024D01*
G01X333988Y152484D02*
X333982Y152538D01*
G01X333994Y152353D02*
X333988Y152484D01*
G01X334000Y152147D02*
X333994Y152353D01*
G01X336014Y133893D02*
X336020Y133840D01*
G01X336008Y134024D02*
X336014Y133893D01*
G01X336002Y134231D02*
X336008Y134024D01*
G01X337921Y152484D02*
X337914Y152538D01*
G01X337927Y152353D02*
X337921Y152484D01*
G01X337932Y152147D02*
X337927Y152353D01*
G01X339955Y133893D02*
X339962Y133840D01*
G01X339949Y134024D02*
X339955Y133893D01*
G01X339944Y134231D02*
X339949Y134024D01*
G01X341862Y152484D02*
X341856Y152538D01*
G01X341868Y152353D02*
X341862Y152484D01*
G01X341874Y152147D02*
X341868Y152353D01*
G01X343888Y133893D02*
X343894Y133840D01*
G01X343882Y134024D02*
X343888Y133893D01*
G01X343876Y134231D02*
X343882Y134024D01*
G01X345795Y152484D02*
X345788Y152538D01*
G01X345801Y152353D02*
X345795Y152484D01*
G01X345806Y152147D02*
X345801Y152353D01*
G01X330045Y151511D02*
X330040Y151553D01*
G01X330049Y151413D02*
X330045Y151511D01*
G01X330054Y151260D02*
X330049Y151413D01*
G01X332083Y134866D02*
X332088Y134824D01*
G01X332079Y134965D02*
X332083Y134866D01*
G01X332074Y135117D02*
X332079Y134965D01*
G01X333987Y151511D02*
X333982Y151553D01*
G01X333991Y151413D02*
X333987Y151511D01*
G01X333995Y151260D02*
X333991Y151413D01*
G01X336015Y134866D02*
X336020Y134824D01*
G01X336011Y134965D02*
X336015Y134866D01*
G01X336007Y135117D02*
X336011Y134965D01*
G01X337919Y151511D02*
X337914Y151553D01*
G01X337923Y151413D02*
X337919Y151511D01*
G01X337928Y151260D02*
X337923Y151413D01*
G01X339957Y134866D02*
X339962Y134824D01*
G01X339953Y134965D02*
X339957Y134866D01*
G01X339948Y135117D02*
X339953Y134965D01*
G01X341861Y151511D02*
X341856Y151553D01*
G01X341865Y151413D02*
X341861Y151511D01*
G01X341869Y151260D02*
X341865Y151413D01*
G01X343889Y134866D02*
X343894Y134824D01*
G01X343885Y134965D02*
X343889Y134866D01*
G01X343881Y135117D02*
X343885Y134965D01*
G01X345793Y151511D02*
X345788Y151553D01*
G01X345797Y151413D02*
X345793Y151511D01*
G01X345802Y151260D02*
X345797Y151413D01*
G01X334243Y135645D02*
X334248Y135615D01*
G01X334239Y135841D02*
X334243Y135645D01*
G01X334237Y136168D02*
X334239Y135841D01*
G01X334236Y136570D02*
X334237Y136168D01*
G01X335758Y150733D02*
X335754Y150762D01*
G01X335762Y150537D02*
X335758Y150733D01*
G01X335765Y150209D02*
X335762Y150537D01*
G01X335766Y149807D02*
X335765Y150209D01*
G01X342117Y135645D02*
X342122Y135615D01*
G01X342113Y135841D02*
X342117Y135645D01*
G01X342111Y136168D02*
X342113Y135841D01*
G01X342110Y136570D02*
X342111Y136168D01*
G01X343632Y150733D02*
X343628Y150762D01*
G01X343637Y150537D02*
X343632Y150733D01*
G01X343639Y150209D02*
X343637Y150537D01*
G01X343640Y149807D02*
X343639Y150209D01*
G01X331822Y151608D02*
X331814Y151756D01*
G01X331829Y151193D02*
X331822Y151608D01*
G01X331834Y150573D02*
X331829Y151193D01*
G01X331836Y149826D02*
X331834Y150573D01*
G01X338180Y134770D02*
X338188Y134621D01*
G01X338173Y135184D02*
X338180Y134770D01*
G01X338168Y135804D02*
X338173Y135184D01*
G01X338166Y136551D02*
X338168Y135804D01*
G01X338184Y135678D02*
X338188Y135605D01*
G01X338181Y135887D02*
X338184Y135678D01*
G01X338178Y136200D02*
X338181Y135887D01*
G01X338177Y136570D02*
X338178Y136200D01*
G01X339692Y150699D02*
X339688Y150772D01*
G01X339695Y150490D02*
X339692Y150699D01*
G01X339698Y150178D02*
X339695Y150490D01*
G01X339699Y149807D02*
X339698Y150178D01*
G01X339696Y151608D02*
X339688Y151756D01*
G01X339703Y151193D02*
X339696Y151608D01*
G01X339708Y150573D02*
X339703Y151193D01*
G01X339710Y149826D02*
X339708Y150573D01*
G01X346054Y134770D02*
X346062Y134621D01*
G01X346047Y135184D02*
X346054Y134770D01*
G01X346042Y135804D02*
X346047Y135184D01*
G01X346040Y136551D02*
X346042Y135804D01*
G01X346058Y135678D02*
X346062Y135605D01*
G01X346055Y135887D02*
X346058Y135678D01*
G01X346052Y136200D02*
X346055Y135887D01*
G01X346051Y136570D02*
X346052Y136200D01*
G01X331818Y135680D02*
X331814Y135605D01*
G01X331821Y135887D02*
X331818Y135680D01*
G01X331824Y136197D02*
X331821Y135887D01*
G01X331825Y136570D02*
X331824Y136197D01*
G01X338168Y150573D02*
X338166Y149826D01*
G01X338173Y151193D02*
X338168Y150573D01*
G01X338180Y151608D02*
X338173Y151193D01*
G01X338188Y151756D02*
X338180Y151608D01*
G01X339708Y135804D02*
X339710Y136551D01*
G01X339703Y135184D02*
X339708Y135804D01*
G01X339696Y134770D02*
X339703Y135184D01*
G01X339688Y134621D02*
X339696Y134770D01*
G01X346042Y150573D02*
X346040Y149826D01*
G01X346047Y151193D02*
X346042Y150573D01*
G01X346054Y151608D02*
X346047Y151193D01*
G01X346062Y151756D02*
X346054Y151608D01*
G01X338178Y150178D02*
X338177Y149807D01*
G01X338181Y150490D02*
X338178Y150178D01*
G01X338184Y150699D02*
X338181Y150490D01*
G01X338188Y150772D02*
X338184Y150699D01*
G01X339698Y136200D02*
X339699Y136570D01*
G01X339695Y135887D02*
X339698Y136200D01*
G01X339692Y135678D02*
X339695Y135887D01*
G01X339688Y135605D02*
X339692Y135678D01*
G01X346052Y150178D02*
X346051Y149807D01*
G01X346055Y150490D02*
X346052Y150178D01*
G01X346058Y150699D02*
X346055Y150490D01*
G01X346062Y150772D02*
X346058Y150699D01*
G01X337923Y134965D02*
X337928Y135117D01*
G01X337919Y134866D02*
X337923Y134965D01*
G01X337914Y134824D02*
X337919Y134866D01*
G01X339953Y151413D02*
X339948Y151260D01*
G01X339957Y151511D02*
X339953Y151413D01*
G01X339962Y151553D02*
X339957Y151511D01*
G01X341856Y134965D02*
X341860Y135117D01*
G01X341851Y134866D02*
X341856Y134965D01*
G01X341847Y134824D02*
X341851Y134866D01*
G01X343894Y151413D02*
X343890Y151260D01*
G01X343899Y151511D02*
X343894Y151413D01*
G01X343903Y151553D02*
X343899Y151511D01*
G01X345797Y134965D02*
X345802Y135117D01*
G01X345793Y134866D02*
X345797Y134965D01*
G01X345788Y134824D02*
X345793Y134866D01*
G01X339949Y152353D02*
X339944Y152147D01*
G01X339955Y152484D02*
X339949Y152353D01*
G01X339962Y152538D02*
X339955Y152484D01*
G01X337927Y134024D02*
X337932Y134231D01*
G01X337921Y133893D02*
X337927Y134024D01*
G01X337914Y133840D02*
X337921Y133893D01*
G01X343891Y152353D02*
X343885Y152147D01*
G01X343897Y152484D02*
X343891Y152353D01*
G01X343903Y152538D02*
X343897Y152484D01*
G01X341859Y134024D02*
X341865Y134231D01*
G01X341853Y133893D02*
X341859Y134024D01*
G01X341847Y133840D02*
X341853Y133893D01*
G01X345801Y134024D02*
X345806Y134231D01*
G01X345795Y133893D02*
X345801Y134024D01*
G01X345788Y133840D02*
X345795Y133893D01*
G01X342120Y150209D02*
X342119Y149807D01*
G01X342123Y150537D02*
X342120Y150209D01*
G01X342127Y150733D02*
X342123Y150537D01*
G01X342131Y150762D02*
X342127Y150733D01*
G01X343630Y136168D02*
X343631Y136570D01*
G01X343627Y135841D02*
X343630Y136168D01*
G01X343623Y135645D02*
X343627Y135841D01*
G01X343619Y135615D02*
X343623Y135645D01*
G01X323939Y135610D02*
X323938Y135617D01*
G01X323939Y135606D02*
Y135610D01*
G01X323940Y135605D02*
X323939Y135606D01*
G01X322441Y150768D02*
X322442Y150760D01*
G01X322441Y150771D02*
Y150768D01*
G01X322440Y150772D02*
X322441Y150771D01*
G01X331813Y135610D02*
X331812Y135617D01*
G01X331813Y135606D02*
Y135610D01*
G01X331814Y135605D02*
X331813Y135606D01*
G01X323939Y134622D02*
X323940Y134621D01*
G01X323939Y134624D02*
Y134622D01*
G01X323938Y134627D02*
X323939Y134624D01*
G01X322441Y151756D02*
X322440D01*
G01X322441Y151754D02*
Y151756D01*
G01X322442Y151750D02*
X322441Y151754D01*
G01X331813Y134622D02*
X331814Y134621D01*
G01X331813Y134624D02*
Y134622D01*
G01X331812Y134627D02*
X331813Y134624D01*
G01X330315Y151756D02*
X330314D01*
G01X330315Y151754D02*
Y151756D01*
G01X330316Y151750D02*
X330315Y151754D01*
G01X339687Y134622D02*
X339688Y134621D01*
G01X339687Y134624D02*
Y134622D01*
G01X339686Y134627D02*
X339687Y134624D01*
G01X338189Y151756D02*
X338188D01*
G01X338189Y151754D02*
Y151756D01*
G01X338190Y151750D02*
X338189Y151754D01*
G01X345758Y134823D02*
X345743Y134822D01*
G01X345773Y134823D02*
X345758D01*
G01X345788Y134824D02*
X345773Y134823D01*
G01X341817D02*
X341802Y134822D01*
G01X341832Y134823D02*
X341817D01*
G01X341847Y134824D02*
X341832Y134823D01*
G01X337884D02*
X337869Y134822D01*
G01X337899Y134823D02*
X337884D01*
G01X337914Y134824D02*
X337899Y134823D01*
G01X333943D02*
X333928Y134822D01*
G01X333958Y134823D02*
X333943D01*
G01X333973Y134824D02*
X333958Y134823D01*
G01X330010D02*
X329995Y134822D01*
G01X330025Y134823D02*
X330010D01*
G01X330040Y134824D02*
X330025Y134823D01*
G01X322136D02*
X322121Y134822D01*
G01X322151Y134823D02*
X322136D01*
G01X322166Y134824D02*
X322151Y134823D01*
G01X314262D02*
X314247Y134822D01*
G01X314277Y134823D02*
X314262D01*
G01X314292Y134824D02*
X314277Y134823D01*
G01X310321D02*
X310306Y134822D01*
G01X310336Y134823D02*
X310321D01*
G01X310351Y134824D02*
X310336Y134823D01*
G01X306388D02*
X306373Y134822D01*
G01X306403Y134823D02*
X306388D01*
G01X306418Y134824D02*
X306403Y134823D01*
G01X302447D02*
X302432Y134822D01*
G01X302462Y134823D02*
X302447D01*
G01X302477Y134824D02*
X302462Y134823D01*
G01X298514D02*
X298499Y134822D01*
G01X298529Y134823D02*
X298514D01*
G01X298544Y134824D02*
X298529Y134823D01*
G01X294573D02*
X294558Y134822D01*
G01X294588Y134823D02*
X294573D01*
G01X294603Y134824D02*
X294588Y134823D01*
G01X290640D02*
X290625Y134822D01*
G01X290655Y134823D02*
X290640D01*
G01X290670Y134824D02*
X290655Y134823D01*
G01X345758Y133838D02*
X345743D01*
G01X345773Y133839D02*
X345758Y133838D01*
G01X345788Y133840D02*
X345773Y133839D01*
G01X341817Y133838D02*
X341802D01*
G01X341832Y133839D02*
X341817Y133838D01*
G01X341847Y133840D02*
X341832Y133839D01*
G01X337884Y133838D02*
X337869D01*
G01X337899Y133839D02*
X337884Y133838D01*
G01X337914Y133840D02*
X337899Y133839D01*
G01X333943Y133838D02*
X333928D01*
G01X333958Y133839D02*
X333943Y133838D01*
G01X333973Y133840D02*
X333958Y133839D01*
G01X326069Y133838D02*
X326054D01*
G01X326084Y133839D02*
X326069Y133838D01*
G01X326099Y133840D02*
X326084Y133839D01*
G01X318195Y133838D02*
X318180D01*
G01X318210Y133839D02*
X318195Y133838D01*
G01X318225Y133840D02*
X318210Y133839D01*
G01X314262Y133838D02*
X314247D01*
G01X314277Y133839D02*
X314262Y133838D01*
G01X314292Y133840D02*
X314277Y133839D01*
G01X310321Y133838D02*
X310306D01*
G01X310336Y133839D02*
X310321Y133838D01*
G01X310351Y133840D02*
X310336Y133839D01*
G01X306388Y133838D02*
X306373D01*
G01X306403Y133839D02*
X306388Y133838D01*
G01X306418Y133840D02*
X306403Y133839D01*
G01X302447Y133838D02*
X302432D01*
G01X302462Y133839D02*
X302447Y133838D01*
G01X302477Y133840D02*
X302462Y133839D01*
G01X298514Y133838D02*
X298499D01*
G01X298529Y133839D02*
X298514Y133838D01*
G01X298544Y133840D02*
X298529Y133839D01*
G01X294573Y133838D02*
X294558D01*
G01X294588Y133839D02*
X294573Y133838D01*
G01X294603Y133840D02*
X294588Y133839D01*
G01X290640Y133838D02*
X290625D01*
G01X290655Y133839D02*
X290640Y133838D01*
G01X290670Y133840D02*
X290655Y133839D01*
G01X286699Y133838D02*
X286684D01*
G01X286714Y133839D02*
X286699Y133838D01*
G01X286729Y133840D02*
X286714Y133839D01*
G01X282766Y133838D02*
X282751D01*
G01X282781Y133839D02*
X282766Y133838D01*
G01X282796Y133840D02*
X282781Y133839D01*
G01X278825Y133838D02*
X278810D01*
G01X278840Y133839D02*
X278825Y133838D01*
G01X278855Y133840D02*
X278840Y133839D01*
G01X274892Y133838D02*
X274877D01*
G01X274907Y133839D02*
X274892Y133838D01*
G01X274922Y133840D02*
X274907Y133839D01*
G01X270951Y133838D02*
X270936D01*
G01X270966Y133839D02*
X270951Y133838D01*
G01X270981Y133840D02*
X270966Y133839D01*
G01X267018Y133838D02*
X267003D01*
G01X267033Y133839D02*
X267018Y133838D01*
G01X267048Y133840D02*
X267033Y133839D01*
G01X269110D02*
X269095Y133840D01*
G01X269125Y133838D02*
X269110Y133839D01*
G01X269140Y133838D02*
X269125D01*
G01X273043Y133839D02*
X273028Y133840D01*
G01X273058Y133838D02*
X273043Y133839D01*
G01X273073Y133838D02*
X273058D01*
G01X276984Y133839D02*
X276969Y133840D01*
G01X276999Y133838D02*
X276984Y133839D01*
G01X277014Y133838D02*
X276999D01*
G01X280917Y133839D02*
X280902Y133840D01*
G01X280932Y133838D02*
X280917Y133839D01*
G01X280947Y133838D02*
X280932D01*
G01X284858Y133839D02*
X284843Y133840D01*
G01X284873Y133838D02*
X284858Y133839D01*
G01X284889Y133838D02*
X284873D01*
G01X288791Y133839D02*
X288776Y133840D01*
G01X288806Y133838D02*
X288791Y133839D01*
G01X288821Y133838D02*
X288806D01*
G01X292733Y133839D02*
X292717Y133840D01*
G01X292748Y133838D02*
X292733Y133839D01*
G01X292763Y133838D02*
X292748D01*
G01X296665Y133839D02*
X296650Y133840D01*
G01X296680Y133838D02*
X296665Y133839D01*
G01X296695Y133838D02*
X296680D01*
G01X300607Y133839D02*
X300592Y133840D01*
G01X300622Y133838D02*
X300607Y133839D01*
G01X300637Y133838D02*
X300622D01*
G01X304539Y133839D02*
X304524Y133840D01*
G01X304554Y133838D02*
X304539Y133839D01*
G01X304569Y133838D02*
X304554D01*
G01X308481Y133839D02*
X308466Y133840D01*
G01X308496Y133838D02*
X308481Y133839D01*
G01X308511Y133838D02*
X308496D01*
G01X312413Y133839D02*
X312398Y133840D01*
G01X312428Y133838D02*
X312413Y133839D01*
G01X312443Y133838D02*
X312428D01*
G01X316355Y133839D02*
X316340Y133840D01*
G01X316370Y133838D02*
X316355Y133839D01*
G01X316385Y133838D02*
X316370D01*
G01X320287Y133839D02*
X320272Y133840D01*
G01X320302Y133838D02*
X320287Y133839D01*
G01X320317Y133838D02*
X320302D01*
G01X324229Y133839D02*
X324214Y133840D01*
G01X324244Y133838D02*
X324229Y133839D01*
G01X324259Y133838D02*
X324244D01*
G01X328161Y133839D02*
X328146Y133840D01*
G01X328176Y133838D02*
X328161Y133839D01*
G01X328191Y133838D02*
X328176D01*
G01X332103Y133839D02*
X332088Y133840D01*
G01X332118Y133838D02*
X332103Y133839D01*
G01X332133Y133838D02*
X332118D01*
G01X336035Y133839D02*
X336020Y133840D01*
G01X336050Y133838D02*
X336035Y133839D01*
G01X336065Y133838D02*
X336050D01*
G01X339977Y133839D02*
X339962Y133840D01*
G01X339992Y133838D02*
X339977Y133839D01*
G01X340007Y133838D02*
X339992D01*
G01X343909Y133839D02*
X343894Y133840D01*
G01X343924Y133838D02*
X343909Y133839D01*
G01X343939Y133838D02*
X343924D01*
G01X269110Y134823D02*
X269095Y134824D01*
G01X269125Y134823D02*
X269110D01*
G01X269140Y134822D02*
X269125Y134823D01*
G01X273043D02*
X273028Y134824D01*
G01X273058Y134823D02*
X273043D01*
G01X273073Y134822D02*
X273058Y134823D01*
G01X276984D02*
X276969Y134824D01*
G01X276999Y134823D02*
X276984D01*
G01X277014Y134822D02*
X276999Y134823D01*
G01X280917D02*
X280902Y134824D01*
G01X280932Y134823D02*
X280917D01*
G01X280947Y134822D02*
X280932Y134823D01*
G01X284858D02*
X284843Y134824D01*
G01X284873Y134823D02*
X284858D01*
G01X284889Y134822D02*
X284873Y134823D01*
G01X288791D02*
X288776Y134824D01*
G01X288806Y134823D02*
X288791D01*
G01X288821Y134822D02*
X288806Y134823D01*
G01X292733D02*
X292717Y134824D01*
G01X292748Y134823D02*
X292733D01*
G01X292763Y134822D02*
X292748Y134823D01*
G01X296665D02*
X296650Y134824D01*
G01X296680Y134823D02*
X296665D01*
G01X296695Y134822D02*
X296680Y134823D01*
G01X300607D02*
X300592Y134824D01*
G01X300622Y134823D02*
X300607D01*
G01X300637Y134822D02*
X300622Y134823D01*
G01X304539D02*
X304524Y134824D01*
G01X304554Y134823D02*
X304539D01*
G01X304569Y134822D02*
X304554Y134823D01*
G01X308481D02*
X308466Y134824D01*
G01X308496Y134823D02*
X308481D01*
G01X308511Y134822D02*
X308496Y134823D01*
G01X312413D02*
X312398Y134824D01*
G01X312428Y134823D02*
X312413D01*
G01X312443Y134822D02*
X312428Y134823D01*
G01X316355D02*
X316340Y134824D01*
G01X316370Y134823D02*
X316355D01*
G01X316385Y134822D02*
X316370Y134823D01*
G01X324229D02*
X324214Y134824D01*
G01X324244Y134823D02*
X324229D01*
G01X324259Y134822D02*
X324244Y134823D01*
G01X332103D02*
X332088Y134824D01*
G01X332118Y134823D02*
X332103D01*
G01X332133Y134822D02*
X332118Y134823D01*
G01X336035D02*
X336020Y134824D01*
G01X336050Y134823D02*
X336035D01*
G01X336065Y134822D02*
X336050Y134823D01*
G01X339977D02*
X339962Y134824D01*
G01X339992Y134823D02*
X339977D01*
G01X340007Y134822D02*
X339992Y134823D01*
G01X343909D02*
X343894Y134824D01*
G01X343924Y134823D02*
X343909D01*
G01X343939Y134822D02*
X343924Y134823D01*
G01X320302D02*
X320317Y134822D01*
G01X320287Y134823D02*
X320302D01*
G01X320272Y134824D02*
X320287Y134823D01*
G01X328176D02*
X328191Y134822D01*
G01X328161Y134823D02*
X328176D01*
G01X328146Y134824D02*
X328161Y134823D01*
G01X330315Y150768D02*
X330316Y150760D01*
G01X330315Y150771D02*
Y150768D01*
G01X330314Y150772D02*
X330315Y150771D01*
G01X346063Y151756D02*
X346062D01*
G01X346063Y151754D02*
Y151756D01*
G01X346064Y151750D02*
X346063Y151754D01*
G01X286699Y134823D02*
X286684Y134822D01*
G01X286714Y134823D02*
X286699D01*
G01X286729Y134824D02*
X286714Y134823D01*
G01X282766D02*
X282751Y134822D01*
G01X282781Y134823D02*
X282766D01*
G01X282796Y134824D02*
X282781Y134823D01*
G01X278825D02*
X278810Y134822D01*
G01X278840Y134823D02*
X278825D01*
G01X278855Y134824D02*
X278840Y134823D01*
G01X274892D02*
X274877Y134822D01*
G01X274907Y134823D02*
X274892D01*
G01X274922Y134824D02*
X274907Y134823D01*
G01X270951D02*
X270936Y134822D01*
G01X270966Y134823D02*
X270951D01*
G01X270981Y134824D02*
X270966Y134823D01*
G01X267018D02*
X267003Y134822D01*
G01X267033Y134823D02*
X267018D01*
G01X267048Y134824D02*
X267033Y134823D01*
G01X339992Y151555D02*
X340007D01*
G01X339977Y151554D02*
X339992Y151555D01*
G01X339962Y151553D02*
X339977Y151554D01*
G01X332118Y151555D02*
X332133D01*
G01X332103Y151554D02*
X332118Y151555D01*
G01X332088Y151553D02*
X332103Y151554D01*
G01X328185Y151555D02*
X328200D01*
G01X328170Y151554D02*
X328185Y151555D01*
G01X328155Y151553D02*
X328170Y151554D01*
G01X324244Y151555D02*
X324259D01*
G01X324229Y151554D02*
X324244Y151555D01*
G01X324214Y151553D02*
X324229Y151554D01*
G01X320311Y151555D02*
X320326D01*
G01X320296Y151554D02*
X320311Y151555D01*
G01X320281Y151553D02*
X320296Y151554D01*
G01X316370Y151555D02*
X316385D01*
G01X316355Y151554D02*
X316370Y151555D01*
G01X316340Y151553D02*
X316355Y151554D01*
G01X312437Y151555D02*
X312452D01*
G01X312422Y151554D02*
X312437Y151555D01*
G01X312407Y151553D02*
X312422Y151554D01*
G01X308496Y151555D02*
X308511D01*
G01X308481Y151554D02*
X308496Y151555D01*
G01X308466Y151553D02*
X308481Y151554D01*
G01X300622Y151555D02*
X300637D01*
G01X300607Y151554D02*
X300622Y151555D01*
G01X300592Y151553D02*
X300607Y151554D01*
G01X292748Y151555D02*
X292763D01*
G01X292733Y151554D02*
X292748Y151555D01*
G01X292717Y151553D02*
X292733Y151554D01*
G01X288815Y151555D02*
X288830D01*
G01X288800Y151554D02*
X288815Y151555D01*
G01X288785Y151553D02*
X288800Y151554D01*
G01X284873Y151555D02*
X284889D01*
G01X284858Y151554D02*
X284873Y151555D01*
G01X284843Y151553D02*
X284858Y151554D01*
G01X280941Y151555D02*
X280956D01*
G01X280926Y151554D02*
X280941Y151555D01*
G01X280911Y151553D02*
X280926Y151554D01*
G01X276999Y151555D02*
X277014D01*
G01X276984Y151554D02*
X276999Y151555D01*
G01X276969Y151553D02*
X276984Y151554D01*
G01X269125Y151555D02*
X269140D01*
G01X269110Y151554D02*
X269125Y151555D01*
G01X269095Y151553D02*
X269110Y151554D01*
G01X343933Y152539D02*
X343948D01*
G01X343918Y152538D02*
X343933Y152539D01*
G01X343903Y152538D02*
X343918D01*
G01X339992Y152539D02*
X340007D01*
G01X339977Y152538D02*
X339992Y152539D01*
G01X339962Y152538D02*
X339977D01*
G01X336059Y152539D02*
X336074D01*
G01X336044Y152538D02*
X336059Y152539D01*
G01X336029Y152538D02*
X336044D01*
G01X320311Y152539D02*
X320326D01*
G01X320296Y152538D02*
X320311Y152539D01*
G01X320281Y152538D02*
X320296D01*
G01X316370Y152539D02*
X316385D01*
G01X316355Y152538D02*
X316370Y152539D01*
G01X316340Y152538D02*
X316355D01*
G01X312437Y152539D02*
X312452D01*
G01X312422Y152538D02*
X312437Y152539D01*
G01X312407Y152538D02*
X312422D01*
G01X308496Y152539D02*
X308511D01*
G01X308481Y152538D02*
X308496Y152539D01*
G01X308466Y152538D02*
X308481D01*
G01X304563Y152539D02*
X304578D01*
G01X304548Y152538D02*
X304563Y152539D01*
G01X304533Y152538D02*
X304548D01*
G01X300622Y152539D02*
X300637D01*
G01X300607Y152538D02*
X300622Y152539D01*
G01X300592Y152538D02*
X300607D01*
G01X296689Y152539D02*
X296704D01*
G01X296674Y152538D02*
X296689Y152539D01*
G01X296659Y152538D02*
X296674D01*
G01X292748Y152539D02*
X292763D01*
G01X292733Y152538D02*
X292748Y152539D01*
G01X292717Y152538D02*
X292733D01*
G01X288815Y152539D02*
X288830D01*
G01X288800Y152538D02*
X288815Y152539D01*
G01X288785Y152538D02*
X288800D01*
G01X284873Y152539D02*
X284889D01*
G01X284858Y152538D02*
X284873Y152539D01*
G01X284843Y152538D02*
X284858D01*
G01X280941Y152539D02*
X280956D01*
G01X280926Y152538D02*
X280941Y152539D01*
G01X280911Y152538D02*
X280926D01*
G01X276999Y152539D02*
X277014D01*
G01X276984Y152538D02*
X276999Y152539D01*
G01X276969Y152538D02*
X276984D01*
G01X273067Y152539D02*
X273082D01*
G01X273052Y152538D02*
X273067Y152539D01*
G01X273037Y152538D02*
X273052D01*
G01X269125Y152539D02*
X269140D01*
G01X269110Y152538D02*
X269125Y152539D01*
G01X269095Y152538D02*
X269110D01*
G01X267033D02*
X267048D01*
G01X267018Y152539D02*
X267033Y152538D01*
G01X267003Y152539D02*
X267018D01*
G01X270975Y152538D02*
X270990D01*
G01X270960Y152539D02*
X270975Y152538D01*
G01X270945Y152539D02*
X270960D01*
G01X274907Y152538D02*
X274922D01*
G01X274892Y152539D02*
X274907Y152538D01*
G01X274877Y152539D02*
X274892D01*
G01X278849Y152538D02*
X278864D01*
G01X278834Y152539D02*
X278849Y152538D01*
G01X278819Y152539D02*
X278834D01*
G01X282781Y152538D02*
X282796D01*
G01X282766Y152539D02*
X282781Y152538D01*
G01X282751Y152539D02*
X282766D01*
G01X286723Y152538D02*
X286738D01*
G01X286708Y152539D02*
X286723Y152538D01*
G01X286693Y152539D02*
X286708D01*
G01X290655Y152538D02*
X290670D01*
G01X290640Y152539D02*
X290655Y152538D01*
G01X290625Y152539D02*
X290640D01*
G01X294597Y152538D02*
X294612D01*
G01X294582Y152539D02*
X294597Y152538D01*
G01X294567Y152539D02*
X294582D01*
G01X298529Y152538D02*
X298544D01*
G01X298514Y152539D02*
X298529Y152538D01*
G01X298499Y152539D02*
X298514D01*
G01X302471Y152538D02*
X302486D01*
G01X302456Y152539D02*
X302471Y152538D01*
G01X302441Y152539D02*
X302456D01*
G01X306403Y152538D02*
X306418D01*
G01X306388Y152539D02*
X306403Y152538D01*
G01X306373Y152539D02*
X306388D01*
G01X310345Y152538D02*
X310360D01*
G01X310330Y152539D02*
X310345Y152538D01*
G01X310315Y152539D02*
X310330D01*
G01X314277Y152538D02*
X314292D01*
G01X314262Y152539D02*
X314277Y152538D01*
G01X314247Y152539D02*
X314262D01*
G01X318219Y152538D02*
X318234D01*
G01X318204Y152539D02*
X318219Y152538D01*
G01X318189Y152539D02*
X318204D01*
G01X322151Y152538D02*
X322166D01*
G01X322136Y152539D02*
X322151Y152538D01*
G01X322121Y152539D02*
X322136D01*
G01X326093Y152538D02*
X326108D01*
G01X326078Y152539D02*
X326093Y152538D01*
G01X326063Y152539D02*
X326078D01*
G01X330025Y152538D02*
X330040D01*
G01X330010Y152539D02*
X330025Y152538D01*
G01X329995Y152539D02*
X330010D01*
G01X333967Y152538D02*
X333982D01*
G01X333952Y152539D02*
X333967Y152538D01*
G01X333937Y152539D02*
X333952D01*
G01X337899Y152538D02*
X337914D01*
G01X337884Y152539D02*
X337899Y152538D01*
G01X337869Y152539D02*
X337884D01*
G01X341841Y152538D02*
X341856D01*
G01X341826Y152539D02*
X341841Y152538D01*
G01X341811Y152539D02*
X341826D01*
G01X345773Y152538D02*
X345788D01*
G01X345758Y152539D02*
X345773Y152538D01*
G01X345743Y152539D02*
X345758D01*
G01X267033Y151554D02*
X267048Y151553D01*
G01X267018Y151555D02*
X267033Y151554D01*
G01X267003Y151555D02*
X267018D01*
G01X270975Y151554D02*
X270990Y151553D01*
G01X270960Y151555D02*
X270975Y151554D01*
G01X270945Y151555D02*
X270960D01*
G01X274907Y151554D02*
X274922Y151553D01*
G01X274892Y151555D02*
X274907Y151554D01*
G01X274877Y151555D02*
X274892D01*
G01X282781Y151554D02*
X282796Y151553D01*
G01X282766Y151555D02*
X282781Y151554D01*
G01X282751Y151555D02*
X282766D01*
G01X290655Y151554D02*
X290670Y151553D01*
G01X290640Y151555D02*
X290655Y151554D01*
G01X290625Y151555D02*
X290640D01*
G01X294597Y151554D02*
X294612Y151553D01*
G01X294582Y151555D02*
X294597Y151554D01*
G01X294567Y151555D02*
X294582D01*
G01X298529Y151554D02*
X298544Y151553D01*
G01X298514Y151555D02*
X298529Y151554D01*
G01X298499Y151555D02*
X298514D01*
G01X302471Y151554D02*
X302486Y151553D01*
G01X302456Y151555D02*
X302471Y151554D01*
G01X302441Y151555D02*
X302456D01*
G01X306403Y151554D02*
X306418Y151553D01*
G01X306388Y151555D02*
X306403Y151554D01*
G01X306373Y151555D02*
X306388D01*
G01X314277Y151554D02*
X314292Y151553D01*
G01X314262Y151555D02*
X314277Y151554D01*
G01X314247Y151555D02*
X314262D01*
G01X318219Y151554D02*
X318234Y151553D01*
G01X318204Y151555D02*
X318219Y151554D01*
G01X318189Y151555D02*
X318204D01*
G01X322151Y151554D02*
X322166Y151553D01*
G01X322136Y151555D02*
X322151Y151554D01*
G01X322121Y151555D02*
X322136D01*
G01X326093Y151554D02*
X326108Y151553D01*
G01X326078Y151555D02*
X326093Y151554D01*
G01X326063Y151555D02*
X326078D01*
G01X330025Y151554D02*
X330040Y151553D01*
G01X330010Y151555D02*
X330025Y151554D01*
G01X329995Y151555D02*
X330010D01*
G01X333967Y151554D02*
X333982Y151553D01*
G01X333952Y151555D02*
X333967Y151554D01*
G01X333937Y151555D02*
X333952D01*
G01X337899Y151554D02*
X337914Y151553D01*
G01X337884Y151555D02*
X337899Y151554D01*
G01X337869Y151555D02*
X337884D01*
G01X341841Y151554D02*
X341856Y151553D01*
G01X341826Y151555D02*
X341841Y151554D01*
G01X341811Y151555D02*
X341826D01*
G01X345773Y151554D02*
X345788Y151553D01*
G01X345758Y151555D02*
X345773Y151554D01*
G01X345743Y151555D02*
X345758D01*
G01X278834D02*
X278819D01*
G01X278849Y151554D02*
X278834Y151555D01*
G01X278864Y151553D02*
X278849Y151554D01*
G01X286708Y151555D02*
X286693D01*
G01X286723Y151554D02*
X286708Y151555D01*
G01X286738Y151553D02*
X286723Y151554D01*
G01X310330Y151555D02*
X310315D01*
G01X310345Y151554D02*
X310330Y151555D01*
G01X310360Y151553D02*
X310345Y151554D01*
G01X267245Y129981D02*
X267403Y129943D01*
G01X268741D02*
X268899Y129981D01*
G01X267245Y131039D02*
X267403Y130965D01*
G01X268741D02*
X268899Y131039D01*
G01X267324Y134627D02*
X267335Y134640D01*
G01X268808D02*
X268820Y134627D01*
G01X268899Y156396D02*
X268741Y156434D01*
G01X267403D02*
X267245Y156396D01*
G01X268899Y155338D02*
X268741Y155412D01*
G01X267403D02*
X267245Y155338D01*
G01X267335Y151737D02*
X267324Y151750D01*
G01X268820D02*
X268808Y151737D01*
G01X272741Y134640D02*
X272752Y134627D01*
G01X271256D02*
X271268Y134640D01*
G01X272836Y138680D02*
X272678Y138717D01*
G01X271340D02*
X271182Y138680D01*
G01X272836Y137621D02*
X272678Y137696D01*
G01X271340D02*
X271182Y137621D01*
G01Y147698D02*
X271340Y147660D01*
G01X271182Y148756D02*
X271340Y148681D01*
G01X272678D02*
X272836Y148756D01*
G01X272678Y147660D02*
X272836Y147698D01*
G01X273082Y151555D02*
X273037Y151553D01*
G01X271277Y151737D02*
X271265Y151750D01*
G01X272762D02*
X272750Y151737D01*
G01X275119Y129981D02*
X275277Y129943D01*
G01X276615D02*
X276773Y129981D01*
G01X275119Y131039D02*
X275277Y130965D01*
G01X276615D02*
X276773Y131039D01*
G01X275198Y134627D02*
X275209Y134640D01*
G01X276682D02*
X276694Y134627D01*
G01X276773Y156396D02*
X276615Y156434D01*
G01X275277D02*
X275119Y156396D01*
G01X276773Y155338D02*
X276615Y155412D01*
G01X275277D02*
X275119Y155338D01*
G01X275209Y151737D02*
X275198Y151750D01*
G01X276694D02*
X276682Y151737D01*
G01X280615Y134640D02*
X280626Y134627D01*
G01X279130D02*
X279142Y134640D01*
G01X280710Y138680D02*
X280552Y138717D01*
G01X279214D02*
X279056Y138680D01*
G01X280710Y137621D02*
X280552Y137696D01*
G01X279214D02*
X279056Y137621D01*
G01Y147698D02*
X279214Y147660D01*
G01X280552D02*
X280710Y147698D01*
G01X279056Y148756D02*
X279214Y148681D01*
G01X280552D02*
X280710Y148756D01*
G01X279151Y151737D02*
X279139Y151750D01*
G01X280636D02*
X280624Y151737D01*
G01X282993Y129981D02*
X283151Y129943D01*
G01X284489D02*
X284647Y129981D01*
G01X282993Y131039D02*
X283151Y130965D01*
G01X284489D02*
X284647Y131039D01*
G01X283072Y134627D02*
X283083Y134640D01*
G01X284556D02*
X284568Y134627D01*
G01X284647Y156396D02*
X284489Y156434D01*
G01X283151D02*
X282993Y156396D01*
G01X284647Y155338D02*
X284489Y155412D01*
G01X283151D02*
X282993Y155338D01*
G01X283083Y151737D02*
X283072Y151750D01*
G01X284568D02*
X284556Y151737D01*
G01X288489Y134640D02*
X288500Y134627D01*
G01X287004D02*
X287016Y134640D01*
G01X288584Y138680D02*
X288426Y138717D01*
G01X287088D02*
X286930Y138680D01*
G01X288584Y137621D02*
X288426Y137696D01*
G01X287088D02*
X286930Y137621D01*
G01Y147698D02*
X287088Y147660D01*
G01X288426D02*
X288584Y147698D01*
G01X286930Y148756D02*
X287088Y148681D01*
G01X288426D02*
X288584Y148756D01*
G01X287025Y151737D02*
X287014Y151750D01*
G01X288510D02*
X288498Y151737D01*
G01X290867Y129981D02*
X291025Y129943D01*
G01X292363D02*
X292521Y129981D01*
G01X290867Y131039D02*
X291025Y130965D01*
G01X292363D02*
X292521Y131039D01*
G01X290946Y134627D02*
X290957Y134640D01*
G01X292430D02*
X292442Y134627D01*
G01X292521Y156396D02*
X292363Y156434D01*
G01X291025D02*
X290867Y156396D01*
G01X292521Y155338D02*
X292363Y155412D01*
G01X291025D02*
X290867Y155338D01*
G01X290957Y151737D02*
X290946Y151750D01*
G01X292442D02*
X292430Y151737D01*
G01X296363Y134640D02*
X296374Y134627D01*
G01X294878D02*
X294890Y134640D01*
G01X296458Y138680D02*
X296300Y138717D01*
G01X294962D02*
X294804Y138680D01*
G01X296458Y137621D02*
X296300Y137696D01*
G01X294962D02*
X294804Y137621D01*
G01Y147698D02*
X294962Y147660D01*
G01X294804Y148756D02*
X294962Y148681D01*
G01X296300D02*
X296458Y148756D01*
G01X296300Y147660D02*
X296458Y147698D01*
G01X296704Y151555D02*
X296659Y151553D01*
G01X294899Y151737D02*
X294888Y151750D01*
G01X296384D02*
X296372Y151737D01*
G01X298741Y129981D02*
X298899Y129943D01*
G01X300237D02*
X300395Y129981D01*
G01X298741Y131039D02*
X298899Y130965D01*
G01X300237D02*
X300395Y131039D01*
G01X298820Y134627D02*
X298831Y134640D01*
G01X300304D02*
X300316Y134627D01*
G01X300395Y156396D02*
X300237Y156434D01*
G01X298899D02*
X298741Y156396D01*
G01X300395Y155338D02*
X300237Y155412D01*
G01X298899D02*
X298741Y155338D01*
G01X298831Y151737D02*
X298820Y151750D01*
G01X300316D02*
X300304Y151737D01*
G01X304237Y134640D02*
X304248Y134627D01*
G01X302752D02*
X302764Y134640D01*
G01X304332Y138680D02*
X304174Y138717D01*
G01X302836D02*
X302678Y138680D01*
G01X304332Y137621D02*
X304174Y137696D01*
G01X302836D02*
X302678Y137621D01*
G01Y147698D02*
X302836Y147660D01*
G01X302678Y148756D02*
X302836Y148681D01*
G01X304174D02*
X304332Y148756D01*
G01X304174Y147660D02*
X304332Y147698D01*
G01X304578Y151555D02*
X304533Y151553D01*
G01X302773Y151737D02*
X302762Y151750D01*
G01X304258D02*
X304246Y151737D01*
G01X306615Y129981D02*
X306773Y129943D01*
G01X308111D02*
X308269Y129981D01*
G01X306615Y131039D02*
X306773Y130965D01*
G01X308111D02*
X308269Y131039D01*
G01X306694Y134627D02*
X306705Y134640D01*
G01X308178D02*
X308190Y134627D01*
G01X308269Y156396D02*
X308111Y156434D01*
G01X306773D02*
X306615Y156396D01*
G01X308269Y155338D02*
X308111Y155412D01*
G01X306773D02*
X306615Y155338D01*
G01X306705Y151737D02*
X306694Y151750D01*
G01X308190D02*
X308178Y151737D01*
G01X312111Y134640D02*
X312122Y134627D01*
G01X310626D02*
X310638Y134640D01*
G01X312206Y138680D02*
X312048Y138717D01*
G01X310710D02*
X310552Y138680D01*
G01X312206Y137621D02*
X312048Y137696D01*
G01X310710D02*
X310552Y137621D01*
G01Y147698D02*
X310710Y147660D01*
G01X312048D02*
X312206Y147698D01*
G01X310552Y148756D02*
X310710Y148681D01*
G01X312048D02*
X312206Y148756D01*
G01X310647Y151737D02*
X310636Y151750D01*
G01X312132D02*
X312120Y151737D01*
G01X314489Y129981D02*
X314647Y129943D01*
G01X315985D02*
X316143Y129981D01*
G01X314489Y131039D02*
X314647Y130965D01*
G01X315985D02*
X316143Y131039D01*
G01X314568Y134627D02*
X314579Y134640D01*
G01X316052D02*
X316064Y134627D01*
G01X316143Y156396D02*
X315985Y156434D01*
G01X314647D02*
X314489Y156396D01*
G01X316143Y155338D02*
X315985Y155412D01*
G01X314647D02*
X314489Y155338D01*
G01X314579Y151737D02*
X314568Y151750D01*
G01X316064D02*
X316052Y151737D01*
G01X319985Y134640D02*
X319996Y134627D01*
G01X318500D02*
X318512Y134640D01*
G01X318180Y134822D02*
X318225Y134824D01*
G01X318584Y138717D02*
X318426Y138680D01*
G01X320080D02*
X319922Y138717D01*
G01X318584Y137696D02*
X318426Y137621D01*
G01X320080D02*
X319922Y137696D01*
G01X318521Y151737D02*
X318510Y151750D01*
G01X320006D02*
X319994Y151737D01*
G01X319922Y147660D02*
X320080Y147698D01*
G01X318426D02*
X318584Y147660D01*
G01X319922Y148681D02*
X320080Y148756D01*
G01X318426D02*
X318584Y148681D01*
G01X323859Y129943D02*
X324017Y129981D01*
G01X322363D02*
X322521Y129943D01*
G01X323859Y130965D02*
X324017Y131039D01*
G01X322363D02*
X322521Y130965D01*
G01X322121Y133838D02*
X322166Y133840D01*
G01X322442Y134627D02*
X322453Y134640D01*
G01X323926D02*
X323938Y134627D01*
G01X322521Y156434D02*
X322363Y156396D01*
G01X324017D02*
X323859Y156434D01*
G01X322521Y155412D02*
X322363Y155338D01*
G01X324017D02*
X323859Y155412D01*
G01X322453Y151737D02*
X322442Y151750D01*
G01X323938D02*
X323926Y151737D01*
G01X324259Y152539D02*
X324214Y152538D01*
G01X327954Y138680D02*
X327796Y138717D01*
G01X326458D02*
X326300Y138680D01*
G01X326458Y137696D02*
X326300Y137621D01*
G01X327954D02*
X327796Y137696D01*
G01X327859Y134640D02*
X327870Y134627D01*
G01X326374D02*
X326386Y134640D01*
G01X326054Y134822D02*
X326099Y134824D01*
G01X326300Y147698D02*
X326458Y147660D01*
G01X327796Y148681D02*
X327954Y148756D01*
G01X326300D02*
X326458Y148681D01*
G01X327796Y147660D02*
X327954Y147698D01*
G01X326395Y151737D02*
X326384Y151750D01*
G01X327880D02*
X327868Y151737D01*
G01X328200Y152539D02*
X328155Y152538D01*
G01X331733Y129943D02*
X331891Y129981D01*
G01X330237D02*
X330395Y129943D01*
G01X331733Y130965D02*
X331891Y131039D01*
G01X330237D02*
X330395Y130965D01*
G01X329995Y133838D02*
X330040Y133840D01*
G01X330316Y134627D02*
X330327Y134640D01*
G01X331800D02*
X331812Y134627D01*
G01X330395Y156434D02*
X330237Y156396D01*
G01X331891D02*
X331733Y156434D01*
G01X330395Y155412D02*
X330237Y155338D01*
G01X331891D02*
X331733Y155412D01*
G01X330327Y151737D02*
X330316Y151750D01*
G01X331812D02*
X331800Y151737D01*
G01X332133Y152539D02*
X332088Y152538D01*
G01X335733Y134640D02*
X335744Y134627D01*
G01X334248D02*
X334260Y134640D01*
G01X335828Y138680D02*
X335670Y138717D01*
G01X334332D02*
X334174Y138680D01*
G01X335828Y137621D02*
X335670Y137696D01*
G01X334332D02*
X334174Y137621D01*
G01Y147698D02*
X334332Y147660D01*
G01X334174Y148756D02*
X334332Y148681D01*
G01X335670D02*
X335828Y148756D01*
G01X335670Y147660D02*
X335828Y147698D01*
G01X336074Y151555D02*
X336029Y151553D01*
G01X334269Y151737D02*
X334258Y151750D01*
G01X335754D02*
X335742Y151737D01*
G01X338111Y129981D02*
X338269Y129943D01*
G01X339607D02*
X339765Y129981D01*
G01X338111Y131039D02*
X338269Y130965D01*
G01X339607D02*
X339765Y131039D01*
G01X338190Y134627D02*
X338201Y134640D01*
G01X339674D02*
X339686Y134627D01*
G01X339765Y156396D02*
X339607Y156434D01*
G01X338269D02*
X338111Y156396D01*
G01X339765Y155338D02*
X339607Y155412D01*
G01X338269D02*
X338111Y155338D01*
G01X338201Y151737D02*
X338190Y151750D01*
G01X339686D02*
X339674Y151737D01*
G01X343607Y134640D02*
X343618Y134627D01*
G01X342122D02*
X342134Y134640D01*
G01X343702Y138680D02*
X343544Y138717D01*
G01X342206D02*
X342048Y138680D01*
G01X343702Y137621D02*
X343544Y137696D01*
G01X342206D02*
X342048Y137621D01*
G01Y147698D02*
X342206Y147660D01*
G01X342048Y148756D02*
X342206Y148681D01*
G01X343544D02*
X343702Y148756D01*
G01X343544Y147660D02*
X343702Y147698D01*
G01X343948Y151555D02*
X343903Y151553D01*
G01X342143Y151737D02*
X342132Y151750D01*
G01X343628D02*
X343616Y151737D01*
G01X345985Y129981D02*
X346143Y129943D01*
G01X345985Y131039D02*
X346143Y130965D01*
G01X346064Y134627D02*
X346075Y134640D01*
G01X346143Y156434D02*
X345985Y156396D01*
G01X346143Y155412D02*
X345985Y155338D01*
G01X346075Y151737D02*
X346064Y151750D01*
G01X346075Y151737D02*
X346329Y151368D01*
G01X346284Y150441D02*
X346062Y150762D01*
G01X269253Y156476D02*
X266891D01*
G01X273190D02*
X270828D01*
G01X277127D02*
X274765D01*
G01X281064D02*
X278702D01*
G01X285001D02*
X282639D01*
G01X288938D02*
X286576D01*
G01X292875D02*
X290513D01*
G01X296812D02*
X294450D01*
G01X300749D02*
X298387D01*
G01X304686D02*
X302324D01*
G01X308623D02*
X306261D01*
G01X312560D02*
X310198D01*
G01X316497D02*
X314135D01*
G01X320434D02*
X318072D01*
G01X324371D02*
X322009D01*
G01X328308D02*
X325946D01*
G01X332245D02*
X329883D01*
G01X336182D02*
X333820D01*
G01X340119D02*
X337757D01*
G01X344056D02*
X341694D01*
G01X347993D02*
X345631D01*
G01X268741Y155492D02*
X267403D01*
G01X276615D02*
X275277D01*
G01X284489D02*
X283151D01*
G01X292363D02*
X291025D01*
G01X300237D02*
X298899D01*
G01X308111D02*
X306773D01*
G01X315985D02*
X314647D01*
G01X323859D02*
X322521D01*
G01X331733D02*
X330395D01*
G01X339607D02*
X338269D01*
G01X347481D02*
X346143D01*
G01X345985Y155393D02*
X347639D01*
G01X338111D02*
X339765D01*
G01X330237D02*
X331891D01*
G01X322363D02*
X324017D01*
G01X314489D02*
X316143D01*
G01X306615D02*
X308269D01*
G01X298741D02*
X300395D01*
G01X290867D02*
X292521D01*
G01X282993D02*
X284647D01*
G01X275119D02*
X276773D01*
G01X267245D02*
X268899D01*
G01X269253Y155295D02*
X266891D01*
G01X273190D02*
X270828D01*
G01X277127D02*
X274765D01*
G01X281064D02*
X278702D01*
G01X285001D02*
X282639D01*
G01X288938D02*
X286576D01*
G01X292875D02*
X290513D01*
G01X296812D02*
X294450D01*
G01X300749D02*
X298387D01*
G01X304686D02*
X302324D01*
G01X308623D02*
X306261D01*
G01X312560D02*
X310198D01*
G01X316497D02*
X314135D01*
G01X320434D02*
X318072D01*
G01X324371D02*
X322009D01*
G01X328308D02*
X325946D01*
G01X332245D02*
X329883D01*
G01X336182D02*
X333820D01*
G01X340119D02*
X337757D01*
G01X344056D02*
X341694D01*
G01X347993D02*
X345631D01*
G01X268899Y154901D02*
X267245D01*
G01X276773D02*
X275119D01*
G01X284647D02*
X282993D01*
G01X292521D02*
X290867D01*
G01X300395D02*
X298741D01*
G01X308269D02*
X306615D01*
G01X316143D02*
X314489D01*
G01X324017D02*
X322363D01*
G01X331891D02*
X330237D01*
G01X339765D02*
X338111D01*
G01X347639D02*
X345985D01*
G01X273426Y154035D02*
X270592D01*
G01X277363D02*
X274529D01*
G01X281300D02*
X278466D01*
G01X285237D02*
X282403D01*
G01X289174D02*
X286340D01*
G01X293111D02*
X290277D01*
G01X297048D02*
X294214D01*
G01X300985D02*
X298151D01*
G01X304922D02*
X302088D01*
G01X308859D02*
X306025D01*
G01X312796D02*
X309962D01*
G01X316733D02*
X313899D01*
G01X320670D02*
X317836D01*
G01X324607D02*
X321773D01*
G01X328544D02*
X325710D01*
G01X332481D02*
X329647D01*
G01X336418D02*
X333584D01*
G01X340355D02*
X337521D01*
G01X344292D02*
X341458D01*
G01X348229D02*
X345395D01*
G01X268899Y153130D02*
X267245D01*
G01X276773D02*
X275119D01*
G01X284647D02*
X282993D01*
G01X292521D02*
X290867D01*
G01X300395D02*
X298741D01*
G01X308269D02*
X306615D01*
G01X316143D02*
X314489D01*
G01X324017D02*
X322363D01*
G01X331891D02*
X330237D01*
G01X339765D02*
X338111D01*
G01X347639D02*
X345985D01*
G01Y152637D02*
X347639D01*
G01X338111D02*
X339765D01*
G01X330237D02*
X331891D01*
G01X322363D02*
X324017D01*
G01X314489D02*
X316143D01*
G01X306615D02*
X308269D01*
G01X298741D02*
X300395D01*
G01X290867D02*
X292521D01*
G01X282993D02*
X284647D01*
G01X275119D02*
X276773D01*
G01X267245D02*
X268899D01*
G01X273426Y152539D02*
X270592D01*
G01X277363D02*
X274529D01*
G01X281300D02*
X278466D01*
G01X285237D02*
X282403D01*
G01X289174D02*
X286340D01*
G01X293111D02*
X290277D01*
G01X297048D02*
X294214D01*
G01X300985D02*
X298151D01*
G01X304922D02*
X302088D01*
G01X308859D02*
X306025D01*
G01X312796D02*
X309962D01*
G01X316733D02*
X313899D01*
G01X320670D02*
X317836D01*
G01X324607D02*
X321773D01*
G01X328544D02*
X325710D01*
G01X332481D02*
X329647D01*
G01X336418D02*
X333584D01*
G01X340355D02*
X337521D01*
G01X344292D02*
X341458D01*
G01X348229D02*
X345395D01*
G01Y152382D02*
X345985D01*
G01X343702D02*
X344292D01*
G01X341458D02*
X342048D01*
G01X339765D02*
X340355D01*
G01X337521D02*
X338111D01*
G01X335828D02*
X336418D01*
G01X333584D02*
X334174D01*
G01X331891D02*
X332481D01*
G01X329647D02*
X330237D01*
G01X327954D02*
X328544D01*
G01X325710D02*
X326300D01*
G01X324017D02*
X324607D01*
G01X321773D02*
X322363D01*
G01X320080D02*
X320670D01*
G01X317836D02*
X318426D01*
G01X316143D02*
X316733D01*
G01X313899D02*
X314489D01*
G01X312206D02*
X312796D01*
G01X309962D02*
X310552D01*
G01X308269D02*
X308859D01*
G01X306025D02*
X306615D01*
G01X304332D02*
X304922D01*
G01X302088D02*
X302678D01*
G01X300395D02*
X300985D01*
G01X298151D02*
X298741D01*
G01X296458D02*
X297048D01*
G01X294214D02*
X294804D01*
G01X292521D02*
X293111D01*
G01X290277D02*
X290867D01*
G01X288584D02*
X289174D01*
G01X286340D02*
X286930D01*
G01X284647D02*
X285237D01*
G01X282403D02*
X282993D01*
G01X280710D02*
X281300D01*
G01X278466D02*
X279056D01*
G01X276773D02*
X277363D01*
G01X274529D02*
X275119D01*
G01X272836D02*
X273426D01*
G01X270592D02*
X271182D01*
G01X268899D02*
X269489D01*
G01X345806Y152147D02*
X347818D01*
G01X341874D02*
X343885D01*
G01X337932D02*
X339944D01*
G01X334000D02*
X336011D01*
G01X330058D02*
X332070D01*
G01X326126D02*
X328137D01*
G01X322184D02*
X324196D01*
G01X318252D02*
X320263D01*
G01X314310D02*
X316322D01*
G01X310378D02*
X312389D01*
G01X306436D02*
X308448D01*
G01X302504D02*
X304515D01*
G01X298562D02*
X300574D01*
G01X294630D02*
X296641D01*
G01X290688D02*
X292700D01*
G01X286756D02*
X288767D01*
G01X282814D02*
X284825D01*
G01X278882D02*
X280893D01*
G01X274940D02*
X276951D01*
G01X271008D02*
X273019D01*
G01X267066D02*
X269077D01*
G01X268822Y151756D02*
X267322D01*
G01X272763D02*
X271264D01*
G01X276696D02*
X275196D01*
G01X280637D02*
X279138D01*
G01X284570D02*
X283070D01*
G01X288511D02*
X287012D01*
G01X292444D02*
X290944D01*
G01X296385D02*
X294886D01*
G01X300318D02*
X298818D01*
G01X304259D02*
X302760D01*
G01X308192D02*
X306692D01*
G01X312133D02*
X310634D01*
G01X316066D02*
X314566D01*
G01X320007D02*
X318508D01*
G01X323940D02*
X322440D01*
G01X327881D02*
X326382D01*
G01X331814D02*
X330314D01*
G01X335755D02*
X334256D01*
G01X339688D02*
X338188D01*
G01X343629D02*
X342130D01*
G01X347562D02*
X346062D01*
G01X346075Y151737D02*
X347548D01*
G01X342143D02*
X343616D01*
G01X338201D02*
X339674D01*
G01X334269D02*
X335742D01*
G01X330327D02*
X331800D01*
G01X326395D02*
X327868D01*
G01X322453D02*
X323926D01*
G01X318521D02*
X319994D01*
G01X314579D02*
X316052D01*
G01X310647D02*
X312120D01*
G01X306705D02*
X308178D01*
G01X302773D02*
X304246D01*
G01X298831D02*
X300304D01*
G01X294899D02*
X296372D01*
G01X290957D02*
X292430D01*
G01X287025D02*
X288498D01*
G01X283083D02*
X284556D01*
G01X279151D02*
X280624D01*
G01X275209D02*
X276682D01*
G01X271277D02*
X272750D01*
G01X267335D02*
X268808D01*
G01X269489Y151712D02*
X268899D01*
G01X271182D02*
X270592D01*
G01X273426D02*
X272836D01*
G01X275119D02*
X274529D01*
G01X277363D02*
X276773D01*
G01X279056D02*
X278466D01*
G01X281300D02*
X280710D01*
G01X282993D02*
X282403D01*
G01X285237D02*
X284647D01*
G01X286930D02*
X286340D01*
G01X289174D02*
X288584D01*
G01X290867D02*
X290277D01*
G01X293111D02*
X292521D01*
G01X294804D02*
X294214D01*
G01X297048D02*
X296458D01*
G01X298741D02*
X298151D01*
G01X300985D02*
X300395D01*
G01X302678D02*
X302088D01*
G01X304922D02*
X304332D01*
G01X306615D02*
X306025D01*
G01X308859D02*
X308269D01*
G01X310552D02*
X309962D01*
G01X312796D02*
X312206D01*
G01X314489D02*
X313899D01*
G01X316733D02*
X316143D01*
G01X318426D02*
X317836D01*
G01X320670D02*
X320080D01*
G01X322363D02*
X321773D01*
G01X324607D02*
X324017D01*
G01X326300D02*
X325710D01*
G01X328544D02*
X327954D01*
G01X330237D02*
X329647D01*
G01X332481D02*
X331891D01*
G01X334174D02*
X333584D01*
G01X336418D02*
X335828D01*
G01X338111D02*
X337521D01*
G01X340355D02*
X339765D01*
G01X342048D02*
X341458D01*
G01X344292D02*
X343702D01*
G01X345985D02*
X345395D01*
G01Y151555D02*
X348229D01*
G01X341458D02*
X344292D01*
G01X337521D02*
X340355D01*
G01X333584D02*
X336418D01*
G01X329647D02*
X332481D01*
G01X325710D02*
X328544D01*
G01X321773D02*
X324607D01*
G01X313899D02*
X316733D01*
G01X309962D02*
X312796D01*
G01X306025D02*
X308859D01*
G01X302088D02*
X304922D01*
G01X298151D02*
X300985D01*
G01X294214D02*
X297048D01*
G01X290277D02*
X293111D01*
G01X282403D02*
X285237D01*
G01X274529D02*
X277363D01*
G01X270592D02*
X273426D01*
G01X281300D02*
X278466D01*
G01X289174D02*
X286340D01*
G01X320670D02*
X317836D01*
G01X272836Y151456D02*
X271182D01*
G01X280710D02*
X279056D01*
G01X288584D02*
X286930D01*
G01X296458D02*
X294804D01*
G01X304332D02*
X302678D01*
G01X312206D02*
X310552D01*
G01X320080D02*
X318426D01*
G01X327954D02*
X326300D01*
G01X335828D02*
X334174D01*
G01X343702D02*
X342048D01*
G01X268555Y151368D02*
X267589D01*
G01X272496D02*
X271531D01*
G01X276429D02*
X275463D01*
G01X280370D02*
X279405D01*
G01X284303D02*
X283337D01*
G01X288244D02*
X287279D01*
G01X292177D02*
X291211D01*
G01X296118D02*
X295153D01*
G01X300051D02*
X299085D01*
G01X303992D02*
X303027D01*
G01X307925D02*
X306959D01*
G01X311866D02*
X310901D01*
G01X315799D02*
X314833D01*
G01X319740D02*
X318775D01*
G01X323673D02*
X322707D01*
G01X327614D02*
X326649D01*
G01X331547D02*
X330581D01*
G01X335488D02*
X334523D01*
G01X339421D02*
X338455D01*
G01X343362D02*
X342397D01*
G01X347295D02*
X346329D01*
G01X345395Y151358D02*
X345710D01*
G01X341458D02*
X341773D01*
G01X337521D02*
X337836D01*
G01X333584D02*
X333899D01*
G01X325710D02*
X326025D01*
G01X317836D02*
X318151D01*
G01X313899D02*
X314214D01*
G01X309962D02*
X310277D01*
G01X306025D02*
X306340D01*
G01X302088D02*
X302403D01*
G01X298151D02*
X298466D01*
G01X294214D02*
X294529D01*
G01X290277D02*
X290592D01*
G01X286340D02*
X286655D01*
G01X282403D02*
X282717D01*
G01X278466D02*
X278780D01*
G01X274529D02*
X274843D01*
G01X270592D02*
X270906D01*
G01X269489D02*
X269174D01*
G01X273426D02*
X273111D01*
G01X277363D02*
X277048D01*
G01X281300D02*
X280985D01*
G01X285237D02*
X284922D01*
G01X289174D02*
X288859D01*
G01X293111D02*
X292796D01*
G01X297048D02*
X296733D01*
G01X300985D02*
X300670D01*
G01X304922D02*
X304607D01*
G01X308859D02*
X308544D01*
G01X312796D02*
X312481D01*
G01X316733D02*
X316418D01*
G01X320670D02*
X320355D01*
G01X322088D02*
X321773D01*
G01X324607D02*
X324292D01*
G01X328544D02*
X328229D01*
G01X329962D02*
X329647D01*
G01X332481D02*
X332166D01*
G01X336418D02*
X336103D01*
G01X340355D02*
X340040D01*
G01X344292D02*
X343977D01*
G01X269082Y151260D02*
X267061D01*
G01X273024D02*
X271003D01*
G01X276956D02*
X274935D01*
G01X280898D02*
X278877D01*
G01X284830D02*
X282809D01*
G01X288772D02*
X286751D01*
G01X292704D02*
X290683D01*
G01X296646D02*
X294625D01*
G01X300578D02*
X298557D01*
G01X304520D02*
X302499D01*
G01X308452D02*
X306431D01*
G01X312394D02*
X310373D01*
G01X316326D02*
X314306D01*
G01X320268D02*
X318247D01*
G01X324200D02*
X322180D01*
G01X328142D02*
X326121D01*
G01X332074D02*
X330054D01*
G01X336016D02*
X333995D01*
G01X339948D02*
X337928D01*
G01X343890D02*
X341869D01*
G01X347822D02*
X345802D01*
G01X342048Y150964D02*
X343702D01*
G01X334174D02*
X335828D01*
G01X326300D02*
X327954D01*
G01X318426D02*
X320080D01*
G01X310552D02*
X312206D01*
G01X302678D02*
X304332D01*
G01X294804D02*
X296458D01*
G01X286930D02*
X288584D01*
G01X279056D02*
X280710D01*
G01X271182D02*
X272836D01*
G01X268822Y150772D02*
X267322D01*
G01X272763D02*
X271264D01*
G01X276696D02*
X275196D01*
G01X280637D02*
X279138D01*
G01X284570D02*
X283070D01*
G01X288511D02*
X287012D01*
G01X292444D02*
X290944D01*
G01X296385D02*
X294886D01*
G01X300318D02*
X298818D01*
G01X304259D02*
X302760D01*
G01X308192D02*
X306692D01*
G01X312133D02*
X310634D01*
G01X316066D02*
X314566D01*
G01X320007D02*
X318508D01*
G01X323940D02*
X322440D01*
G01X327881D02*
X326382D01*
G01X331814D02*
X330314D01*
G01X335755D02*
X334256D01*
G01X339688D02*
X338188D01*
G01X343629D02*
X342130D01*
G01X347562D02*
X346062D01*
G01X268820Y150762D02*
X267324D01*
G01X272762D02*
X271265D01*
G01X276694D02*
X275198D01*
G01X280636D02*
X279139D01*
G01X284568D02*
X283072D01*
G01X288510D02*
X287013D01*
G01X292442D02*
X290946D01*
G01X296384D02*
X294887D01*
G01X300316D02*
X298820D01*
G01X304258D02*
X302761D01*
G01X308190D02*
X306694D01*
G01X312132D02*
X310635D01*
G01X316064D02*
X314568D01*
G01X320006D02*
X318509D01*
G01X323938D02*
X322442D01*
G01X327880D02*
X326383D01*
G01X331812D02*
X330316D01*
G01X335754D02*
X334257D01*
G01X339686D02*
X338190D01*
G01X343628D02*
X342131D01*
G01X347560D02*
X346064D01*
G01X346284Y150441D02*
X347340D01*
G01X342351D02*
X343408D01*
G01X338410D02*
X339466D01*
G01X334477D02*
X335534D01*
G01X330536D02*
X331592D01*
G01X326603D02*
X327660D01*
G01X322662D02*
X323718D01*
G01X318729D02*
X319786D01*
G01X314788D02*
X315844D01*
G01X310855D02*
X311912D01*
G01X306914D02*
X307970D01*
G01X302981D02*
X304038D01*
G01X299040D02*
X300096D01*
G01X295107D02*
X296164D01*
G01X291166D02*
X292222D01*
G01X287233D02*
X288290D01*
G01X283292D02*
X284348D01*
G01X279359D02*
X280416D01*
G01X275418D02*
X276474D01*
G01X271485D02*
X272542D01*
G01X267544D02*
X268600D01*
G01X329883Y150393D02*
X332245D01*
G01X325946D02*
X328308D01*
G01X322009D02*
X324371D01*
G01X269253D02*
X266891D01*
G01X273190D02*
X270828D01*
G01X277127D02*
X274765D01*
G01X281064D02*
X278702D01*
G01X285001D02*
X282639D01*
G01X288938D02*
X286576D01*
G01X292875D02*
X290513D01*
G01X296812D02*
X294450D01*
G01X300749D02*
X298387D01*
G01X304686D02*
X302324D01*
G01X308623D02*
X306261D01*
G01X312560D02*
X310198D01*
G01X316497D02*
X314135D01*
G01X320434D02*
X318072D01*
G01X336182D02*
X333820D01*
G01X340119D02*
X337757D01*
G01X344056D02*
X341694D01*
G01X347993D02*
X345631D01*
G01X345395Y149862D02*
X345710D01*
G01X343977D02*
X344292D01*
G01X341458D02*
X341773D01*
G01X340040D02*
X340355D01*
G01X337521D02*
X337836D01*
G01X336103D02*
X336418D01*
G01X333584D02*
X333899D01*
G01X332166D02*
X332481D01*
G01X329647D02*
X329962D01*
G01X328229D02*
X328544D01*
G01X325710D02*
X326025D01*
G01X324292D02*
X324607D01*
G01X320355D02*
X320670D01*
G01X321773D02*
X322088D01*
G01X317836D02*
X318151D01*
G01X316418D02*
X316733D01*
G01X313899D02*
X314214D01*
G01X312481D02*
X312796D01*
G01X309962D02*
X310277D01*
G01X308544D02*
X308859D01*
G01X306025D02*
X306340D01*
G01X304607D02*
X304922D01*
G01X302088D02*
X302403D01*
G01X300670D02*
X300985D01*
G01X298151D02*
X298466D01*
G01X296733D02*
X297048D01*
G01X294214D02*
X294529D01*
G01X292796D02*
X293111D01*
G01X290277D02*
X290592D01*
G01X288859D02*
X289174D01*
G01X286340D02*
X286655D01*
G01X284922D02*
X285237D01*
G01X282403D02*
X282717D01*
G01X280985D02*
X281300D01*
G01X278466D02*
X278780D01*
G01X277048D02*
X277363D01*
G01X274529D02*
X274843D01*
G01X273111D02*
X273426D01*
G01X270592D02*
X270906D01*
G01X269174D02*
X269489D01*
G01X346040Y149826D02*
X347584D01*
G01X342108D02*
X343651D01*
G01X338166D02*
X339710D01*
G01X334234D02*
X335777D01*
G01X330292D02*
X331836D01*
G01X326360D02*
X327903D01*
G01X322418D02*
X323962D01*
G01X318486D02*
X320029D01*
G01X314544D02*
X316088D01*
G01X310612D02*
X312155D01*
G01X306670D02*
X308214D01*
G01X302738D02*
X304281D01*
G01X298796D02*
X300340D01*
G01X294864D02*
X296407D01*
G01X290922D02*
X292466D01*
G01X286990D02*
X288533D01*
G01X283048D02*
X284592D01*
G01X279116D02*
X280659D01*
G01X275174D02*
X276718D01*
G01X271242D02*
X272785D01*
G01X267300D02*
X268844D01*
G01X346051Y149807D02*
X347573D01*
G01X342119D02*
X343640D01*
G01X338177D02*
X339699D01*
G01X334245D02*
X335766D01*
G01X330303D02*
X331825D01*
G01X326371D02*
X327892D01*
G01X322429D02*
X323951D01*
G01X318497D02*
X320018D01*
G01X314555D02*
X316077D01*
G01X310623D02*
X312144D01*
G01X306681D02*
X308203D01*
G01X302749D02*
X304270D01*
G01X298807D02*
X300329D01*
G01X294875D02*
X296396D01*
G01X290933D02*
X292455D01*
G01X287001D02*
X288522D01*
G01X283059D02*
X284581D01*
G01X279127D02*
X280648D01*
G01X275185D02*
X276707D01*
G01X271253D02*
X272774D01*
G01X267311D02*
X268833D01*
G01X342048Y149193D02*
X343702D01*
G01X334174D02*
X335828D01*
G01X326300D02*
X327954D01*
G01X318426D02*
X320080D01*
G01X310552D02*
X312206D01*
G01X302678D02*
X304332D01*
G01X294804D02*
X296458D01*
G01X286930D02*
X288584D01*
G01X279056D02*
X280710D01*
G01X271182D02*
X272836D01*
G01Y148700D02*
X271182D01*
G01X280710D02*
X279056D01*
G01X288584D02*
X286930D01*
G01X296458D02*
X294804D01*
G01X304332D02*
X302678D01*
G01X312206D02*
X310552D01*
G01X320080D02*
X318426D01*
G01X327954D02*
X326300D01*
G01X335828D02*
X334174D01*
G01X343702D02*
X342048D01*
G01X272678Y148602D02*
X271340D01*
G01X280552D02*
X279214D01*
G01X288426D02*
X287088D01*
G01X296300D02*
X294962D01*
G01X304174D02*
X302836D01*
G01X312048D02*
X310710D01*
G01X319922D02*
X318584D01*
G01X327796D02*
X326458D01*
G01X335670D02*
X334332D01*
G01X343544D02*
X342206D01*
G01Y147618D02*
X343544D01*
G01X334332D02*
X335670D01*
G01X326458D02*
X327796D01*
G01X318584D02*
X319922D01*
G01X310710D02*
X312048D01*
G01X302836D02*
X304174D01*
G01X294962D02*
X296300D01*
G01X287088D02*
X288426D01*
G01X279214D02*
X280552D01*
G01X271340D02*
X272678D01*
G01X268869Y146999D02*
X267274D01*
G01X272811D02*
X271216D01*
G01X276743D02*
X275148D01*
G01X280685D02*
X279090D01*
G01X284617D02*
X283022D01*
G01X288559D02*
X286964D01*
G01X292491D02*
X290896D01*
G01X296433D02*
X294838D01*
G01X300365D02*
X298770D01*
G01X304307D02*
X302712D01*
G01X308239D02*
X306644D01*
G01X312181D02*
X310586D01*
G01X316114D02*
X314518D01*
G01X320055D02*
X318460D01*
G01X323988D02*
X322392D01*
G01X327929D02*
X326334D01*
G01X331862D02*
X330266D01*
G01X335803D02*
X334208D01*
G01X339736D02*
X338140D01*
G01X343677D02*
X342082D01*
G01X347610D02*
X346014D01*
G01X269174Y146889D02*
X266969D01*
G01X273111D02*
X270906D01*
G01X277048D02*
X274843D01*
G01X280985D02*
X278780D01*
G01X284922D02*
X282717D01*
G01X288859D02*
X286655D01*
G01X292796D02*
X290592D01*
G01X296733D02*
X294529D01*
G01X300670D02*
X298466D01*
G01X304607D02*
X302403D01*
G01X308544D02*
X306340D01*
G01X312481D02*
X310277D01*
G01X316418D02*
X314214D01*
G01X320355D02*
X318151D01*
G01X324292D02*
X322088D01*
G01X328229D02*
X326025D01*
G01X332166D02*
X329962D01*
G01X336103D02*
X333899D01*
G01X340040D02*
X337836D01*
G01X343977D02*
X341773D01*
G01X347914D02*
X345710D01*
G01X268941Y146239D02*
X267202D01*
G01X272883D02*
X271144D01*
G01X276815D02*
X275076D01*
G01X280757D02*
X279018D01*
G01X284689D02*
X282950D01*
G01X288631D02*
X286892D01*
G01X292563D02*
X290824D01*
G01X296505D02*
X294766D01*
G01X300437D02*
X298698D01*
G01X304379D02*
X302640D01*
G01X308311D02*
X306573D01*
G01X312253D02*
X310514D01*
G01X316185D02*
X314447D01*
G01X320127D02*
X318388D01*
G01X324059D02*
X322321D01*
G01X328001D02*
X326262D01*
G01X331933D02*
X330195D01*
G01X335875D02*
X334136D01*
G01X339807D02*
X338069D01*
G01X343749D02*
X342010D01*
G01X347681D02*
X345943D01*
G01X346017Y146037D02*
X347607D01*
G01X342084D02*
X343675D01*
G01X338143D02*
X339733D01*
G01X334210D02*
X335801D01*
G01X330269D02*
X331859D01*
G01X326336D02*
X327927D01*
G01X322395D02*
X323985D01*
G01X318462D02*
X320053D01*
G01X314521D02*
X316111D01*
G01X310588D02*
X312179D01*
G01X306647D02*
X308237D01*
G01X302714D02*
X304305D01*
G01X298773D02*
X300363D01*
G01X294840D02*
X296431D01*
G01X290899D02*
X292489D01*
G01X286966D02*
X288557D01*
G01X283025D02*
X284615D01*
G01X279092D02*
X280683D01*
G01X275151D02*
X276741D01*
G01X271218D02*
X272809D01*
G01X267277D02*
X268867D01*
G01X345964Y146012D02*
X347660D01*
G01X342032D02*
X343728D01*
G01X338090D02*
X339786D01*
G01X334158D02*
X335854D01*
G01X330216D02*
X331912D01*
G01X326284D02*
X327980D01*
G01X322342D02*
X324038D01*
G01X318410D02*
X320106D01*
G01X314468D02*
X316164D01*
G01X310536D02*
X312232D01*
G01X306594D02*
X308290D01*
G01X302661D02*
X304358D01*
G01X298720D02*
X300416D01*
G01X294787D02*
X296484D01*
G01X290846D02*
X292542D01*
G01X286913D02*
X288610D01*
G01X282972D02*
X284668D01*
G01X279039D02*
X280736D01*
G01X275098D02*
X276794D01*
G01X271165D02*
X272862D01*
G01X267224D02*
X268920D01*
G01X268927Y145945D02*
X267217D01*
G01X272869D02*
X271158D01*
G01X276801D02*
X275091D01*
G01X280743D02*
X279032D01*
G01X284675D02*
X282965D01*
G01X288617D02*
X286906D01*
G01X292549D02*
X290839D01*
G01X296491D02*
X294780D01*
G01X300423D02*
X298713D01*
G01X304365D02*
X302654D01*
G01X308297D02*
X306587D01*
G01X312239D02*
X310529D01*
G01X316171D02*
X314461D01*
G01X320113D02*
X318403D01*
G01X324045D02*
X322335D01*
G01X327987D02*
X326277D01*
G01X331919D02*
X330209D01*
G01X335861D02*
X334151D01*
G01X339793D02*
X338083D01*
G01X343735D02*
X342025D01*
G01X347667D02*
X345957D01*
G01X345938Y145353D02*
X347686D01*
G01X342005D02*
X343754D01*
G01X338064D02*
X339812D01*
G01X334131D02*
X335880D01*
G01X330190D02*
X331938D01*
G01X326257D02*
X328006D01*
G01X322316D02*
X324064D01*
G01X318383D02*
X320132D01*
G01X314442D02*
X316190D01*
G01X310509D02*
X312258D01*
G01X306568D02*
X308316D01*
G01X302635D02*
X304384D01*
G01X298694D02*
X300442D01*
G01X294761D02*
X296510D01*
G01X290820D02*
X292568D01*
G01X286887D02*
X288636D01*
G01X282946D02*
X284694D01*
G01X279013D02*
X280762D01*
G01X275072D02*
X276820D01*
G01X271139D02*
X272888D01*
G01X267198D02*
X268946D01*
G01X268918Y145050D02*
X267226D01*
G01X272859D02*
X271168D01*
G01X276792D02*
X275100D01*
G01X280733D02*
X279042D01*
G01X284666D02*
X282974D01*
G01X288607D02*
X286916D01*
G01X292540D02*
X290848D01*
G01X296481D02*
X294790D01*
G01X300414D02*
X298722D01*
G01X304355D02*
X302664D01*
G01X308288D02*
X306596D01*
G01X312229D02*
X310538D01*
G01X316162D02*
X314470D01*
G01X320103D02*
X318412D01*
G01X324036D02*
X322344D01*
G01X327977D02*
X326286D01*
G01X331910D02*
X330218D01*
G01X335851D02*
X334160D01*
G01X339784D02*
X338092D01*
G01X343725D02*
X342034D01*
G01X347658D02*
X345966D01*
G01X268927Y144960D02*
X267217D01*
G01X272869D02*
X271158D01*
G01X276801D02*
X275091D01*
G01X280743D02*
X279032D01*
G01X284675D02*
X282965D01*
G01X288617D02*
X286906D01*
G01X292549D02*
X290839D01*
G01X296491D02*
X294780D01*
G01X300423D02*
X298713D01*
G01X304365D02*
X302654D01*
G01X308297D02*
X306587D01*
G01X312239D02*
X310529D01*
G01X316171D02*
X314461D01*
G01X320113D02*
X318403D01*
G01X324045D02*
X322335D01*
G01X327987D02*
X326277D01*
G01X331919D02*
X330209D01*
G01X335861D02*
X334151D01*
G01X339793D02*
X338083D01*
G01X343735D02*
X342025D01*
G01X347667D02*
X345957D01*
G01X345710Y144634D02*
X347914D01*
G01X341773D02*
X343977D01*
G01X337836D02*
X340040D01*
G01X333899D02*
X336103D01*
G01X329962D02*
X332166D01*
G01X326025D02*
X328229D01*
G01X322088D02*
X324292D01*
G01X318151D02*
X320355D01*
G01X314214D02*
X316418D01*
G01X310277D02*
X312481D01*
G01X306340D02*
X308544D01*
G01X302403D02*
X304607D01*
G01X298466D02*
X300670D01*
G01X294529D02*
X296733D01*
G01X290592D02*
X292796D01*
G01X286655D02*
X288859D01*
G01X282717D02*
X284922D01*
G01X278780D02*
X280985D01*
G01X274843D02*
X277048D01*
G01X270906D02*
X273111D01*
G01X266969D02*
X269174D01*
G01X345710Y144467D02*
X347914D01*
G01X341773D02*
X343977D01*
G01X337836D02*
X340040D01*
G01X333899D02*
X336103D01*
G01X329962D02*
X332166D01*
G01X326025D02*
X328229D01*
G01X322088D02*
X324292D01*
G01X318151D02*
X320355D01*
G01X314214D02*
X316418D01*
G01X310277D02*
X312481D01*
G01X306340D02*
X308544D01*
G01X302403D02*
X304607D01*
G01X298466D02*
X300670D01*
G01X294529D02*
X296733D01*
G01X290592D02*
X292796D01*
G01X286655D02*
X288859D01*
G01X282717D02*
X284922D01*
G01X278780D02*
X280985D01*
G01X274843D02*
X277048D01*
G01X270906D02*
X273111D01*
G01X266969D02*
X269174D01*
G01Y141910D02*
X266969D01*
G01X273111D02*
X270906D01*
G01X277048D02*
X274843D01*
G01X280985D02*
X278780D01*
G01X284922D02*
X282717D01*
G01X288859D02*
X286655D01*
G01X292796D02*
X290592D01*
G01X296733D02*
X294529D01*
G01X300670D02*
X298466D01*
G01X304607D02*
X302403D01*
G01X308544D02*
X306340D01*
G01X312481D02*
X310277D01*
G01X316418D02*
X314214D01*
G01X320355D02*
X318151D01*
G01X324292D02*
X322088D01*
G01X328229D02*
X326025D01*
G01X332166D02*
X329962D01*
G01X336103D02*
X333899D01*
G01X340040D02*
X337836D01*
G01X343977D02*
X341773D01*
G01X347914D02*
X345710D01*
G01X269174Y141743D02*
X266969D01*
G01X273111D02*
X270906D01*
G01X277048D02*
X274843D01*
G01X280985D02*
X278780D01*
G01X284922D02*
X282717D01*
G01X288859D02*
X286655D01*
G01X292796D02*
X290592D01*
G01X296733D02*
X294529D01*
G01X300670D02*
X298466D01*
G01X304607D02*
X302403D01*
G01X308544D02*
X306340D01*
G01X312481D02*
X310277D01*
G01X316418D02*
X314214D01*
G01X320355D02*
X318151D01*
G01X324292D02*
X322088D01*
G01X328229D02*
X326025D01*
G01X332166D02*
X329962D01*
G01X336103D02*
X333899D01*
G01X340040D02*
X337836D01*
G01X343977D02*
X341773D01*
G01X347914D02*
X345710D01*
G01X345957Y141417D02*
X347667D01*
G01X342015D02*
X343725D01*
G01X338083D02*
X339793D01*
G01X334141D02*
X335851D01*
G01X330209D02*
X331919D01*
G01X326267D02*
X327977D01*
G01X322335D02*
X324045D01*
G01X318393D02*
X320103D01*
G01X314461D02*
X316171D01*
G01X310519D02*
X312229D01*
G01X306587D02*
X308297D01*
G01X302645D02*
X304355D01*
G01X298713D02*
X300423D01*
G01X294771D02*
X296481D01*
G01X290839D02*
X292549D01*
G01X286897D02*
X288607D01*
G01X282965D02*
X284675D01*
G01X279023D02*
X280733D01*
G01X275091D02*
X276801D01*
G01X271149D02*
X272859D01*
G01X267217D02*
X268927D01*
G01X345966Y141327D02*
X347658D01*
G01X342025D02*
X343716D01*
G01X338092D02*
X339784D01*
G01X334151D02*
X335842D01*
G01X330218D02*
X331910D01*
G01X326277D02*
X327968D01*
G01X322344D02*
X324036D01*
G01X318403D02*
X320094D01*
G01X314470D02*
X316162D01*
G01X310529D02*
X312220D01*
G01X306596D02*
X308288D01*
G01X302654D02*
X304346D01*
G01X298722D02*
X300414D01*
G01X294780D02*
X296472D01*
G01X290848D02*
X292540D01*
G01X286906D02*
X288598D01*
G01X282974D02*
X284666D01*
G01X279032D02*
X280724D01*
G01X275100D02*
X276792D01*
G01X271158D02*
X272850D01*
G01X267226D02*
X268918D01*
G01X268946Y141024D02*
X267198D01*
G01X272878D02*
X271130D01*
G01X276820D02*
X275072D01*
G01X280752D02*
X279004D01*
G01X284694D02*
X282946D01*
G01X288626D02*
X286878D01*
G01X292568D02*
X290820D01*
G01X296500D02*
X294752D01*
G01X300442D02*
X298694D01*
G01X304374D02*
X302626D01*
G01X308316D02*
X306568D01*
G01X312248D02*
X310500D01*
G01X316190D02*
X314442D01*
G01X320122D02*
X318374D01*
G01X324064D02*
X322316D01*
G01X327996D02*
X326248D01*
G01X331938D02*
X330190D01*
G01X335870D02*
X334122D01*
G01X339812D02*
X338064D01*
G01X343744D02*
X341996D01*
G01X347686D02*
X345938D01*
G01X345957Y140433D02*
X347667D01*
G01X342015D02*
X343725D01*
G01X338083D02*
X339793D01*
G01X334141D02*
X335851D01*
G01X330209D02*
X331919D01*
G01X326267D02*
X327977D01*
G01X322335D02*
X324045D01*
G01X318393D02*
X320103D01*
G01X314461D02*
X316171D01*
G01X310519D02*
X312229D01*
G01X306587D02*
X308297D01*
G01X302645D02*
X304355D01*
G01X298713D02*
X300423D01*
G01X294771D02*
X296481D01*
G01X290839D02*
X292549D01*
G01X286897D02*
X288607D01*
G01X282965D02*
X284675D01*
G01X279023D02*
X280733D01*
G01X275091D02*
X276801D01*
G01X271149D02*
X272859D01*
G01X267217D02*
X268927D01*
G01X268920Y140365D02*
X267224D01*
G01X272852D02*
X271156D01*
G01X276794D02*
X275098D01*
G01X280726D02*
X279030D01*
G01X284668D02*
X282972D01*
G01X288600D02*
X286904D01*
G01X292542D02*
X290846D01*
G01X296474D02*
X294778D01*
G01X300416D02*
X298720D01*
G01X304348D02*
X302652D01*
G01X308290D02*
X306594D01*
G01X312222D02*
X310526D01*
G01X316164D02*
X314468D01*
G01X320096D02*
X318400D01*
G01X324038D02*
X322342D01*
G01X327970D02*
X326274D01*
G01X331912D02*
X330216D01*
G01X335844D02*
X334148D01*
G01X339786D02*
X338090D01*
G01X343718D02*
X342022D01*
G01X347660D02*
X345964D01*
G01X268867Y140340D02*
X267277D01*
G01X272799D02*
X271209D01*
G01X276741D02*
X275151D01*
G01X280673D02*
X279083D01*
G01X284615D02*
X283025D01*
G01X288547D02*
X286957D01*
G01X292489D02*
X290899D01*
G01X296421D02*
X294831D01*
G01X300363D02*
X298773D01*
G01X304295D02*
X302705D01*
G01X308237D02*
X306647D01*
G01X312169D02*
X310579D01*
G01X316111D02*
X314521D01*
G01X320044D02*
X318453D01*
G01X323985D02*
X322395D01*
G01X327918D02*
X326327D01*
G01X331859D02*
X330269D01*
G01X335792D02*
X334201D01*
G01X339733D02*
X338143D01*
G01X343666D02*
X342075D01*
G01X347607D02*
X346017D01*
G01X345943Y140138D02*
X347681D01*
G01X342001D02*
X343740D01*
G01X338069D02*
X339807D01*
G01X334127D02*
X335866D01*
G01X330195D02*
X331933D01*
G01X326253D02*
X327992D01*
G01X322321D02*
X324059D01*
G01X318379D02*
X320118D01*
G01X314447D02*
X316185D01*
G01X310505D02*
X312244D01*
G01X306573D02*
X308311D01*
G01X302631D02*
X304370D01*
G01X298698D02*
X300437D01*
G01X294757D02*
X296496D01*
G01X290824D02*
X292563D01*
G01X286883D02*
X288622D01*
G01X282950D02*
X284689D01*
G01X279009D02*
X280748D01*
G01X275076D02*
X276815D01*
G01X271135D02*
X272874D01*
G01X267202D02*
X268941D01*
G01X345710Y139488D02*
X347914D01*
G01X341773D02*
X343977D01*
G01X337836D02*
X340040D01*
G01X333899D02*
X336103D01*
G01X329962D02*
X332166D01*
G01X326025D02*
X328229D01*
G01X322088D02*
X324292D01*
G01X318151D02*
X320355D01*
G01X314214D02*
X316418D01*
G01X310277D02*
X312481D01*
G01X306340D02*
X308544D01*
G01X302403D02*
X304607D01*
G01X298466D02*
X300670D01*
G01X294529D02*
X296733D01*
G01X290592D02*
X292796D01*
G01X286655D02*
X288859D01*
G01X282717D02*
X284922D01*
G01X278780D02*
X280985D01*
G01X274843D02*
X277048D01*
G01X270906D02*
X273111D01*
G01X266969D02*
X269174D01*
G01X346014Y139379D02*
X347610D01*
G01X342073D02*
X343668D01*
G01X338140D02*
X339736D01*
G01X334199D02*
X335794D01*
G01X330266D02*
X331862D01*
G01X326325D02*
X327920D01*
G01X322392D02*
X323988D01*
G01X318451D02*
X320046D01*
G01X314518D02*
X316114D01*
G01X310577D02*
X312172D01*
G01X306644D02*
X308239D01*
G01X302703D02*
X304298D01*
G01X298770D02*
X300365D01*
G01X294829D02*
X296424D01*
G01X290896D02*
X292491D01*
G01X286955D02*
X288550D01*
G01X283022D02*
X284617D01*
G01X279081D02*
X280676D01*
G01X275148D02*
X276743D01*
G01X271207D02*
X272802D01*
G01X267274D02*
X268869D01*
G01X272678Y138760D02*
X271340D01*
G01X280552D02*
X279214D01*
G01X288426D02*
X287088D01*
G01X296300D02*
X294962D01*
G01X304174D02*
X302836D01*
G01X312048D02*
X310710D01*
G01X319922D02*
X318584D01*
G01X327796D02*
X326458D01*
G01X335670D02*
X334332D01*
G01X343544D02*
X342206D01*
G01X272678Y137775D02*
X271340D01*
G01X280552D02*
X279214D01*
G01X288426D02*
X287088D01*
G01X296300D02*
X294962D01*
G01X304174D02*
X302836D01*
G01X312048D02*
X310710D01*
G01X319922D02*
X318584D01*
G01X327796D02*
X326458D01*
G01X335670D02*
X334332D01*
G01X343544D02*
X342206D01*
G01X342048Y137677D02*
X343702D01*
G01X334174D02*
X335828D01*
G01X326300D02*
X327954D01*
G01X318426D02*
X320080D01*
G01X310552D02*
X312206D01*
G01X302678D02*
X304332D01*
G01X294804D02*
X296458D01*
G01X286930D02*
X288584D01*
G01X279056D02*
X280710D01*
G01X271182D02*
X272836D01*
G01Y137185D02*
X271182D01*
G01X280710D02*
X279056D01*
G01X288584D02*
X286930D01*
G01X296458D02*
X294804D01*
G01X304332D02*
X302678D01*
G01X312206D02*
X310552D01*
G01X320080D02*
X318426D01*
G01X327954D02*
X326300D01*
G01X335828D02*
X334174D01*
G01X343702D02*
X342048D01*
G01X346284Y150441D02*
X346293Y150393D01*
G01X342143Y151737D02*
X342397Y151368D01*
G01X342351Y150441D02*
X342130Y150762D01*
G01X338201Y151737D02*
X338455Y151368D01*
G01X338410Y150441D02*
X338188Y150762D01*
G01X334269Y151737D02*
X334523Y151368D01*
G01X334477Y150441D02*
X334256Y150762D01*
G01X343399Y135937D02*
X343620Y135615D01*
G01X343607Y134640D02*
X343353Y135009D01*
G01X330581Y151368D02*
X330327Y151737D01*
G01X330316Y150760D02*
X330536Y150441D01*
G01X339466Y135937D02*
X339688Y135615D01*
G01X339674Y134640D02*
X339421Y135009D01*
G01X326649Y151368D02*
X326395Y151737D01*
G01X326603Y150441D02*
X326382Y150762D01*
G01X335525Y135937D02*
X335746Y135615D01*
G01X335733Y134640D02*
X335479Y135009D01*
G01X322707Y151368D02*
X322453Y151737D01*
G01X322442Y150760D02*
X322662Y150441D01*
G01X331812Y135617D02*
X331592Y135937D01*
G01X331547Y135009D02*
X331800Y134640D01*
G01X318775Y151368D02*
X318521Y151737D01*
G01X318729Y150441D02*
X318508Y150762D01*
G01X327651Y135937D02*
X327872Y135615D01*
G01X327605Y135009D02*
X327859Y134640D01*
G01X268833Y136570D02*
X267311D01*
G01X272765D02*
X271243D01*
G01X276707D02*
X275185D01*
G01X280639D02*
X279117D01*
G01X284581D02*
X283059D01*
G01X288513D02*
X286991D01*
G01X292455D02*
X290933D01*
G01X296387D02*
X294865D01*
G01X300329D02*
X298807D01*
G01X304261D02*
X302740D01*
G01X308203D02*
X306681D01*
G01X312135D02*
X310614D01*
G01X316077D02*
X314555D01*
G01X320009D02*
X318488D01*
G01X323951D02*
X322429D01*
G01X327883D02*
X326362D01*
G01X331825D02*
X330303D01*
G01X335757D02*
X334236D01*
G01X339699D02*
X338177D01*
G01X343631D02*
X342110D01*
G01X347573D02*
X346051D01*
G01X268844Y136551D02*
X267300D01*
G01X272776D02*
X271232D01*
G01X276718D02*
X275174D01*
G01X280650D02*
X279107D01*
G01X284592D02*
X283048D01*
G01X288524D02*
X286981D01*
G01X292466D02*
X290922D01*
G01X296398D02*
X294855D01*
G01X300340D02*
X298796D01*
G01X304272D02*
X302729D01*
G01X308214D02*
X306670D01*
G01X312146D02*
X310603D01*
G01X316088D02*
X314544D01*
G01X320020D02*
X318477D01*
G01X323962D02*
X322418D01*
G01X327894D02*
X326351D01*
G01X331836D02*
X330292D01*
G01X335768D02*
X334225D01*
G01X339710D02*
X338166D01*
G01X343642D02*
X342099D01*
G01X347584D02*
X346040D01*
G01X270906Y136515D02*
X270592D01*
G01X269489D02*
X269174D01*
G01X273426D02*
X273111D01*
G01X274843D02*
X274529D01*
G01X277363D02*
X277048D01*
G01X278780D02*
X278466D01*
G01X281300D02*
X280985D01*
G01X282717D02*
X282403D01*
G01X285237D02*
X284922D01*
G01X286655D02*
X286340D01*
G01X289174D02*
X288859D01*
G01X290592D02*
X290277D01*
G01X293111D02*
X292796D01*
G01X294529D02*
X294214D01*
G01X297048D02*
X296733D01*
G01X298466D02*
X298151D01*
G01X302403D02*
X302088D01*
G01X300985D02*
X300670D01*
G01X304922D02*
X304607D01*
G01X306340D02*
X306025D01*
G01X308859D02*
X308544D01*
G01X310277D02*
X309962D01*
G01X312796D02*
X312481D01*
G01X314214D02*
X313899D01*
G01X316733D02*
X316418D01*
G01X318151D02*
X317836D01*
G01X320670D02*
X320355D01*
G01X322088D02*
X321773D01*
G01X324607D02*
X324292D01*
G01X326025D02*
X325710D01*
G01X328544D02*
X328229D01*
G01X329962D02*
X329647D01*
G01X332481D02*
X332166D01*
G01X333899D02*
X333584D01*
G01X336418D02*
X336103D01*
G01X337836D02*
X337521D01*
G01X340355D02*
X340040D01*
G01X341773D02*
X341458D01*
G01X344292D02*
X343977D01*
G01X345710D02*
X345395D01*
G01X269253Y135984D02*
X266891D01*
G01X273190D02*
X270828D01*
G01X277127D02*
X274765D01*
G01X281064D02*
X278702D01*
G01X285001D02*
X282639D01*
G01X288938D02*
X286576D01*
G01X292875D02*
X290513D01*
G01X296812D02*
X294450D01*
G01X300749D02*
X298387D01*
G01X304686D02*
X302324D01*
G01X308623D02*
X306261D01*
G01X312560D02*
X310198D01*
G01X316497D02*
X314135D01*
G01X320434D02*
X318072D01*
G01X324371D02*
X322009D01*
G01X328308D02*
X325946D01*
G01X332245D02*
X329883D01*
G01X336182D02*
X333820D01*
G01X340119D02*
X337757D01*
G01X344056D02*
X341694D01*
G01X347993D02*
X345631D01*
G01X268600Y135937D02*
X267544D01*
G01X272532D02*
X271476D01*
G01X276474D02*
X275418D01*
G01X280406D02*
X279350D01*
G01X284348D02*
X283292D01*
G01X288280D02*
X287224D01*
G01X292222D02*
X291166D01*
G01X296155D02*
X295098D01*
G01X300096D02*
X299040D01*
G01X304029D02*
X302972D01*
G01X307970D02*
X306914D01*
G01X311903D02*
X310846D01*
G01X315844D02*
X314788D01*
G01X319777D02*
X318720D01*
G01X323718D02*
X322662D01*
G01X327651D02*
X326594D01*
G01X331592D02*
X330536D01*
G01X335525D02*
X334468D01*
G01X339466D02*
X338410D01*
G01X343399D02*
X342342D01*
G01X347340D02*
X346284D01*
G01X346064Y135615D02*
X347560D01*
G01X342122D02*
X343619D01*
G01X338190D02*
X339686D01*
G01X334248D02*
X335745D01*
G01X330316D02*
X331812D01*
G01X326374D02*
X327870D01*
G01X322442D02*
X323938D01*
G01X318500D02*
X319996D01*
G01X314568D02*
X316064D01*
G01X310626D02*
X312122D01*
G01X306694D02*
X308190D01*
G01X302752D02*
X304248D01*
G01X298820D02*
X300316D01*
G01X294878D02*
X296374D01*
G01X290946D02*
X292442D01*
G01X287004D02*
X288500D01*
G01X283072D02*
X284568D01*
G01X279130D02*
X280626D01*
G01X275198D02*
X276694D01*
G01X271256D02*
X272752D01*
G01X267324D02*
X268820D01*
G01X346062Y135605D02*
X347562D01*
G01X342121D02*
X343620D01*
G01X338188D02*
X339688D01*
G01X334247D02*
X335746D01*
G01X330314D02*
X331814D01*
G01X326373D02*
X327872D01*
G01X322440D02*
X323940D01*
G01X318499D02*
X319998D01*
G01X314566D02*
X316066D01*
G01X310625D02*
X312124D01*
G01X306692D02*
X308192D01*
G01X302751D02*
X304250D01*
G01X298818D02*
X300318D01*
G01X294876D02*
X296376D01*
G01X290944D02*
X292444D01*
G01X287002D02*
X288502D01*
G01X283070D02*
X284570D01*
G01X279128D02*
X280628D01*
G01X275196D02*
X276696D01*
G01X271254D02*
X272754D01*
G01X267322D02*
X268822D01*
G01X272836Y135413D02*
X271182D01*
G01X280710D02*
X279056D01*
G01X288584D02*
X286930D01*
G01X296458D02*
X294804D01*
G01X304332D02*
X302678D01*
G01X312206D02*
X310552D01*
G01X320080D02*
X318426D01*
G01X327954D02*
X326300D01*
G01X335828D02*
X334174D01*
G01X343702D02*
X342048D01*
G01X345802Y135117D02*
X347822D01*
G01X341860D02*
X343881D01*
G01X337928D02*
X339948D01*
G01X333986D02*
X336007D01*
G01X330054D02*
X332074D01*
G01X326112D02*
X328133D01*
G01X322180D02*
X324200D01*
G01X318238D02*
X320259D01*
G01X314306D02*
X316326D01*
G01X310364D02*
X312385D01*
G01X306431D02*
X308452D01*
G01X302490D02*
X304511D01*
G01X298557D02*
X300578D01*
G01X294616D02*
X296637D01*
G01X290683D02*
X292704D01*
G01X286742D02*
X288763D01*
G01X282809D02*
X284830D01*
G01X278868D02*
X280889D01*
G01X274935D02*
X276956D01*
G01X270994D02*
X273015D01*
G01X267061D02*
X269082D01*
G01X343977Y135019D02*
X344292D01*
G01X340040D02*
X340355D01*
G01X336103D02*
X336418D01*
G01X328229D02*
X328544D01*
G01X320355D02*
X320670D01*
G01X316418D02*
X316733D01*
G01X312481D02*
X312796D01*
G01X308544D02*
X308859D01*
G01X304607D02*
X304922D01*
G01X300670D02*
X300985D01*
G01X296733D02*
X297048D01*
G01X292796D02*
X293111D01*
G01X288859D02*
X289174D01*
G01X284922D02*
X285237D01*
G01X280985D02*
X281300D01*
G01X277048D02*
X277363D01*
G01X273111D02*
X273426D01*
G01X269174D02*
X269489D01*
G01X270906D02*
X270592D01*
G01X274843D02*
X274529D01*
G01X278780D02*
X278466D01*
G01X282717D02*
X282403D01*
G01X286655D02*
X286340D01*
G01X290592D02*
X290277D01*
G01X294529D02*
X294214D01*
G01X298466D02*
X298151D01*
G01X302403D02*
X302088D01*
G01X306340D02*
X306025D01*
G01X310277D02*
X309962D01*
G01X314214D02*
X313899D01*
G01X318151D02*
X317836D01*
G01X322088D02*
X321773D01*
G01X324607D02*
X324292D01*
G01X326025D02*
X325710D01*
G01X329962D02*
X329647D01*
G01X332481D02*
X332166D01*
G01X333899D02*
X333584D01*
G01X337836D02*
X337521D01*
G01X341773D02*
X341458D01*
G01X345710D02*
X345395D01*
G01X346329Y135009D02*
X347295D01*
G01X342388D02*
X343353D01*
G01X338455D02*
X339421D01*
G01X334514D02*
X335479D01*
G01X330581D02*
X331547D01*
G01X326640D02*
X327605D01*
G01X322707D02*
X323673D01*
G01X318766D02*
X319731D01*
G01X314833D02*
X315799D01*
G01X310892D02*
X311857D01*
G01X306959D02*
X307925D01*
G01X303018D02*
X303983D01*
G01X299085D02*
X300051D01*
G01X295144D02*
X296109D01*
G01X291211D02*
X292177D01*
G01X287270D02*
X288235D01*
G01X283337D02*
X284303D01*
G01X279396D02*
X280361D01*
G01X275463D02*
X276429D01*
G01X271521D02*
X272487D01*
G01X267589D02*
X268555D01*
G01X342048Y134921D02*
X343702D01*
G01X334174D02*
X335828D01*
G01X326300D02*
X327954D01*
G01X318426D02*
X320080D01*
G01X310552D02*
X312206D01*
G01X302678D02*
X304332D01*
G01X294804D02*
X296458D01*
G01X286930D02*
X288584D01*
G01X279056D02*
X280710D01*
G01X271182D02*
X272836D01*
G01X345395Y134822D02*
X348229D01*
G01X341458D02*
X344292D01*
G01X337521D02*
X340355D01*
G01X333584D02*
X336418D01*
G01X329647D02*
X332481D01*
G01X325710D02*
X328544D01*
G01X321773D02*
X324607D01*
G01X317836D02*
X320670D01*
G01X313899D02*
X316733D01*
G01X309962D02*
X312796D01*
G01X306025D02*
X308859D01*
G01X302088D02*
X304922D01*
G01X298151D02*
X300985D01*
G01X294214D02*
X297048D01*
G01X290277D02*
X293111D01*
G01X286340D02*
X289174D01*
G01X282403D02*
X285237D01*
G01X278466D02*
X281300D01*
G01X274529D02*
X277363D01*
G01X270592D02*
X273426D01*
G01X345395Y134665D02*
X345985D01*
G01X343702D02*
X344292D01*
G01X341458D02*
X342048D01*
G01X339765D02*
X340355D01*
G01X337521D02*
X338111D01*
G01X335828D02*
X336418D01*
G01X333584D02*
X334174D01*
G01X331891D02*
X332481D01*
G01X329647D02*
X330237D01*
G01X327954D02*
X328544D01*
G01X325710D02*
X326300D01*
G01X324017D02*
X324607D01*
G01X321773D02*
X322363D01*
G01X320080D02*
X320670D01*
G01X317836D02*
X318426D01*
G01X316143D02*
X316733D01*
G01X313899D02*
X314489D01*
G01X312206D02*
X312796D01*
G01X309962D02*
X310552D01*
G01X308269D02*
X308859D01*
G01X306025D02*
X306615D01*
G01X304332D02*
X304922D01*
G01X302088D02*
X302678D01*
G01X300395D02*
X300985D01*
G01X298151D02*
X298741D01*
G01X296458D02*
X297048D01*
G01X294214D02*
X294804D01*
G01X292521D02*
X293111D01*
G01X290277D02*
X290867D01*
G01X288584D02*
X289174D01*
G01X286340D02*
X286930D01*
G01X284647D02*
X285237D01*
G01X282403D02*
X282993D01*
G01X280710D02*
X281300D01*
G01X278466D02*
X279056D01*
G01X276773D02*
X277363D01*
G01X274529D02*
X275119D01*
G01X272836D02*
X273426D01*
G01X270592D02*
X271182D01*
G01X268899D02*
X269489D01*
G01X268808Y134640D02*
X267335D01*
G01X272741D02*
X271268D01*
G01X276682D02*
X275209D01*
G01X280615D02*
X279142D01*
G01X284556D02*
X283083D01*
G01X288489D02*
X287016D01*
G01X292430D02*
X290957D01*
G01X296363D02*
X294890D01*
G01X300304D02*
X298831D01*
G01X304237D02*
X302764D01*
G01X308178D02*
X306705D01*
G01X312111D02*
X310638D01*
G01X316052D02*
X314579D01*
G01X319985D02*
X318512D01*
G01X323926D02*
X322453D01*
G01X327859D02*
X326386D01*
G01X331800D02*
X330327D01*
G01X335733D02*
X334260D01*
G01X339674D02*
X338201D01*
G01X343607D02*
X342134D01*
G01X347548D02*
X346075D01*
G01X346062Y134621D02*
X347562D01*
G01X342121D02*
X343620D01*
G01X338188D02*
X339688D01*
G01X334247D02*
X335746D01*
G01X330314D02*
X331814D01*
G01X326373D02*
X327872D01*
G01X322440D02*
X323940D01*
G01X318499D02*
X319998D01*
G01X314566D02*
X316066D01*
G01X310625D02*
X312124D01*
G01X306692D02*
X308192D01*
G01X302751D02*
X304250D01*
G01X298818D02*
X300318D01*
G01X294876D02*
X296376D01*
G01X290944D02*
X292444D01*
G01X287002D02*
X288502D01*
G01X283070D02*
X284570D01*
G01X279128D02*
X280628D01*
G01X275196D02*
X276696D01*
G01X271254D02*
X272754D01*
G01X267322D02*
X268822D01*
G01X269077Y134231D02*
X267066D01*
G01X273010D02*
X270999D01*
G01X276951D02*
X274940D01*
G01X280884D02*
X278873D01*
G01X284825D02*
X282814D01*
G01X288758D02*
X286747D01*
G01X292700D02*
X290688D01*
G01X296632D02*
X294621D01*
G01X300574D02*
X298562D01*
G01X304506D02*
X302495D01*
G01X308448D02*
X306436D01*
G01X312380D02*
X310369D01*
G01X316322D02*
X314310D01*
G01X320254D02*
X318243D01*
G01X324196D02*
X322184D01*
G01X328128D02*
X326117D01*
G01X332070D02*
X330058D01*
G01X336002D02*
X333991D01*
G01X339944D02*
X337932D01*
G01X343876D02*
X341865D01*
G01X347818D02*
X345806D01*
G01X269489Y133996D02*
X268899D01*
G01X271182D02*
X270592D01*
G01X273426D02*
X272836D01*
G01X275119D02*
X274529D01*
G01X277363D02*
X276773D01*
G01X279056D02*
X278466D01*
G01X281300D02*
X280710D01*
G01X282993D02*
X282403D01*
G01X285237D02*
X284647D01*
G01X286930D02*
X286340D01*
G01X289174D02*
X288584D01*
G01X290867D02*
X290277D01*
G01X293111D02*
X292521D01*
G01X294804D02*
X294214D01*
G01X297048D02*
X296458D01*
G01X298741D02*
X298151D01*
G01X300985D02*
X300395D01*
G01X302678D02*
X302088D01*
G01X304922D02*
X304332D01*
G01X306615D02*
X306025D01*
G01X308859D02*
X308269D01*
G01X310552D02*
X309962D01*
G01X312796D02*
X312206D01*
G01X314489D02*
X313899D01*
G01X316733D02*
X316143D01*
G01X318426D02*
X317836D01*
G01X320670D02*
X320080D01*
G01X322363D02*
X321773D01*
G01X324607D02*
X324017D01*
G01X326300D02*
X325710D01*
G01X328544D02*
X327954D01*
G01X330237D02*
X329647D01*
G01X332481D02*
X331891D01*
G01X334174D02*
X333584D01*
G01X336418D02*
X335828D01*
G01X338111D02*
X337521D01*
G01X340355D02*
X339765D01*
G01X342048D02*
X341458D01*
G01X344292D02*
X343702D01*
G01X345985D02*
X345395D01*
G01X273426Y133838D02*
X270592D01*
G01X277363D02*
X274529D01*
G01X281300D02*
X278466D01*
G01X285237D02*
X282403D01*
G01X289174D02*
X286340D01*
G01X293111D02*
X290277D01*
G01X297048D02*
X294214D01*
G01X300985D02*
X298151D01*
G01X304922D02*
X302088D01*
G01X308859D02*
X306025D01*
G01X312796D02*
X309962D01*
G01X316733D02*
X313899D01*
G01X320670D02*
X317836D01*
G01X324607D02*
X321773D01*
G01X328544D02*
X325710D01*
G01X332481D02*
X329647D01*
G01X336418D02*
X333584D01*
G01X340355D02*
X337521D01*
G01X344292D02*
X341458D01*
G01X348229D02*
X345395D01*
G01X268899Y133740D02*
X267245D01*
G01X276773D02*
X275119D01*
G01X284647D02*
X282993D01*
G01X292521D02*
X290867D01*
G01X300395D02*
X298741D01*
G01X308269D02*
X306615D01*
G01X316143D02*
X314489D01*
G01X324017D02*
X322363D01*
G01X331891D02*
X330237D01*
G01X339765D02*
X338111D01*
G01X347639D02*
X345985D01*
G01Y133248D02*
X347639D01*
G01X338111D02*
X339765D01*
G01X330237D02*
X331891D01*
G01X322363D02*
X324017D01*
G01X314489D02*
X316143D01*
G01X306615D02*
X308269D01*
G01X298741D02*
X300395D01*
G01X290867D02*
X292521D01*
G01X282993D02*
X284647D01*
G01X275119D02*
X276773D01*
G01X267245D02*
X268899D01*
G01X345395Y132342D02*
X348229D01*
G01X341458D02*
X344292D01*
G01X337521D02*
X340355D01*
G01X333584D02*
X336418D01*
G01X329647D02*
X332481D01*
G01X325710D02*
X328544D01*
G01X321773D02*
X324607D01*
G01X317836D02*
X320670D01*
G01X313899D02*
X316733D01*
G01X309962D02*
X312796D01*
G01X306025D02*
X308859D01*
G01X302088D02*
X304922D01*
G01X298151D02*
X300985D01*
G01X294214D02*
X297048D01*
G01X290277D02*
X293111D01*
G01X286340D02*
X289174D01*
G01X282403D02*
X285237D01*
G01X278466D02*
X281300D01*
G01X274529D02*
X277363D01*
G01X270592D02*
X273426D01*
G01X345985Y131476D02*
X347639D01*
G01X338111D02*
X339765D01*
G01X330237D02*
X331891D01*
G01X322363D02*
X324017D01*
G01X314489D02*
X316143D01*
G01X306615D02*
X308269D01*
G01X298741D02*
X300395D01*
G01X290867D02*
X292521D01*
G01X282993D02*
X284647D01*
G01X275119D02*
X276773D01*
G01X267245D02*
X268899D01*
G01X329883Y131082D02*
X332245D01*
G01X325946D02*
X328308D01*
G01X322009D02*
X324371D01*
G01X318072D02*
X320434D01*
G01X269253D02*
X266891D01*
G01X273190D02*
X270828D01*
G01X277127D02*
X274765D01*
G01X281064D02*
X278702D01*
G01X285001D02*
X282639D01*
G01X288938D02*
X286576D01*
G01X292875D02*
X290513D01*
G01X296812D02*
X294450D01*
G01X300749D02*
X298387D01*
G01X304686D02*
X302324D01*
G01X308623D02*
X306261D01*
G01X312560D02*
X310198D01*
G01X316497D02*
X314135D01*
G01X336182D02*
X333820D01*
G01X340119D02*
X337757D01*
G01X344056D02*
X341694D01*
G01X347993D02*
X345631D01*
G01X268899Y130984D02*
X267245D01*
G01X276773D02*
X275119D01*
G01X284647D02*
X282993D01*
G01X292521D02*
X290867D01*
G01X300395D02*
X298741D01*
G01X308269D02*
X306615D01*
G01X316143D02*
X314489D01*
G01X324017D02*
X322363D01*
G01X331891D02*
X330237D01*
G01X339765D02*
X338111D01*
G01X347639D02*
X345985D01*
G01X268741Y130885D02*
X267403D01*
G01X276615D02*
X275277D01*
G01X284489D02*
X283151D01*
G01X292363D02*
X291025D01*
G01X300237D02*
X298899D01*
G01X308111D02*
X306773D01*
G01X315985D02*
X314647D01*
G01X323859D02*
X322521D01*
G01X331733D02*
X330395D01*
G01X339607D02*
X338269D01*
G01X347481D02*
X346143D01*
G01X345631Y129901D02*
X347993D01*
G01X341694D02*
X344056D01*
G01X337757D02*
X340119D01*
G01X333820D02*
X336182D01*
G01X329883D02*
X332245D01*
G01X325946D02*
X328308D01*
G01X322009D02*
X324371D01*
G01X318072D02*
X320434D01*
G01X314135D02*
X316497D01*
G01X310198D02*
X312560D01*
G01X306261D02*
X308623D01*
G01X302324D02*
X304686D01*
G01X298387D02*
X300749D01*
G01X294450D02*
X296812D01*
G01X290513D02*
X292875D01*
G01X286576D02*
X288938D01*
G01X282639D02*
X285001D01*
G01X278702D02*
X281064D01*
G01X274765D02*
X277127D01*
G01X270828D02*
X273190D01*
G01X266891D02*
X269253D01*
G01X346812Y123011D02*
X366497D01*
G01X323190D02*
X342875D01*
G01X299568D02*
X319253D01*
G01X275946D02*
X295631D01*
G01X342351Y150441D02*
X342361Y150393D01*
G01X343399Y135937D02*
X343389Y135984D01*
G01X338410Y150441D02*
X338419Y150393D01*
G01X339466Y135937D02*
X339457Y135984D01*
G01X334477Y150441D02*
X334487Y150393D01*
G01X335525Y135937D02*
X335515Y135984D01*
G01X330545Y150393D02*
X330536Y150441D01*
G01X331583Y135984D02*
X331592Y135937D01*
G01X326603Y150441D02*
X326613Y150393D01*
G01X327651Y135937D02*
X327641Y135984D01*
G01X322671Y150393D02*
X322662Y150441D01*
G01X323709Y135984D02*
X323718Y135937D01*
G01X318729Y150441D02*
X318739Y150393D01*
G01X314579Y151737D02*
X314833Y151368D01*
G01X314788Y150441D02*
X314566Y150762D01*
G01X323938Y135617D02*
X323718Y135937D01*
G01X323673Y135009D02*
X323926Y134640D01*
G01X310647Y151737D02*
X310901Y151368D01*
G01X310855Y150441D02*
X310634Y150762D01*
G01X319777Y135937D02*
X319998Y135615D01*
G01X319731Y135009D02*
X319985Y134640D01*
G01X306705Y151737D02*
X306959Y151368D01*
G01X306914Y150441D02*
X306692Y150762D01*
G01X315844Y135937D02*
X316066Y135615D01*
G01X316052Y134640D02*
X315799Y135009D01*
G01X302773Y151737D02*
X303027Y151368D01*
G01X302981Y150441D02*
X302760Y150762D01*
G01X311903Y135937D02*
X312124Y135615D01*
G01X312111Y134640D02*
X311857Y135009D01*
G01X298831Y151737D02*
X299085Y151368D01*
G01X299040Y150441D02*
X298818Y150762D01*
G01X307970Y135937D02*
X308192Y135615D01*
G01X308178Y134640D02*
X307925Y135009D01*
G01X294899Y151737D02*
X295153Y151368D01*
G01X295107Y150441D02*
X294886Y150762D01*
G01X304029Y135937D02*
X304250Y135615D01*
G01X304237Y134640D02*
X303983Y135009D01*
G01X290957Y151737D02*
X291211Y151368D01*
G01X291166Y150441D02*
X290944Y150762D01*
G01X300096Y135937D02*
X300318Y135615D01*
G01X300304Y134640D02*
X300051Y135009D01*
G01X287025Y151737D02*
X287279Y151368D01*
G01X287233Y150441D02*
X287012Y150762D01*
G01X346293Y135984D02*
X346284Y135937D01*
G01X342352Y135984D02*
X342342Y135937D01*
G01X345966Y145050D02*
X346017Y146037D01*
G01X346014Y146999D02*
X345964Y146012D01*
G01X343668Y139379D02*
X343718Y140365D01*
G01X343716Y141327D02*
X343666Y140340D01*
G01X342034Y145050D02*
X342084Y146037D01*
G01X342082Y146999D02*
X342032Y146012D01*
G01X339736Y139379D02*
X339786Y140365D01*
G01X339784Y141327D02*
X339733Y140340D01*
G01X338092Y145050D02*
X338143Y146037D01*
G01X338140Y146999D02*
X338090Y146012D01*
G01X335794Y139379D02*
X335844Y140365D01*
G01X335842Y141327D02*
X335792Y140340D01*
G01X334160Y145050D02*
X334210Y146037D01*
G01X334208Y146999D02*
X334158Y146012D01*
G01X345806Y134231D02*
X345943Y140138D01*
G01X345938Y141024D02*
X345802Y135117D01*
G01X343754Y145353D02*
X343890Y151260D01*
G01X343885Y152147D02*
X343749Y146239D01*
G01X341865Y134231D02*
X342001Y140138D01*
G01X341996Y141024D02*
X341860Y135117D01*
G01X339812Y145353D02*
X339948Y151260D01*
G01X339944Y152147D02*
X339807Y146239D01*
G01X337932Y134231D02*
X338069Y140138D01*
G01X338064Y141024D02*
X337928Y135117D01*
G01X335880Y145353D02*
X336016Y151260D01*
G01X336011Y152147D02*
X335875Y146239D01*
G01X333991Y134231D02*
X334127Y140138D01*
G01X334122Y141024D02*
X333986Y135117D01*
G01X346316Y150393D02*
X346329Y151368D01*
G01X343366Y135984D02*
X343353Y135009D01*
G01X342384Y150393D02*
X342397Y151368D01*
G01X339434Y135984D02*
X339421Y135009D01*
G01X338442Y150393D02*
X338455Y151368D01*
G01X335492Y135984D02*
X335479Y135009D01*
G01X334510Y150393D02*
X334523Y151368D01*
G01X331560Y135984D02*
X331547Y135009D01*
G01X346812Y128523D02*
Y123011D01*
G01X346418Y155492D02*
Y156476D01*
G01Y130885D02*
Y129901D01*
G01X346143Y130965D02*
Y129901D01*
G01Y156476D02*
Y155412D01*
G01X346064Y135617D02*
Y134627D01*
G01Y151750D02*
Y150760D01*
G01X345985Y151555D02*
Y156396D01*
G01Y129981D02*
Y134822D01*
G01X345788Y133840D02*
Y134824D01*
G01Y151553D02*
Y152538D01*
G01X345710Y152539D02*
Y133838D01*
G01X345631Y135984D02*
Y129901D01*
G01Y156476D02*
Y150393D01*
G01X345434Y134822D02*
Y133838D01*
G01Y152539D02*
Y151555D01*
G01X345429Y152539D02*
Y151555D01*
G01X345395Y136515D02*
Y132342D01*
G01Y154035D02*
Y149862D01*
G01X344292D02*
Y154035D01*
G01Y132342D02*
Y136515D01*
G01X344258Y152539D02*
Y151555D01*
G01X344253Y134822D02*
Y133838D01*
G01X344248Y134822D02*
Y133838D01*
G01X344056Y135984D02*
Y129901D01*
G01Y156476D02*
Y150393D01*
G01X343977Y133838D02*
Y152539D01*
G01X343903Y152538D02*
Y151553D01*
G01X343894Y134824D02*
Y133840D01*
G01X343702Y147698D02*
Y152539D01*
G01Y133838D02*
Y138680D01*
G01X343628Y150760D02*
Y151750D01*
G01X343618Y134627D02*
Y135617D01*
G01X343544Y138760D02*
Y137696D01*
G01Y148681D02*
Y147618D01*
G01X343269D02*
Y148602D01*
G01Y138760D02*
Y137775D01*
G01X342875Y128523D02*
Y123011D01*
G01X342481Y147618D02*
Y148602D01*
G01Y137775D02*
Y138760D01*
G01X342206D02*
Y137696D01*
G01Y148681D02*
Y147618D01*
G01X342132Y151750D02*
Y150760D01*
G01X342122Y135617D02*
Y134627D01*
G01X342048Y147698D02*
Y152539D01*
G01Y133838D02*
Y138680D01*
G01X341856Y151553D02*
Y152538D01*
G01X341847Y133840D02*
Y134824D01*
G01X341773Y152539D02*
Y133838D01*
G01X341694Y135984D02*
Y129901D01*
G01Y156476D02*
Y150393D01*
G01X341502Y152539D02*
Y151555D01*
G01X341497Y152539D02*
Y151555D01*
G01X341492Y134822D02*
Y133838D01*
G01X341458Y136515D02*
Y132342D01*
G01Y154035D02*
Y149862D01*
G01X340355D02*
Y154035D01*
G01Y132342D02*
Y136515D01*
G01X340321Y134822D02*
Y133838D01*
G01X340316Y134822D02*
Y133838D01*
G01Y152539D02*
Y151555D01*
G01X340119Y135984D02*
Y129901D01*
G01Y156476D02*
Y150393D01*
G01X340040Y133838D02*
Y152539D01*
G01X339962Y134824D02*
Y133840D01*
G01Y152538D02*
Y151553D01*
G01X339765Y151555D02*
Y156396D01*
G01Y129981D02*
Y134822D01*
G01X339725Y128523D02*
Y123011D01*
G01X339686Y150760D02*
Y151750D01*
G01Y134627D02*
Y135617D01*
G01X339607Y130965D02*
Y129901D01*
G01Y156476D02*
Y155412D01*
G01X339332Y130885D02*
Y129901D01*
G01Y156476D02*
Y155492D01*
G01X338544D02*
Y156476D01*
G01Y130885D02*
Y129901D01*
G01X338269Y130965D02*
Y129901D01*
G01Y156476D02*
Y155412D01*
G01X338190Y135617D02*
Y134627D01*
G01Y151750D02*
Y150760D01*
G01X338111Y151555D02*
Y156396D01*
G01Y129981D02*
Y134822D01*
G01X337914Y133840D02*
Y134824D01*
G01Y151553D02*
Y152538D01*
G01X337836Y152539D02*
Y133838D01*
G01X337757Y135984D02*
Y129901D01*
G01Y156476D02*
Y150393D01*
G01X337560Y134822D02*
Y133838D01*
G01Y152539D02*
Y151555D01*
G01X337555Y152539D02*
Y151555D01*
G01X337521Y136515D02*
Y132342D01*
G01Y154035D02*
Y149862D01*
G01X336418D02*
Y154035D01*
G01Y132342D02*
Y136515D01*
G01X336384Y152539D02*
Y151555D01*
G01X336379Y134822D02*
Y133838D01*
G01X336374Y134822D02*
Y133838D01*
G01X336182Y135984D02*
Y129901D01*
G01Y156476D02*
Y150393D01*
G01X336103Y133838D02*
Y152539D01*
G01X336029Y152538D02*
Y151553D01*
G01X336020Y134824D02*
Y133840D01*
G01X335828Y147698D02*
Y152539D01*
G01Y133838D02*
Y138680D01*
G01X335754Y150760D02*
Y151750D01*
G01X335744Y134627D02*
Y135617D01*
G01X335670Y138760D02*
Y137696D01*
G01Y148681D02*
Y147618D01*
G01X335395D02*
Y148602D01*
G01Y138760D02*
Y137775D01*
G01X334607Y147618D02*
Y148602D01*
G01Y137775D02*
Y138760D01*
G01X334332D02*
Y137696D01*
G01Y148681D02*
Y147618D01*
G01X334258Y151750D02*
Y150760D01*
G01X334248Y135617D02*
Y134627D01*
G01X334174Y147698D02*
Y152539D01*
G01Y133838D02*
Y138680D01*
G01X333982Y151553D02*
Y152538D01*
G01X333973Y133840D02*
Y134824D01*
G01X333899Y152539D02*
Y133838D01*
G01X333820Y135984D02*
Y129901D01*
G01Y156476D02*
Y150393D01*
G01X333628Y152539D02*
Y151555D01*
G01X333623Y152539D02*
Y151555D01*
G01X333618Y134822D02*
Y133838D01*
G01X333584Y136515D02*
Y132342D01*
G01Y154035D02*
Y149862D01*
G01X332481D02*
Y154035D01*
G01Y132342D02*
Y136515D01*
G01X332447Y134822D02*
Y133838D01*
G01X332442Y134822D02*
Y133838D01*
G01Y152539D02*
Y151555D01*
G01X332245Y135984D02*
Y129901D01*
G01Y156476D02*
Y150393D01*
G01X332166Y133838D02*
Y152539D01*
G01X332088Y134824D02*
Y133840D01*
G01Y152538D02*
Y151553D01*
G01X331891Y151555D02*
Y156396D01*
G01Y129981D02*
Y134822D01*
G01X331812Y150760D02*
Y151750D01*
G01Y134627D02*
Y135617D01*
G01X331733Y130965D02*
Y129901D01*
G01Y156476D02*
Y155412D01*
G01X331458Y129901D02*
Y130885D01*
G01Y156476D02*
Y155492D01*
G01X330670Y130885D02*
Y129901D01*
G01Y156476D02*
Y155492D01*
G01X346329Y135009D02*
X346316Y135984D01*
G01X343362Y151368D02*
X343375Y150393D01*
G01X342388Y135009D02*
X342375Y135984D01*
G01X339421Y151368D02*
X339434Y150393D01*
G01X338455Y135009D02*
X338442Y135984D01*
G01X335488Y151368D02*
X335501Y150393D01*
G01X334514Y135009D02*
X334500Y135984D01*
G01X331547Y151368D02*
X331560Y150393D01*
G01X330581Y135009D02*
X330568Y135984D01*
G01X345943Y146239D02*
X345806Y152147D01*
G01X345802Y151260D02*
X345938Y145353D01*
G01X343881Y135117D02*
X343744Y141024D01*
G01X343740Y140138D02*
X343876Y134231D01*
G01X342010Y146239D02*
X341874Y152147D01*
G01X341869Y151260D02*
X342005Y145353D01*
G01X339948Y135117D02*
X339812Y141024D01*
G01X339807Y140138D02*
X339944Y134231D01*
G01X338069Y146239D02*
X337932Y152147D01*
G01X337928Y151260D02*
X338064Y145353D01*
G01X336007Y135117D02*
X335870Y141024D01*
G01X335866Y140138D02*
X336002Y134231D01*
G01X334136Y146239D02*
X334000Y152147D01*
G01X333995Y151260D02*
X334131Y145353D01*
G01X332074Y135117D02*
X331938Y141024D01*
G01X331933Y140138D02*
X332070Y134231D01*
G01X330195Y146239D02*
X330058Y152147D01*
G01X330054Y151260D02*
X330190Y145353D01*
G01X346017Y140340D02*
X345966Y141327D01*
G01X345964Y140365D02*
X346014Y139379D01*
G01X343728Y146012D02*
X343677Y146999D01*
G01X343675Y146037D02*
X343725Y145050D01*
G01X342075Y140340D02*
X342025Y141327D01*
G01X342022Y140365D02*
X342073Y139379D01*
G01X339786Y146012D02*
X339736Y146999D01*
G01X339733Y146037D02*
X339784Y145050D01*
G01X338143Y140340D02*
X338092Y141327D01*
G01X338090Y140365D02*
X338140Y139379D01*
G01X335854Y146012D02*
X335803Y146999D01*
G01X335801Y146037D02*
X335851Y145050D01*
G01X334201Y140340D02*
X334151Y141327D01*
G01X334148Y140365D02*
X334199Y139379D01*
G01X331912Y146012D02*
X331862Y146999D01*
G01X331859Y146037D02*
X331910Y145050D01*
G01X330269Y140340D02*
X330218Y141327D01*
G01X330216Y140365D02*
X330266Y139379D01*
G01X327980Y146012D02*
X327929Y146999D01*
G01X327927Y146037D02*
X327977Y145050D01*
G01X319777Y135937D02*
X319767Y135984D01*
G01X314788Y150441D02*
X314797Y150393D01*
G01X315844Y135937D02*
X315835Y135984D01*
G01X310855Y150441D02*
X310865Y150393D01*
G01X311903Y135937D02*
X311893Y135984D01*
G01X306914Y150441D02*
X306923Y150393D01*
G01X307970Y135937D02*
X307961Y135984D01*
G01X302981Y150441D02*
X302991Y150393D01*
G01X304029Y135937D02*
X304019Y135984D01*
G01X299040Y150441D02*
X299049Y150393D01*
G01X300096Y135937D02*
X300087Y135984D01*
G01X295107Y150441D02*
X295117Y150393D01*
G01X296155Y135937D02*
X296145Y135984D01*
G01X296155Y135937D02*
X296376Y135615D01*
G01X296363Y134640D02*
X296109Y135009D01*
G01X283083Y151737D02*
X283337Y151368D01*
G01X283292Y150441D02*
X283070Y150762D01*
G01X292222Y135937D02*
X292444Y135615D01*
G01X292430Y134640D02*
X292177Y135009D01*
G01X279151Y151737D02*
X279405Y151368D01*
G01X279359Y150441D02*
X279138Y150762D01*
G01X288280Y135937D02*
X288502Y135615D01*
G01X288489Y134640D02*
X288235Y135009D01*
G01X275209Y151737D02*
X275463Y151368D01*
G01X275418Y150441D02*
X275196Y150762D01*
G01X284348Y135937D02*
X284569Y135615D01*
G01X284556Y134640D02*
X284303Y135009D01*
G01X271277Y151737D02*
X271531Y151368D01*
G01X271485Y150441D02*
X271264Y150762D01*
G01X280406Y135937D02*
X280628Y135615D01*
G01X280615Y134640D02*
X280361Y135009D01*
G01X267335Y151737D02*
X267589Y151368D01*
G01X267544Y150441D02*
X267322Y150762D01*
G01X276474Y135937D02*
X276695Y135615D01*
G01X276682Y134640D02*
X276429Y135009D01*
G01X272532Y135937D02*
X272754Y135615D01*
G01X272741Y134640D02*
X272487Y135009D01*
G01X268600Y135937D02*
X268821Y135615D01*
G01X268808Y134640D02*
X268555Y135009D01*
G01X346075Y134640D02*
X346329Y135009D01*
G01X346062Y135615D02*
X346284Y135937D01*
G01X342134Y134640D02*
X342388Y135009D01*
G01X342121Y135615D02*
X342342Y135937D01*
G01X338201Y134640D02*
X338455Y135009D01*
G01X338188Y135615D02*
X338410Y135937D01*
G01X343398Y150393D02*
X343408Y150441D01*
G01X338419Y135984D02*
X338410Y135937D01*
G01X339457Y150393D02*
X339466Y150441D01*
G01X334478Y135984D02*
X334468Y135937D01*
G01X335524Y150393D02*
X335534Y150441D01*
G01X330536Y135937D02*
X330545Y135984D01*
G01X331592Y150441D02*
X331583Y150393D01*
G01X326604Y135984D02*
X326594Y135937D01*
G01X327650Y150393D02*
X327660Y150441D01*
G01X322662Y135937D02*
X322671Y135984D01*
G01X323718Y150441D02*
X323709Y150393D01*
G01X318730Y135984D02*
X318720Y135937D01*
G01X319776Y150393D02*
X319786Y150441D01*
G01X331862Y139379D02*
X331912Y140365D01*
G01X331910Y141327D02*
X331859Y140340D01*
G01X330218Y145050D02*
X330269Y146037D01*
G01X330266Y146999D02*
X330216Y146012D01*
G01X327920Y139379D02*
X327970Y140365D01*
G01X327968Y141327D02*
X327918Y140340D01*
G01X326286Y145050D02*
X326336Y146037D01*
G01X326334Y146999D02*
X326284Y146012D01*
G01X323988Y139379D02*
X324038Y140365D01*
G01X324036Y141327D02*
X323985Y140340D01*
G01X322344Y145050D02*
X322395Y146037D01*
G01X322392Y146999D02*
X322342Y146012D01*
G01X320046Y139379D02*
X320096Y140365D01*
G01X320094Y141327D02*
X320044Y140340D01*
G01X318412Y145050D02*
X318462Y146037D01*
G01X318460Y146999D02*
X318410Y146012D01*
G01X316114Y139379D02*
X316164Y140365D01*
G01X316162Y141327D02*
X316111Y140340D01*
G01X314470Y145050D02*
X314521Y146037D01*
G01X314518Y146999D02*
X314468Y146012D01*
G01X312172Y139379D02*
X312222Y140365D01*
G01X312220Y141327D02*
X312169Y140340D01*
G01X310538Y145050D02*
X310588Y146037D01*
G01X310586Y146999D02*
X310536Y146012D01*
G01X331938Y145353D02*
X332074Y151260D01*
G01X332070Y152147D02*
X331933Y146239D01*
G01X330058Y134231D02*
X330195Y140138D01*
G01X330190Y141024D02*
X330054Y135117D01*
G01X328006Y145353D02*
X328142Y151260D01*
G01X328137Y152147D02*
X328001Y146239D01*
G01X326117Y134231D02*
X326253Y140138D01*
G01X326248Y141024D02*
X326112Y135117D01*
G01X324064Y145353D02*
X324200Y151260D01*
G01X324196Y152147D02*
X324059Y146239D01*
G01X322184Y134231D02*
X322321Y140138D01*
G01X322316Y141024D02*
X322180Y135117D01*
G01X320132Y145353D02*
X320268Y151260D01*
G01X320263Y152147D02*
X320127Y146239D01*
G01X318243Y134231D02*
X318379Y140138D01*
G01X318374Y141024D02*
X318238Y135117D01*
G01X316190Y145353D02*
X316326Y151260D01*
G01X316322Y152147D02*
X316185Y146239D01*
G01X314310Y134231D02*
X314447Y140138D01*
G01X314442Y141024D02*
X314306Y135117D01*
G01X312258Y145353D02*
X312394Y151260D01*
G01X312389Y152147D02*
X312253Y146239D01*
G01X310369Y134231D02*
X310505Y140138D01*
G01X310500Y141024D02*
X310364Y135117D01*
G01X308316Y145353D02*
X308452Y151260D01*
G01X308448Y152147D02*
X308311Y146239D01*
G01X330568Y150393D02*
X330581Y151368D01*
G01X327618Y135984D02*
X327605Y135009D01*
G01X326636Y150393D02*
X326649Y151368D01*
G01X323686Y135984D02*
X323673Y135009D01*
G01X322694Y150393D02*
X322707Y151368D01*
G01X319744Y135984D02*
X319731Y135009D01*
G01X318762Y150393D02*
X318775Y151368D01*
G01X315812Y135984D02*
X315799Y135009D01*
G01X314820Y150393D02*
X314833Y151368D01*
G01X311870Y135984D02*
X311857Y135009D01*
G01X310888Y150393D02*
X310901Y151368D01*
G01X307938Y135984D02*
X307925Y135009D01*
G01X330395Y130965D02*
Y129901D01*
G01Y156476D02*
Y155412D01*
G01X330316Y135617D02*
Y134627D01*
G01Y151750D02*
Y150760D01*
G01X330237Y151555D02*
Y156396D01*
G01Y129981D02*
Y134822D01*
G01X330040Y133840D02*
Y134824D01*
G01Y151553D02*
Y152538D01*
G01X329962Y152539D02*
Y133838D01*
G01X329883Y135984D02*
Y129901D01*
G01Y156476D02*
Y150393D01*
G01X329686Y134822D02*
Y133838D01*
G01Y152539D02*
Y151555D01*
G01X329681Y152539D02*
Y151555D01*
G01X329647Y136515D02*
Y132342D01*
G01Y154035D02*
Y149862D01*
G01X328544D02*
Y154035D01*
G01Y132342D02*
Y136515D01*
G01X328510Y152539D02*
Y151555D01*
G01X328505Y134822D02*
Y133838D01*
G01X328500Y134822D02*
Y133838D01*
G01X328308Y135984D02*
Y129901D01*
G01Y156476D02*
Y150393D01*
G01X328229Y133838D02*
Y152539D01*
G01X328155Y152538D02*
Y151553D01*
G01X328146Y134824D02*
Y133840D01*
G01X327954Y147698D02*
Y152539D01*
G01Y133838D02*
Y138680D01*
G01X327880Y150760D02*
Y151750D01*
G01X327870Y134627D02*
Y135617D01*
G01X327796Y138760D02*
Y137696D01*
G01Y148681D02*
Y147618D01*
G01X327521D02*
Y148602D01*
G01Y138760D02*
Y137775D01*
G01X326733Y147618D02*
Y148602D01*
G01Y138760D02*
Y137775D01*
G01X326458Y138760D02*
Y137696D01*
G01Y148681D02*
Y147618D01*
G01X326384Y151750D02*
Y150760D01*
G01X326374Y135617D02*
Y134627D01*
G01X326340Y128523D02*
Y123011D01*
G01X326300Y147698D02*
Y152539D01*
G01Y133838D02*
Y138680D01*
G01X326108Y151553D02*
Y152538D01*
G01X326099Y133840D02*
Y134824D01*
G01X326025Y152539D02*
Y133838D01*
G01X325946Y135984D02*
Y129901D01*
G01Y156476D02*
Y150393D01*
G01X325754Y152539D02*
Y151555D01*
G01X325749Y152539D02*
Y151555D01*
G01X325744Y134822D02*
Y133838D01*
G01X325710Y136515D02*
Y132342D01*
G01Y154035D02*
Y149862D01*
G01X324607D02*
Y154035D01*
G01Y132342D02*
Y136515D01*
G01X324573Y134822D02*
Y133838D01*
G01X324568Y134822D02*
Y133838D01*
G01Y152539D02*
Y151555D01*
G01X324371Y135984D02*
Y129901D01*
G01Y156476D02*
Y150393D01*
G01X324292Y133838D02*
Y152539D01*
G01X324214Y134824D02*
Y133840D01*
G01Y152538D02*
Y151553D01*
G01X324017Y151555D02*
Y156396D01*
G01Y129981D02*
Y134822D01*
G01X323938Y150760D02*
Y151750D01*
G01Y134627D02*
Y135617D01*
G01X323859Y130965D02*
Y129901D01*
G01Y156476D02*
Y155412D01*
G01X323584Y129901D02*
Y130885D01*
G01Y156476D02*
Y155492D01*
G01X323190Y128523D02*
Y123011D01*
G01X322796Y130885D02*
Y129901D01*
G01Y156476D02*
Y155492D01*
G01X322521Y130965D02*
Y129901D01*
G01Y156476D02*
Y155412D01*
G01X322442Y135617D02*
Y134627D01*
G01Y151750D02*
Y150760D01*
G01X322363Y151555D02*
Y156396D01*
G01Y129981D02*
Y134822D01*
G01X322166Y133840D02*
Y134824D01*
G01Y151553D02*
Y152538D01*
G01X322088Y152539D02*
Y133838D01*
G01X322009Y135984D02*
Y129901D01*
G01Y156476D02*
Y150393D01*
G01X321812Y134822D02*
Y133838D01*
G01Y152539D02*
Y151555D01*
G01X321807Y152539D02*
Y151555D01*
G01X321773Y136515D02*
Y132342D01*
G01Y154035D02*
Y149862D01*
G01X320670D02*
Y154035D01*
G01Y132342D02*
Y136515D01*
G01X320636Y152539D02*
Y151555D01*
G01X320631Y134822D02*
Y133838D01*
G01X320626Y134822D02*
Y133838D01*
G01X320434Y135984D02*
Y129901D01*
G01Y156476D02*
Y150393D01*
G01X320355Y133838D02*
Y152539D01*
G01X320281Y152538D02*
Y151553D01*
G01X320272Y134824D02*
Y133840D01*
G01X320080Y147698D02*
Y152539D01*
G01Y133838D02*
Y138680D01*
G01X320006Y150760D02*
Y151750D01*
G01X319996Y134627D02*
Y135617D01*
G01X319922Y138760D02*
Y137696D01*
G01Y148681D02*
Y147618D01*
G01X319647D02*
Y148602D01*
G01Y138760D02*
Y137775D01*
G01X319253Y128523D02*
Y123011D01*
G01X318859Y147618D02*
Y148602D01*
G01Y138760D02*
Y137775D01*
G01X318584Y138760D02*
Y137696D01*
G01Y148681D02*
Y147618D01*
G01X318510Y151750D02*
Y150760D01*
G01X318500Y135617D02*
Y134627D01*
G01X318426Y147698D02*
Y152539D01*
G01Y133838D02*
Y138680D01*
G01X318234Y151553D02*
Y152538D01*
G01X318225Y133840D02*
Y134824D01*
G01X318151Y152539D02*
Y133838D01*
G01X318072Y135984D02*
Y129901D01*
G01Y156476D02*
Y150393D01*
G01X317880Y152539D02*
Y151555D01*
G01X317875Y152539D02*
Y151555D01*
G01X317870Y134822D02*
Y133838D01*
G01X317836Y136515D02*
Y132342D01*
G01Y154035D02*
Y149862D01*
G01X316733D02*
Y154035D01*
G01Y132342D02*
Y136515D01*
G01X316699Y134822D02*
Y133838D01*
G01X316694Y134822D02*
Y133838D01*
G01Y152539D02*
Y151555D01*
G01X316497Y135984D02*
Y129901D01*
G01Y156476D02*
Y150393D01*
G01X316418Y133838D02*
Y152539D01*
G01X316340Y134824D02*
Y133840D01*
G01Y152538D02*
Y151553D01*
G01X316143Y151555D02*
Y156396D01*
G01Y129981D02*
Y134822D01*
G01X316103Y128523D02*
Y123011D01*
G01X316064Y150760D02*
Y151750D01*
G01Y134627D02*
Y135617D01*
G01X315985Y130965D02*
Y129901D01*
G01Y156476D02*
Y155412D01*
G01X315710Y130885D02*
Y129901D01*
G01Y156476D02*
Y155492D01*
G01X314922D02*
Y156476D01*
G01Y130885D02*
Y129901D01*
G01X314647Y130965D02*
Y129901D01*
G01Y156476D02*
Y155412D01*
G01X314568Y135617D02*
Y134627D01*
G01Y151750D02*
Y150760D01*
G01X314489Y151555D02*
Y156396D01*
G01Y129981D02*
Y134822D01*
G01X314292Y133840D02*
Y134824D01*
G01Y151553D02*
Y152538D01*
G01X314214Y152539D02*
Y133838D01*
G01X314135Y135984D02*
Y129901D01*
G01Y156476D02*
Y150393D01*
G01X313938Y134822D02*
Y133838D01*
G01Y152539D02*
Y151555D01*
G01X313933Y152539D02*
Y151555D01*
G01X313899Y136515D02*
Y132342D01*
G01Y154035D02*
Y149862D01*
G01X312796D02*
Y154035D01*
G01Y132342D02*
Y136515D01*
G01X312762Y152539D02*
Y151555D01*
G01X312757Y134822D02*
Y133838D01*
G01X312752Y134822D02*
Y133838D01*
G01X312560Y135984D02*
Y129901D01*
G01Y156476D02*
Y150393D01*
G01X312481Y133838D02*
Y152539D01*
G01X312407Y152538D02*
Y151553D01*
G01X312398Y134824D02*
Y133840D01*
G01X312206Y147698D02*
Y152539D01*
G01Y133838D02*
Y138680D01*
G01X312132Y150760D02*
Y151750D01*
G01X312122Y134627D02*
Y135617D01*
G01X312048Y138760D02*
Y137696D01*
G01Y148681D02*
Y147618D01*
G01X311773Y138760D02*
Y137775D01*
G01Y148602D02*
Y147618D01*
G01X310985Y138760D02*
Y137775D01*
G01Y148602D02*
Y147618D01*
G01X310710Y138760D02*
Y137696D01*
G01Y148681D02*
Y147618D01*
G01X310636Y151750D02*
Y150760D01*
G01X310626Y135617D02*
Y134627D01*
G01X310552Y147698D02*
Y152539D01*
G01Y133838D02*
Y138680D01*
G01X310360Y151553D02*
Y152538D01*
G01X310351Y133840D02*
Y134824D01*
G01X310277Y152539D02*
Y133838D01*
G01X310198Y135984D02*
Y129901D01*
G01Y156476D02*
Y150393D01*
G01X310006Y152539D02*
Y151555D01*
G01X310001Y152539D02*
Y151555D01*
G01X309996Y134822D02*
Y133838D01*
G01X309962Y136515D02*
Y132342D01*
G01Y154035D02*
Y149862D01*
G01X308859D02*
Y154035D01*
G01Y132342D02*
Y136515D01*
G01X308825Y134822D02*
Y133838D01*
G01X308820Y134822D02*
Y133838D01*
G01Y152539D02*
Y151555D01*
G01X308623Y135984D02*
Y129901D01*
G01Y156476D02*
Y150393D01*
G01X308544Y133838D02*
Y152539D01*
G01X308466Y134824D02*
Y133840D01*
G01Y152538D02*
Y151553D01*
G01X308269Y151555D02*
Y156396D01*
G01Y129981D02*
Y134822D01*
G01X308190Y150760D02*
Y151750D01*
G01Y134627D02*
Y135617D01*
G01X308111Y130965D02*
Y129901D01*
G01Y156476D02*
Y155412D01*
G01X307836Y130885D02*
Y129901D01*
G01Y156476D02*
Y155492D01*
G01X307048D02*
Y156476D01*
G01Y130885D02*
Y129901D01*
G01X306773Y130965D02*
Y129901D01*
G01Y156476D02*
Y155412D01*
G01X306694Y135617D02*
Y134627D01*
G01Y151750D02*
Y150760D01*
G01X306615Y151555D02*
Y156396D01*
G01Y129981D02*
Y134822D01*
G01X306418Y151553D02*
Y152538D01*
G01Y133840D02*
Y134824D01*
G01X306340Y152539D02*
Y133838D01*
G01X306261Y135984D02*
Y129901D01*
G01Y156476D02*
Y150393D01*
G01X327614Y151368D02*
X327627Y150393D01*
G01X326640Y135009D02*
X326626Y135984D01*
G01X323673Y151368D02*
X323686Y150393D01*
G01X322707Y135009D02*
X322694Y135984D01*
G01X319740Y151368D02*
X319753Y150393D01*
G01X318766Y135009D02*
X318752Y135984D01*
G01X315799Y151368D02*
X315812Y150393D01*
G01X314833Y135009D02*
X314820Y135984D01*
G01X311866Y151368D02*
X311879Y150393D01*
G01X310892Y135009D02*
X310878Y135984D01*
G01X307925Y151368D02*
X307938Y150393D01*
G01X306959Y135009D02*
X306946Y135984D01*
G01X328133Y135117D02*
X327996Y141024D01*
G01X327992Y140138D02*
X328128Y134231D01*
G01X326262Y146239D02*
X326126Y152147D01*
G01X326121Y151260D02*
X326257Y145353D01*
G01X324200Y135117D02*
X324064Y141024D01*
G01X324059Y140138D02*
X324196Y134231D01*
G01X322321Y146239D02*
X322184Y152147D01*
G01X322180Y151260D02*
X322316Y145353D01*
G01X320259Y135117D02*
X320122Y141024D01*
G01X320118Y140138D02*
X320254Y134231D01*
G01X318388Y146239D02*
X318252Y152147D01*
G01X318247Y151260D02*
X318383Y145353D01*
G01X316326Y135117D02*
X316190Y141024D01*
G01X316185Y140138D02*
X316322Y134231D01*
G01X314447Y146239D02*
X314310Y152147D01*
G01X314306Y151260D02*
X314442Y145353D01*
G01X312385Y135117D02*
X312248Y141024D01*
G01X312244Y140138D02*
X312380Y134231D01*
G01X310514Y146239D02*
X310378Y152147D01*
G01X310373Y151260D02*
X310509Y145353D01*
G01X308452Y135117D02*
X308316Y141024D01*
G01X308311Y140138D02*
X308448Y134231D01*
G01X306573Y146239D02*
X306436Y152147D01*
G01X306431Y151260D02*
X306568Y145353D01*
G01X326327Y140340D02*
X326277Y141327D01*
G01X326274Y140365D02*
X326325Y139379D01*
G01X324038Y146012D02*
X323988Y146999D01*
G01X323985Y146037D02*
X324036Y145050D01*
G01X322395Y140340D02*
X322344Y141327D01*
G01X322342Y140365D02*
X322392Y139379D01*
G01X320106Y146012D02*
X320055Y146999D01*
G01X320053Y146037D02*
X320103Y145050D01*
G01X318453Y140340D02*
X318403Y141327D01*
G01X318400Y140365D02*
X318451Y139379D01*
G01X316164Y146012D02*
X316114Y146999D01*
G01X316111Y146037D02*
X316162Y145050D01*
G01X314521Y140340D02*
X314470Y141327D01*
G01X314468Y140365D02*
X314518Y139379D01*
G01X312232Y146012D02*
X312181Y146999D01*
G01X312179Y146037D02*
X312229Y145050D01*
G01X310579Y140340D02*
X310529Y141327D01*
G01X310526Y140365D02*
X310577Y139379D01*
G01X308290Y146012D02*
X308239Y146999D01*
G01X308237Y146037D02*
X308288Y145050D01*
G01X306647Y140340D02*
X306596Y141327D01*
G01X306594Y140365D02*
X306644Y139379D01*
G01X304358Y146012D02*
X304307Y146999D01*
G01X304305Y146037D02*
X304355Y145050D01*
G01X291166Y150441D02*
X291175Y150393D01*
G01X292222Y135937D02*
X292213Y135984D01*
G01X287233Y150441D02*
X287243Y150393D01*
G01X288280Y135937D02*
X288271Y135984D01*
G01X283292Y150441D02*
X283301Y150393D01*
G01X284348Y135937D02*
X284339Y135984D01*
G01X279359Y150441D02*
X279369Y150393D01*
G01X280406Y135937D02*
X280397Y135984D01*
G01X275418Y150441D02*
X275427Y150393D01*
G01X276474Y135937D02*
X276465Y135984D01*
G01X271485Y150441D02*
X271495Y150393D01*
G01X272532Y135937D02*
X272523Y135984D01*
G01X267544Y150441D02*
X267553Y150393D01*
G01X334260Y134640D02*
X334514Y135009D01*
G01X334247Y135615D02*
X334468Y135937D01*
G01X343629Y150762D02*
X343408Y150441D01*
G01X343616Y151737D02*
X343362Y151368D01*
G01X330327Y134640D02*
X330581Y135009D01*
G01X330536Y135937D02*
X330316Y135617D01*
G01X339688Y150762D02*
X339466Y150441D01*
G01X339674Y151737D02*
X339421Y151368D01*
G01X326386Y134640D02*
X326640Y135009D01*
G01X326373Y135615D02*
X326594Y135937D01*
G01X335755Y150762D02*
X335534Y150441D01*
G01X335742Y151737D02*
X335488Y151368D01*
G01X322453Y134640D02*
X322707Y135009D01*
G01X322662Y135937D02*
X322442Y135617D01*
G01X331592Y150441D02*
X331812Y150760D01*
G01X331800Y151737D02*
X331547Y151368D01*
G01X318512Y134640D02*
X318766Y135009D01*
G01X318499Y135615D02*
X318720Y135937D01*
G01X327881Y150762D02*
X327660Y150441D01*
G01X327868Y151737D02*
X327614Y151368D01*
G01X314579Y134640D02*
X314833Y135009D01*
G01X314566Y135615D02*
X314788Y135937D01*
G01X323718Y150441D02*
X323938Y150760D01*
G01X323926Y151737D02*
X323673Y151368D01*
G01X310638Y134640D02*
X310892Y135009D01*
G01X310625Y135615D02*
X310846Y135937D01*
G01X320007Y150762D02*
X319786Y150441D01*
G01X319994Y151737D02*
X319740Y151368D01*
G01X306705Y134640D02*
X306959Y135009D01*
G01X314797Y135984D02*
X314788Y135937D01*
G01X315835Y150393D02*
X315844Y150441D01*
G01X310856Y135984D02*
X310846Y135937D01*
G01X311902Y150393D02*
X311912Y150441D01*
G01X306923Y135984D02*
X306914Y135937D01*
G01X307961Y150393D02*
X307970Y150441D01*
G01X302982Y135984D02*
X302972Y135937D01*
G01X304028Y150393D02*
X304038Y150441D01*
G01X299049Y135984D02*
X299040Y135937D01*
G01X300087Y150393D02*
X300096Y150441D01*
G01X295108Y135984D02*
X295098Y135937D01*
G01X296154Y150393D02*
X296164Y150441D01*
G01X291175Y135984D02*
X291166Y135937D01*
G01X308239Y139379D02*
X308290Y140365D01*
G01X308288Y141327D02*
X308237Y140340D01*
G01X306596Y145050D02*
X306647Y146037D01*
G01X306644Y146999D02*
X306594Y146012D01*
G01X304298Y139379D02*
X304348Y140365D01*
G01X304346Y141327D02*
X304295Y140340D01*
G01X302664Y145050D02*
X302714Y146037D01*
G01X302712Y146999D02*
X302661Y146012D01*
G01X300365Y139379D02*
X300416Y140365D01*
G01X300414Y141327D02*
X300363Y140340D01*
G01X298722Y145050D02*
X298773Y146037D01*
G01X298770Y146999D02*
X298720Y146012D01*
G01X296424Y139379D02*
X296474Y140365D01*
G01X296472Y141327D02*
X296421Y140340D01*
G01X294790Y145050D02*
X294840Y146037D01*
G01X294838Y146999D02*
X294787Y146012D01*
G01X292491Y139379D02*
X292542Y140365D01*
G01X292540Y141327D02*
X292489Y140340D01*
G01X290848Y145050D02*
X290899Y146037D01*
G01X290896Y146999D02*
X290846Y146012D01*
G01X288550Y139379D02*
X288600Y140365D01*
G01X288598Y141327D02*
X288547Y140340D01*
G01X286916Y145050D02*
X286966Y146037D01*
G01X286964Y146999D02*
X286913Y146012D01*
G01X284617Y139379D02*
X284668Y140365D01*
G01X284666Y141327D02*
X284615Y140340D01*
G01X306436Y134231D02*
X306573Y140138D01*
G01X306568Y141024D02*
X306431Y135117D01*
G01X304384Y145353D02*
X304520Y151260D01*
G01X304515Y152147D02*
X304379Y146239D01*
G01X302495Y134231D02*
X302631Y140138D01*
G01X302626Y141024D02*
X302490Y135117D01*
G01X300442Y145353D02*
X300578Y151260D01*
G01X300574Y152147D02*
X300437Y146239D01*
G01X298562Y134231D02*
X298698Y140138D01*
G01X298694Y141024D02*
X298557Y135117D01*
G01X296510Y145353D02*
X296646Y151260D01*
G01X296641Y152147D02*
X296505Y146239D01*
G01X294621Y134231D02*
X294757Y140138D01*
G01X294752Y141024D02*
X294616Y135117D01*
G01X292568Y145353D02*
X292704Y151260D01*
G01X292700Y152147D02*
X292563Y146239D01*
G01X290688Y134231D02*
X290824Y140138D01*
G01X290820Y141024D02*
X290683Y135117D01*
G01X288636Y145353D02*
X288772Y151260D01*
G01X288767Y152147D02*
X288631Y146239D01*
G01X286747Y134231D02*
X286883Y140138D01*
G01X286878Y141024D02*
X286742Y135117D01*
G01X284694Y145353D02*
X284830Y151260D01*
G01X284825Y152147D02*
X284689Y146239D01*
G01X306946Y150393D02*
X306959Y151368D01*
G01X303996Y135984D02*
X303983Y135009D01*
G01X303014Y150393D02*
X303027Y151368D01*
G01X300064Y135984D02*
X300051Y135009D01*
G01X299072Y150393D02*
X299085Y151368D01*
G01X296122Y135984D02*
X296109Y135009D01*
G01X295140Y150393D02*
X295153Y151368D01*
G01X292190Y135984D02*
X292177Y135009D01*
G01X291198Y150393D02*
X291211Y151368D01*
G01X288248Y135984D02*
X288235Y135009D01*
G01X287266Y150393D02*
X287279Y151368D01*
G01X284316Y135984D02*
X284303Y135009D01*
G01X283324Y150393D02*
X283337Y151368D01*
G01X306064Y134822D02*
Y133838D01*
G01Y152539D02*
Y151555D01*
G01X306059Y152539D02*
Y151555D01*
G01X306025Y136515D02*
Y132342D01*
G01Y154035D02*
Y149862D01*
G01X304922D02*
Y154035D01*
G01Y132342D02*
Y136515D01*
G01X304888Y152539D02*
Y151555D01*
G01X304883Y134822D02*
Y133838D01*
G01X304878Y134822D02*
Y133838D01*
G01X304686Y135984D02*
Y129901D01*
G01Y156476D02*
Y150393D01*
G01X304607Y133838D02*
Y152539D01*
G01X304533Y152538D02*
Y151553D01*
G01X304524Y134824D02*
Y133840D01*
G01X304332Y147698D02*
Y152539D01*
G01Y133838D02*
Y138680D01*
G01X304258Y150760D02*
Y151750D01*
G01X304248Y134627D02*
Y135617D01*
G01X304174Y138760D02*
Y137696D01*
G01Y148681D02*
Y147618D01*
G01X303899D02*
Y148602D01*
G01Y138760D02*
Y137775D01*
G01X303111Y147618D02*
Y148602D01*
G01Y137775D02*
Y138760D01*
G01X302836D02*
Y137696D01*
G01Y148681D02*
Y147618D01*
G01X302762Y151750D02*
Y150760D01*
G01X302752Y135617D02*
Y134627D01*
G01X302717Y128523D02*
Y123011D01*
G01X302678Y147698D02*
Y152539D01*
G01Y133838D02*
Y138680D01*
G01X302486Y151553D02*
Y152538D01*
G01X302477Y133840D02*
Y134824D01*
G01X302403Y152539D02*
Y133838D01*
G01X302324Y135984D02*
Y129901D01*
G01Y156476D02*
Y150393D01*
G01X302132Y152539D02*
Y151555D01*
G01X302127Y152539D02*
Y151555D01*
G01X302122Y134822D02*
Y133838D01*
G01X302088Y136515D02*
Y132342D01*
G01Y154035D02*
Y149862D01*
G01X300985D02*
Y154035D01*
G01Y132342D02*
Y136515D01*
G01X300951Y134822D02*
Y133838D01*
G01X300946Y134822D02*
Y133838D01*
G01Y152539D02*
Y151555D01*
G01X300749Y135984D02*
Y129901D01*
G01Y156476D02*
Y150393D01*
G01X300670Y133838D02*
Y152539D01*
G01X300592Y134824D02*
Y133840D01*
G01Y152538D02*
Y151553D01*
G01X300395Y151555D02*
Y156396D01*
G01Y129981D02*
Y134822D01*
G01X300316Y150760D02*
Y151750D01*
G01Y134627D02*
Y135617D01*
G01X300237Y130965D02*
Y129901D01*
G01Y156476D02*
Y155412D01*
G01X299962Y130885D02*
Y129901D01*
G01Y156476D02*
Y155492D01*
G01X299568Y128523D02*
Y123011D01*
G01X299174Y155492D02*
Y156476D01*
G01Y130885D02*
Y129901D01*
G01X298899Y130965D02*
Y129901D01*
G01Y156476D02*
Y155412D01*
G01X298820Y135617D02*
Y134627D01*
G01Y151750D02*
Y150760D01*
G01X298741Y151555D02*
Y156396D01*
G01Y129981D02*
Y134822D01*
G01X298544Y133840D02*
Y134824D01*
G01Y151553D02*
Y152538D01*
G01X298466Y152539D02*
Y133838D01*
G01X298387Y135984D02*
Y129901D01*
G01Y156476D02*
Y150393D01*
G01X298190Y134822D02*
Y133838D01*
G01Y152539D02*
Y151555D01*
G01X298185Y152539D02*
Y151555D01*
G01X298151Y136515D02*
Y132342D01*
G01Y154035D02*
Y149862D01*
G01X297048D02*
Y154035D01*
G01Y132342D02*
Y136515D01*
G01X297014Y152539D02*
Y151555D01*
G01X297009Y134822D02*
Y133838D01*
G01X297004Y134822D02*
Y133838D01*
G01X296812Y135984D02*
Y129901D01*
G01Y156476D02*
Y150393D01*
G01X296733Y133838D02*
Y152539D01*
G01X296659Y152538D02*
Y151553D01*
G01X296650Y134824D02*
Y133840D01*
G01X296458Y147698D02*
Y152539D01*
G01Y133838D02*
Y138680D01*
G01X296384Y150760D02*
Y151750D01*
G01X296374Y134627D02*
Y135617D01*
G01X296300Y138760D02*
Y137696D01*
G01Y148681D02*
Y147618D01*
G01X296025D02*
Y148602D01*
G01Y138760D02*
Y137775D01*
G01X295631Y128523D02*
Y123011D01*
G01X295237Y147618D02*
Y148602D01*
G01Y137775D02*
Y138760D01*
G01X294962D02*
Y137696D01*
G01Y148681D02*
Y147618D01*
G01X294888Y151750D02*
Y150760D01*
G01X294878Y135617D02*
Y134627D01*
G01X294804Y147698D02*
Y152539D01*
G01Y133838D02*
Y138680D01*
G01X294612Y151553D02*
Y152538D01*
G01X294603Y133840D02*
Y134824D01*
G01X294529Y152539D02*
Y133838D01*
G01X294450Y135984D02*
Y129901D01*
G01Y156476D02*
Y150393D01*
G01X294258Y152539D02*
Y151555D01*
G01X294253Y152539D02*
Y151555D01*
G01X294248Y134822D02*
Y133838D01*
G01X294214Y136515D02*
Y132342D01*
G01Y154035D02*
Y149862D01*
G01X293111D02*
Y154035D01*
G01Y132342D02*
Y136515D01*
G01X293077Y134822D02*
Y133838D01*
G01X293072Y134822D02*
Y133838D01*
G01Y152539D02*
Y151555D01*
G01X292875Y135984D02*
Y129901D01*
G01Y156476D02*
Y150393D01*
G01X292796Y133838D02*
Y152539D01*
G01X292717Y134824D02*
Y133840D01*
G01Y152538D02*
Y151553D01*
G01X292521Y151555D02*
Y156396D01*
G01Y129981D02*
Y134822D01*
G01X292481Y128523D02*
Y123011D01*
G01X292442Y150760D02*
Y151750D01*
G01Y134627D02*
Y135617D01*
G01X292363Y130965D02*
Y129901D01*
G01Y156476D02*
Y155412D01*
G01X292088Y130885D02*
Y129901D01*
G01Y156476D02*
Y155492D01*
G01X291300D02*
Y156476D01*
G01Y130885D02*
Y129901D01*
G01X291025Y130965D02*
Y129901D01*
G01Y156476D02*
Y155412D01*
G01X290946Y135617D02*
Y134627D01*
G01Y151750D02*
Y150760D01*
G01X290867Y151555D02*
Y156396D01*
G01Y129981D02*
Y134822D01*
G01X290670Y133840D02*
Y134824D01*
G01Y151553D02*
Y152538D01*
G01X290592Y152539D02*
Y133838D01*
G01X290513Y135984D02*
Y129901D01*
G01Y156476D02*
Y150393D01*
G01X290316Y134822D02*
Y133838D01*
G01Y152539D02*
Y151555D01*
G01X290311Y152539D02*
Y151555D01*
G01X290277Y136515D02*
Y132342D01*
G01Y154035D02*
Y149862D01*
G01X289174D02*
Y154035D01*
G01Y132342D02*
Y136515D01*
G01X289139Y152539D02*
Y151555D01*
G01X289135Y134822D02*
Y133838D01*
G01X289130Y134822D02*
Y133838D01*
G01X288938Y135984D02*
Y129901D01*
G01Y156476D02*
Y150393D01*
G01X288859Y133838D02*
Y152539D01*
G01X288785Y152538D02*
Y151553D01*
G01X288776Y134824D02*
Y133840D01*
G01X288584Y147698D02*
Y152539D01*
G01Y133838D02*
Y138680D01*
G01X288510Y150760D02*
Y151750D01*
G01X288500Y134627D02*
Y135617D01*
G01X288426Y138760D02*
Y137696D01*
G01Y148681D02*
Y147618D01*
G01X288151Y138760D02*
Y137775D01*
G01Y148602D02*
Y147618D01*
G01X287363Y138760D02*
Y137775D01*
G01Y148602D02*
Y147618D01*
G01X287088Y138760D02*
Y137696D01*
G01Y148681D02*
Y147618D01*
G01X287014Y151750D02*
Y150760D01*
G01X287004Y135617D02*
Y134627D01*
G01X286930Y147698D02*
Y152539D01*
G01Y133838D02*
Y138680D01*
G01X286738Y151553D02*
Y152538D01*
G01X286729Y133840D02*
Y134824D01*
G01X286655Y152539D02*
Y133838D01*
G01X286576Y135984D02*
Y129901D01*
G01Y156476D02*
Y150393D01*
G01X286384Y152539D02*
Y151555D01*
G01X286379Y152539D02*
Y151555D01*
G01X286374Y134822D02*
Y133838D01*
G01X286340Y136515D02*
Y132342D01*
G01Y154035D02*
Y149862D01*
G01X285237D02*
Y154035D01*
G01Y132342D02*
Y136515D01*
G01X285202Y134822D02*
Y133838D01*
G01X285198Y134822D02*
Y133838D01*
G01Y152539D02*
Y151555D01*
G01X285001Y135984D02*
Y129901D01*
G01Y156476D02*
Y150393D01*
G01X284922Y133838D02*
Y152539D01*
G01X284843Y134824D02*
Y133840D01*
G01Y152538D02*
Y151553D01*
G01X284647Y151555D02*
Y156396D01*
G01Y129981D02*
Y134822D01*
G01X284568Y150760D02*
Y151750D01*
G01Y134627D02*
Y135617D01*
G01X284489Y130965D02*
Y129901D01*
G01Y156476D02*
Y155412D01*
G01X284214Y130885D02*
Y129901D01*
G01Y156476D02*
Y155492D01*
G01X283426D02*
Y156476D01*
G01Y130885D02*
Y129901D01*
G01X283151Y130965D02*
Y129901D01*
G01Y156476D02*
Y155412D01*
G01X283072Y135617D02*
Y134627D01*
G01Y151750D02*
Y150760D01*
G01X282993Y151555D02*
Y156396D01*
G01Y129981D02*
Y134822D01*
G01X282796Y133840D02*
Y134824D01*
G01Y151553D02*
Y152538D01*
G01X282717Y152539D02*
Y133838D01*
G01X282639Y135984D02*
Y129901D01*
G01Y156476D02*
Y150393D01*
G01X282442Y134822D02*
Y133838D01*
G01Y152539D02*
Y151555D01*
G01X282437Y152539D02*
Y151555D01*
G01X282403Y136515D02*
Y132342D01*
G01Y154035D02*
Y149862D01*
G01X303992Y151368D02*
X304005Y150393D01*
G01X303018Y135009D02*
X303004Y135984D01*
G01X300051Y151368D02*
X300064Y150393D01*
G01X299085Y135009D02*
X299072Y135984D01*
G01X296118Y151368D02*
X296131Y150393D01*
G01X295144Y135009D02*
X295130Y135984D01*
G01X292177Y151368D02*
X292190Y150393D01*
G01X291211Y135009D02*
X291198Y135984D01*
G01X288244Y151368D02*
X288257Y150393D01*
G01X287270Y135009D02*
X287256Y135984D01*
G01X284303Y151368D02*
X284316Y150393D01*
G01X283337Y135009D02*
X283324Y135984D01*
G01X304511Y135117D02*
X304374Y141024D01*
G01X304370Y140138D02*
X304506Y134231D01*
G01X302640Y146239D02*
X302504Y152147D01*
G01X302499Y151260D02*
X302635Y145353D01*
G01X300578Y135117D02*
X300442Y141024D01*
G01X300437Y140138D02*
X300574Y134231D01*
G01X298698Y146239D02*
X298562Y152147D01*
G01X298557Y151260D02*
X298694Y145353D01*
G01X296637Y135117D02*
X296500Y141024D01*
G01X296496Y140138D02*
X296632Y134231D01*
G01X294766Y146239D02*
X294630Y152147D01*
G01X294625Y151260D02*
X294761Y145353D01*
G01X292704Y135117D02*
X292568Y141024D01*
G01X292563Y140138D02*
X292700Y134231D01*
G01X290824Y146239D02*
X290688Y152147D01*
G01X290683Y151260D02*
X290820Y145353D01*
G01X288763Y135117D02*
X288626Y141024D01*
G01X288622Y140138D02*
X288758Y134231D01*
G01X286892Y146239D02*
X286756Y152147D01*
G01X286751Y151260D02*
X286887Y145353D01*
G01X284830Y135117D02*
X284694Y141024D01*
G01X284689Y140138D02*
X284825Y134231D01*
G01X282950Y146239D02*
X282814Y152147D01*
G01X282809Y151260D02*
X282946Y145353D01*
G01X280889Y135117D02*
X280752Y141024D01*
G01X280748Y140138D02*
X280884Y134231D01*
G01X302705Y140340D02*
X302654Y141327D01*
G01X302652Y140365D02*
X302703Y139379D01*
G01X300416Y146012D02*
X300365Y146999D01*
G01X300363Y146037D02*
X300414Y145050D01*
G01X298773Y140340D02*
X298722Y141327D01*
G01X298720Y140365D02*
X298770Y139379D01*
G01X296484Y146012D02*
X296433Y146999D01*
G01X296431Y146037D02*
X296481Y145050D01*
G01X294831Y140340D02*
X294780Y141327D01*
G01X294778Y140365D02*
X294829Y139379D01*
G01X292542Y146012D02*
X292491Y146999D01*
G01X292489Y146037D02*
X292540Y145050D01*
G01X290899Y140340D02*
X290848Y141327D01*
G01X290846Y140365D02*
X290896Y139379D01*
G01X288610Y146012D02*
X288559Y146999D01*
G01X288557Y146037D02*
X288607Y145050D01*
G01X286957Y140340D02*
X286906Y141327D01*
G01X286904Y140365D02*
X286955Y139379D01*
G01X284668Y146012D02*
X284617Y146999D01*
G01X284615Y146037D02*
X284666Y145050D01*
G01X283025Y140340D02*
X282974Y141327D01*
G01X282972Y140365D02*
X283022Y139379D01*
G01X280736Y146012D02*
X280685Y146999D01*
G01X280683Y146037D02*
X280733Y145050D01*
G01X279083Y140340D02*
X279032Y141327D01*
G01X279030Y140365D02*
X279081Y139379D01*
G01X268600Y135937D02*
X268591Y135984D01*
G01X306692Y135615D02*
X306914Y135937D01*
G01X316066Y150762D02*
X315844Y150441D01*
G01X316052Y151737D02*
X315799Y151368D01*
G01X302764Y134640D02*
X303018Y135009D01*
G01X302751Y135615D02*
X302972Y135937D01*
G01X312133Y150762D02*
X311912Y150441D01*
G01X312120Y151737D02*
X311866Y151368D01*
G01X298831Y134640D02*
X299085Y135009D01*
G01X298818Y135615D02*
X299040Y135937D01*
G01X308192Y150762D02*
X307970Y150441D01*
G01X308178Y151737D02*
X307925Y151368D01*
G01X294890Y134640D02*
X295144Y135009D01*
G01X294877Y135615D02*
X295098Y135937D01*
G01X304259Y150762D02*
X304038Y150441D01*
G01X304246Y151737D02*
X303992Y151368D01*
G01X290957Y134640D02*
X291211Y135009D01*
G01X290944Y135615D02*
X291166Y135937D01*
G01X300318Y150762D02*
X300096Y150441D01*
G01X300304Y151737D02*
X300051Y151368D01*
G01X287016Y134640D02*
X287270Y135009D01*
G01X287003Y135615D02*
X287224Y135937D01*
G01X296385Y150762D02*
X296164Y150441D01*
G01X296372Y151737D02*
X296118Y151368D01*
G01X283083Y134640D02*
X283337Y135009D01*
G01X283070Y135615D02*
X283292Y135937D01*
G01X292444Y150762D02*
X292222Y150441D01*
G01X292430Y151737D02*
X292177Y151368D01*
G01X279142Y134640D02*
X279396Y135009D01*
G01X279129Y135615D02*
X279350Y135937D01*
G01X288511Y150762D02*
X288290Y150441D01*
G01X288498Y151737D02*
X288244Y151368D01*
G01X292213Y150393D02*
X292222Y150441D01*
G01X287233Y135984D02*
X287224Y135937D01*
G01X288280Y150393D02*
X288290Y150441D01*
G01X283301Y135984D02*
X283292Y135937D01*
G01X284339Y150393D02*
X284348Y150441D01*
G01X279359Y135984D02*
X279350Y135937D01*
G01X280406Y150393D02*
X280416Y150441D01*
G01X275427Y135984D02*
X275418Y135937D01*
G01X276465Y150393D02*
X276474Y150441D01*
G01X271485Y135984D02*
X271476Y135937D01*
G01X272532Y150393D02*
X272542Y150441D01*
G01X267553Y135984D02*
X267544Y135937D01*
G01X282974Y145050D02*
X283025Y146037D01*
G01X283022Y146999D02*
X282972Y146012D01*
G01X280676Y139379D02*
X280726Y140365D01*
G01X280724Y141327D02*
X280673Y140340D01*
G01X279042Y145050D02*
X279092Y146037D01*
G01X279090Y146999D02*
X279039Y146012D01*
G01X276743Y139379D02*
X276794Y140365D01*
G01X276792Y141327D02*
X276741Y140340D01*
G01X275100Y145050D02*
X275151Y146037D01*
G01X275148Y146999D02*
X275098Y146012D01*
G01X272802Y139379D02*
X272852Y140365D01*
G01X272850Y141327D02*
X272799Y140340D01*
G01X271168Y145050D02*
X271218Y146037D01*
G01X271216Y146999D02*
X271165Y146012D01*
G01X268869Y139379D02*
X268920Y140365D01*
G01X268918Y141327D02*
X268867Y140340D01*
G01X267226Y145050D02*
X267277Y146037D01*
G01X267274Y146999D02*
X267224Y146012D01*
G01X282814Y134231D02*
X282950Y140138D01*
G01X282946Y141024D02*
X282809Y135117D01*
G01X280762Y145353D02*
X280898Y151260D01*
G01X280893Y152147D02*
X280757Y146239D01*
G01X278873Y134231D02*
X279009Y140138D01*
G01X279004Y141024D02*
X278868Y135117D01*
G01X276820Y145353D02*
X276956Y151260D01*
G01X276951Y152147D02*
X276815Y146239D01*
G01X274940Y134231D02*
X275076Y140138D01*
G01X275072Y141024D02*
X274935Y135117D01*
G01X272888Y145353D02*
X273024Y151260D01*
G01X273019Y152147D02*
X272883Y146239D01*
G01X270999Y134231D02*
X271135Y140138D01*
G01X271130Y141024D02*
X270994Y135117D01*
G01X268946Y145353D02*
X269082Y151260D01*
G01X269077Y152147D02*
X268941Y146239D01*
G01X267066Y134231D02*
X267202Y140138D01*
G01X267198Y141024D02*
X267061Y135117D01*
G01X280374Y135984D02*
X280361Y135009D01*
G01X279392Y150393D02*
X279405Y151368D01*
G01X276442Y135984D02*
X276429Y135009D01*
G01X275450Y150393D02*
X275463Y151368D01*
G01X272500Y135984D02*
X272487Y135009D01*
G01X271518Y150393D02*
X271531Y151368D01*
G01X268568Y135984D02*
X268555Y135009D01*
G01X267576Y150393D02*
X267589Y151368D01*
G01X281300Y149862D02*
Y154035D01*
G01Y132342D02*
Y136515D01*
G01X281265Y152539D02*
Y151555D01*
G01X281261Y134822D02*
Y133838D01*
G01X281256Y134822D02*
Y133838D01*
G01X281064Y135984D02*
Y129901D01*
G01Y156476D02*
Y150393D01*
G01X280985Y133838D02*
Y152539D01*
G01X280911Y152538D02*
Y151553D01*
G01X280902Y134824D02*
Y133840D01*
G01X280710Y147698D02*
Y152539D01*
G01Y133838D02*
Y138680D01*
G01X280636Y150760D02*
Y151750D01*
G01X280626Y134627D02*
Y135617D01*
G01X280552Y138760D02*
Y137696D01*
G01Y148681D02*
Y147618D01*
G01X280277Y138760D02*
Y137775D01*
G01Y148602D02*
Y147618D01*
G01X279489Y138760D02*
Y137775D01*
G01Y148602D02*
Y147618D01*
G01X279214Y138760D02*
Y137696D01*
G01Y148681D02*
Y147618D01*
G01X279139Y151750D02*
Y150760D01*
G01X279130Y135617D02*
Y134627D01*
G01X279095Y128523D02*
Y123011D01*
G01X279056Y147698D02*
Y152539D01*
G01Y133838D02*
Y138680D01*
G01X278864Y151553D02*
Y152538D01*
G01X278855Y133840D02*
Y134824D01*
G01X278780Y152539D02*
Y133838D01*
G01X278702Y135984D02*
Y129901D01*
G01Y156476D02*
Y150393D01*
G01X278510Y152539D02*
Y151555D01*
G01X278505Y152539D02*
Y151555D01*
G01X278500Y134822D02*
Y133838D01*
G01X278466Y136515D02*
Y132342D01*
G01Y154035D02*
Y149862D01*
G01X277363D02*
Y154035D01*
G01Y132342D02*
Y136515D01*
G01X277328Y134822D02*
Y133838D01*
G01X277324Y134822D02*
Y133838D01*
G01Y152539D02*
Y151555D01*
G01X277127Y135984D02*
Y129901D01*
G01Y156476D02*
Y150393D01*
G01X277048Y133838D02*
Y152539D01*
G01X276969Y134824D02*
Y133840D01*
G01Y152538D02*
Y151553D01*
G01X276773Y151555D02*
Y156396D01*
G01Y129981D02*
Y134822D01*
G01X276694Y150760D02*
Y151750D01*
G01Y134627D02*
Y135617D01*
G01X276615Y130965D02*
Y129901D01*
G01Y156476D02*
Y155412D01*
G01X276340Y130885D02*
Y129901D01*
G01Y156476D02*
Y155492D01*
G01X275946Y128523D02*
Y123011D01*
G01X275552Y155492D02*
Y156476D01*
G01Y130885D02*
Y129901D01*
G01X275277Y130965D02*
Y129901D01*
G01Y156476D02*
Y155412D01*
G01X275198Y135617D02*
Y134627D01*
G01Y151750D02*
Y150760D01*
G01X275119Y151555D02*
Y156396D01*
G01Y129981D02*
Y134822D01*
G01X274922Y151553D02*
Y152538D01*
G01Y133840D02*
Y134824D01*
G01X274843Y152539D02*
Y133838D01*
G01X274765Y135984D02*
Y129901D01*
G01Y156476D02*
Y150393D01*
G01X274568Y134822D02*
Y133838D01*
G01Y152539D02*
Y151555D01*
G01X274563Y152539D02*
Y151555D01*
G01X274529Y136515D02*
Y132342D01*
G01Y154035D02*
Y149862D01*
G01X273426D02*
Y154035D01*
G01Y132342D02*
Y136515D01*
G01X273391Y152539D02*
Y151555D01*
G01X273387Y134822D02*
Y133838D01*
G01X273382Y134822D02*
Y133838D01*
G01X273190Y135984D02*
Y129901D01*
G01Y156476D02*
Y150393D01*
G01X273111Y133838D02*
Y152539D01*
G01X273037Y152538D02*
Y151553D01*
G01X273028Y134824D02*
Y133840D01*
G01X272836Y147698D02*
Y152539D01*
G01Y133838D02*
Y138680D01*
G01X272762Y150760D02*
Y151750D01*
G01X272752Y134627D02*
Y135617D01*
G01X272678Y138760D02*
Y137696D01*
G01Y148681D02*
Y147618D01*
G01X272403D02*
Y148602D01*
G01Y138760D02*
Y137775D01*
G01X272009Y128523D02*
Y123011D01*
G01X271615Y147618D02*
Y148602D01*
G01Y137775D02*
Y138760D01*
G01X271340D02*
Y137696D01*
G01Y148681D02*
Y147618D01*
G01X271265Y151750D02*
Y150760D01*
G01X271256Y135617D02*
Y134627D01*
G01X271182Y147698D02*
Y152539D01*
G01Y133838D02*
Y138680D01*
G01X270990Y151553D02*
Y152538D01*
G01X270981Y133840D02*
Y134824D01*
G01X270906Y152539D02*
Y133838D01*
G01X270828Y135984D02*
Y129901D01*
G01Y156476D02*
Y150393D01*
G01X270636Y152539D02*
Y151555D01*
G01X270631Y152539D02*
Y151555D01*
G01X270626Y134822D02*
Y133838D01*
G01X270592Y136515D02*
Y132342D01*
G01Y154035D02*
Y149862D01*
G01X269489D02*
Y154035D01*
G01Y132342D02*
Y136515D01*
G01X269454Y134822D02*
Y133838D01*
G01X269450Y134822D02*
Y133838D01*
G01Y152539D02*
Y151555D01*
G01X269253Y135984D02*
Y129901D01*
G01Y156476D02*
Y150393D01*
G01X269174Y133838D02*
Y152539D01*
G01X269095Y134824D02*
Y133840D01*
G01Y152538D02*
Y151553D01*
G01X268899Y151555D02*
Y156396D01*
G01Y129981D02*
Y134822D01*
G01X268859Y128523D02*
Y123011D01*
G01X268820Y150760D02*
Y151750D01*
G01Y134627D02*
Y135617D01*
G01X268741Y130965D02*
Y129901D01*
G01Y156476D02*
Y155412D01*
G01X268466Y130885D02*
Y129901D01*
G01Y156476D02*
Y155492D01*
G01X267678D02*
Y156476D01*
G01Y130885D02*
Y129901D01*
G01X267403Y130965D02*
Y129901D01*
G01Y156476D02*
Y155412D01*
G01X267324Y135617D02*
Y134627D01*
G01Y151750D02*
Y150760D01*
G01X267245Y151555D02*
Y156396D01*
G01Y129981D02*
Y134822D01*
G01X267048Y151553D02*
Y152538D01*
G01Y133840D02*
Y134824D01*
G01X266969Y152539D02*
Y133838D01*
G01X266891Y135984D02*
Y129901D01*
G01Y156476D02*
Y150393D01*
G01X280370Y151368D02*
X280383Y150393D01*
G01X279396Y135009D02*
X279382Y135984D01*
G01X276429Y151368D02*
X276442Y150393D01*
G01X275463Y135009D02*
X275450Y135984D01*
G01X272496Y151368D02*
X272509Y150393D01*
G01X271521Y135009D02*
X271508Y135984D01*
G01X268555Y151368D02*
X268568Y150393D01*
G01X267589Y135009D02*
X267576Y135984D01*
G01X279018Y146239D02*
X278882Y152147D01*
G01X278877Y151260D02*
X279013Y145353D01*
G01X276956Y135117D02*
X276820Y141024D01*
G01X276815Y140138D02*
X276951Y134231D01*
G01X275076Y146239D02*
X274940Y152147D01*
G01X274935Y151260D02*
X275072Y145353D01*
G01X273015Y135117D02*
X272878Y141024D01*
G01X272874Y140138D02*
X273010Y134231D01*
G01X271144Y146239D02*
X271008Y152147D01*
G01X271003Y151260D02*
X271139Y145353D01*
G01X269082Y135117D02*
X268946Y141024D01*
G01X268941Y140138D02*
X269077Y134231D01*
G01X267202Y146239D02*
X267066Y152147D01*
G01X267061Y151260D02*
X267198Y145353D01*
G01X276794Y146012D02*
X276743Y146999D01*
G01X276741Y146037D02*
X276792Y145050D01*
G01X275151Y140340D02*
X275100Y141327D01*
G01X275098Y140365D02*
X275148Y139379D01*
G01X272862Y146012D02*
X272811Y146999D01*
G01X272809Y146037D02*
X272859Y145050D01*
G01X271209Y140340D02*
X271158Y141327D01*
G01X271156Y140365D02*
X271207Y139379D01*
G01X268920Y146012D02*
X268869Y146999D01*
G01X268867Y146037D02*
X268918Y145050D01*
G01X267277Y140340D02*
X267226Y141327D01*
G01X267224Y140365D02*
X267274Y139379D01*
G01X275209Y134640D02*
X275463Y135009D01*
G01X275196Y135615D02*
X275418Y135937D01*
G01X284569Y150762D02*
X284348Y150441D01*
G01X284556Y151737D02*
X284303Y151368D01*
G01X271268Y134640D02*
X271521Y135009D01*
G01X271255Y135615D02*
X271476Y135937D01*
G01X280637Y150762D02*
X280416Y150441D01*
G01X280624Y151737D02*
X280370Y151368D01*
G01X267335Y134640D02*
X267589Y135009D01*
G01X267322Y135615D02*
X267544Y135937D01*
G01X276695Y150762D02*
X276474Y150441D01*
G01X276682Y151737D02*
X276429Y151368D01*
G01X272763Y150762D02*
X272542Y150441D01*
G01X272750Y151737D02*
X272496Y151368D01*
G01X268821Y150762D02*
X268600Y150441D01*
G01X268808Y151737D02*
X268555Y151368D01*
G01X268591Y150393D02*
X268600Y150441D01*
G01X345953Y225965D02*
X345964Y226012D01*
G01X345948Y226063D02*
X345953Y225965D01*
G01X345943Y226239D02*
X345948Y226063D01*
G01X346038Y228861D02*
X346040Y229826D01*
G01X346036Y228414D02*
X346038Y228861D01*
G01X346033Y228009D02*
X346036Y228414D01*
G01X346029Y227656D02*
X346033Y228009D01*
G01X346025Y227364D02*
X346029Y227656D01*
G01X346020Y227143D02*
X346025Y227364D01*
G01X346014Y226999D02*
X346020Y227143D01*
G01X346049Y228520D02*
X346051Y229807D01*
G01X346045Y227925D02*
X346049Y228520D01*
G01X346041Y227384D02*
X346045Y227925D01*
G01X346036Y226913D02*
X346041Y227384D01*
G01X346030Y226524D02*
X346036Y226913D01*
G01X346024Y226230D02*
X346030Y226524D01*
G01X346017Y226037D02*
X346024Y226230D01*
G01X345952Y224988D02*
X345966Y225050D01*
G01X345945Y225118D02*
X345952Y224988D01*
G01X345938Y225353D02*
X345945Y225118D01*
G01X345953Y220412D02*
X345943Y220138D01*
G01X345959Y220429D02*
X345953Y220412D01*
G01X345964Y220365D02*
X345959Y220429D01*
G01X345952Y221390D02*
X345938Y221024D01*
G01X345959Y221412D02*
X345952Y221390D01*
G01X345966Y221327D02*
X345959Y221412D01*
G01X346030Y219853D02*
X346017Y220340D01*
G01X346036Y219464D02*
X346030Y219853D01*
G01X346041Y218993D02*
X346036Y219464D01*
G01X346045Y218453D02*
X346041Y218993D01*
G01X346049Y217857D02*
X346045Y218453D01*
G01X346051Y217224D02*
X346049Y217857D01*
G01X346051Y216570D02*
Y217224D01*
G01X346025Y219013D02*
X346014Y219379D01*
G01X346029Y218722D02*
X346025Y219013D01*
G01X346033Y218368D02*
X346029Y218722D01*
G01X346036Y217963D02*
X346033Y218368D01*
G01X346038Y217516D02*
X346036Y217963D01*
G01X346040Y217041D02*
X346038Y217516D01*
G01X346040Y216551D02*
Y217041D01*
G01X343739Y225965D02*
X343749Y226239D01*
G01X343733Y225948D02*
X343739Y225965D01*
G01X343728Y226012D02*
X343733Y225948D01*
G01X343740Y224988D02*
X343754Y225353D01*
G01X343733Y224965D02*
X343740Y224988D01*
G01X343725Y225050D02*
X343733Y224965D01*
G01X343661Y226524D02*
X343675Y226037D01*
G01X343655Y226913D02*
X343661Y226524D01*
G01X343650Y227384D02*
X343655Y226913D01*
G01X343646Y227925D02*
X343650Y227384D01*
G01X343643Y228520D02*
X343646Y227925D01*
G01X343641Y229153D02*
X343643Y228520D01*
G01X343640Y229807D02*
X343641Y229153D01*
G01X343636Y231677D02*
X343628Y231750D01*
G01X343639Y231547D02*
X343636Y231677D01*
G01X343643Y231359D02*
X343639Y231547D01*
G01X343646Y231120D02*
X343643Y231359D01*
G01X343648Y230838D02*
X343646Y231120D01*
G01X343650Y230521D02*
X343648Y230838D01*
G01X343651Y230180D02*
X343650Y230521D01*
G01X343651Y229826D02*
Y230180D01*
G01X343667Y227364D02*
X343677Y226999D01*
G01X343663Y227656D02*
X343667Y227364D01*
G01X343659Y228009D02*
X343663Y227656D01*
G01X343656Y228414D02*
X343659Y228009D01*
G01X343653Y228861D02*
X343656Y228414D01*
G01X343652Y229336D02*
X343653Y228861D01*
G01X343651Y229826D02*
X343652Y229336D01*
G01X342021Y225965D02*
X342032Y226012D01*
G01X342015Y226063D02*
X342021Y225965D01*
G01X342010Y226239D02*
X342015Y226063D01*
G01X342106Y228861D02*
X342108Y229826D01*
G01X342104Y228414D02*
X342106Y228861D01*
G01X342100Y228009D02*
X342104Y228414D01*
G01X342097Y227656D02*
X342100Y228009D01*
G01X342092Y227364D02*
X342097Y227656D01*
G01X342087Y227143D02*
X342092Y227364D01*
G01X342082Y226999D02*
X342087Y227143D01*
G01X342110Y230521D02*
X342108Y229826D01*
G01X342111Y230838D02*
X342110Y230521D01*
G01X342114Y231120D02*
X342111Y230838D01*
G01X342117Y231359D02*
X342114Y231120D01*
G01X342120Y231547D02*
X342117Y231359D01*
G01X342124Y231677D02*
X342120Y231547D01*
G01X342128Y231746D02*
X342124Y231677D01*
G01X342132Y231750D02*
X342128Y231746D01*
G01X342116Y228520D02*
X342119Y229807D01*
G01X342113Y227925D02*
X342116Y228520D01*
G01X342109Y227384D02*
X342113Y227925D01*
G01X342104Y226913D02*
X342109Y227384D01*
G01X342098Y226524D02*
X342104Y226913D01*
G01X342091Y226230D02*
X342098Y226524D01*
G01X342084Y226037D02*
X342091Y226230D01*
G01X342019Y224988D02*
X342034Y225050D01*
G01X342012Y225118D02*
X342019Y224988D01*
G01X342005Y225353D02*
X342012Y225118D01*
G01X342011Y220412D02*
X342001Y220138D01*
G01X342017Y220429D02*
X342011Y220412D01*
G01X342022Y220365D02*
X342017Y220429D01*
G01X342010Y221390D02*
X341996Y221024D01*
G01X342017Y221412D02*
X342010Y221390D01*
G01X342025Y221327D02*
X342017Y221412D01*
G01X342089Y219853D02*
X342075Y220340D01*
G01X342095Y219464D02*
X342089Y219853D01*
G01X342100Y218993D02*
X342095Y219464D01*
G01X342104Y218453D02*
X342100Y218993D01*
G01X342107Y217857D02*
X342104Y218453D01*
G01X342109Y217224D02*
X342107Y217857D01*
G01X342110Y216570D02*
X342109Y217224D01*
G01X342114Y214700D02*
X342122Y214627D01*
G01X342111Y214830D02*
X342114Y214700D01*
G01X342107Y215018D02*
X342111Y214830D01*
G01X342104Y215257D02*
X342107Y215018D01*
G01X342102Y215540D02*
X342104Y215257D01*
G01X342100Y215857D02*
X342102Y215540D01*
G01X342099Y216198D02*
X342100Y215857D01*
G01X342099Y216551D02*
Y216198D01*
G01X342083Y219013D02*
X342073Y219379D01*
G01X342087Y218722D02*
X342083Y219013D01*
G01X342091Y218368D02*
X342087Y218722D01*
G01X342094Y217963D02*
X342091Y218368D01*
G01X342097Y217516D02*
X342094Y217963D01*
G01X342098Y217041D02*
X342097Y217516D01*
G01X342099Y216551D02*
X342098Y217041D01*
G01X343729Y220412D02*
X343718Y220365D01*
G01X343735Y220314D02*
X343729Y220412D01*
G01X343740Y220138D02*
X343735Y220314D01*
G01X343644Y217516D02*
X343642Y216551D01*
G01X343646Y217963D02*
X343644Y217516D01*
G01X343649Y218368D02*
X343646Y217963D01*
G01X343653Y218722D02*
X343649Y218368D01*
G01X343658Y219013D02*
X343653Y218722D01*
G01X343663Y219234D02*
X343658Y219013D01*
G01X343668Y219379D02*
X343663Y219234D01*
G01X343640Y215857D02*
X343642Y216551D01*
G01X343639Y215540D02*
X343640Y215857D01*
G01X343636Y215257D02*
X343639Y215540D01*
G01X343633Y215018D02*
X343636Y215257D01*
G01X343630Y214830D02*
X343633Y215018D01*
G01X343626Y214700D02*
X343630Y214830D01*
G01X343622Y214632D02*
X343626Y214700D01*
G01X343618Y214627D02*
X343622Y214632D01*
G01X343634Y217857D02*
X343631Y216570D01*
G01X343637Y218453D02*
X343634Y217857D01*
G01X343641Y218993D02*
X343637Y218453D01*
G01X343646Y219464D02*
X343641Y218993D01*
G01X343652Y219853D02*
X343646Y219464D01*
G01X343659Y220148D02*
X343652Y219853D01*
G01X343666Y220340D02*
X343659Y220148D01*
G01X343731Y221390D02*
X343716Y221327D01*
G01X343738Y221259D02*
X343731Y221390D01*
G01X343744Y221024D02*
X343738Y221259D01*
G01X338079Y225965D02*
X338090Y226012D01*
G01X338074Y226063D02*
X338079Y225965D01*
G01X338069Y226239D02*
X338074Y226063D01*
G01X338164Y228861D02*
X338166Y229826D01*
G01X338162Y228414D02*
X338164Y228861D01*
G01X338159Y228009D02*
X338162Y228414D01*
G01X338155Y227656D02*
X338159Y228009D01*
G01X338151Y227364D02*
X338155Y227656D01*
G01X338146Y227143D02*
X338151Y227364D01*
G01X338140Y226999D02*
X338146Y227143D01*
G01X338175Y228520D02*
X338177Y229807D01*
G01X338171Y227925D02*
X338175Y228520D01*
G01X338167Y227384D02*
X338171Y227925D01*
G01X338162Y226913D02*
X338167Y227384D01*
G01X338156Y226524D02*
X338162Y226913D01*
G01X338150Y226230D02*
X338156Y226524D01*
G01X338143Y226037D02*
X338150Y226230D01*
G01X338078Y224988D02*
X338092Y225050D01*
G01X338071Y225118D02*
X338078Y224988D01*
G01X338064Y225353D02*
X338071Y225118D01*
G01X339797Y225965D02*
X339807Y226239D01*
G01X339791Y225948D02*
X339797Y225965D01*
G01X339786Y226012D02*
X339791Y225948D01*
G01X339798Y224988D02*
X339812Y225353D01*
G01X339791Y224965D02*
X339798Y224988D01*
G01X339784Y225050D02*
X339791Y224965D01*
G01X339720Y226524D02*
X339733Y226037D01*
G01X339714Y226913D02*
X339720Y226524D01*
G01X339709Y227384D02*
X339714Y226913D01*
G01X339704Y227925D02*
X339709Y227384D01*
G01X339701Y228520D02*
X339704Y227925D01*
G01X339699Y229153D02*
X339701Y228520D01*
G01X339699Y229807D02*
Y229153D01*
G01X339725Y227364D02*
X339736Y226999D01*
G01X339721Y227656D02*
X339725Y227364D01*
G01X339717Y228009D02*
X339721Y227656D01*
G01X339714Y228414D02*
X339717Y228009D01*
G01X339712Y228861D02*
X339714Y228414D01*
G01X339710Y229336D02*
X339712Y228861D01*
G01X339710Y229826D02*
Y229336D01*
G01X339797Y220412D02*
X339786Y220365D01*
G01X339802Y220314D02*
X339797Y220412D01*
G01X339807Y220138D02*
X339802Y220314D01*
G01X339712Y217516D02*
X339710Y216551D01*
G01X339714Y217963D02*
X339712Y217516D01*
G01X339717Y218368D02*
X339714Y217963D01*
G01X339721Y218722D02*
X339717Y218368D01*
G01X339725Y219013D02*
X339721Y218722D01*
G01X339730Y219234D02*
X339725Y219013D01*
G01X339736Y219379D02*
X339730Y219234D01*
G01X339701Y217857D02*
X339699Y216570D01*
G01X339704Y218453D02*
X339701Y217857D01*
G01X339709Y218993D02*
X339704Y218453D01*
G01X339714Y219464D02*
X339709Y218993D01*
G01X339720Y219853D02*
X339714Y219464D01*
G01X339726Y220148D02*
X339720Y219853D01*
G01X339733Y220340D02*
X339726Y220148D01*
G01X339798Y221390D02*
X339784Y221327D01*
G01X339805Y221259D02*
X339798Y221390D01*
G01X339812Y221024D02*
X339805Y221259D01*
G01X338079Y220412D02*
X338069Y220138D01*
G01X338084Y220429D02*
X338079Y220412D01*
G01X338090Y220365D02*
X338084Y220429D01*
G01X338078Y221390D02*
X338064Y221024D01*
G01X338085Y221412D02*
X338078Y221390D01*
G01X338092Y221327D02*
X338085Y221412D01*
G01X338156Y219853D02*
X338143Y220340D01*
G01X338162Y219464D02*
X338156Y219853D01*
G01X338167Y218993D02*
X338162Y219464D01*
G01X338171Y218453D02*
X338167Y218993D01*
G01X338175Y217857D02*
X338171Y218453D01*
G01X338177Y217224D02*
X338175Y217857D01*
G01X338177Y216570D02*
Y217224D01*
G01X338151Y219013D02*
X338140Y219379D01*
G01X338155Y218722D02*
X338151Y219013D01*
G01X338159Y218368D02*
X338155Y218722D01*
G01X338162Y217963D02*
X338159Y218368D01*
G01X338164Y217516D02*
X338162Y217963D01*
G01X338166Y217041D02*
X338164Y217516D01*
G01X338166Y216551D02*
Y217041D01*
G01X335865Y225965D02*
X335875Y226239D01*
G01X335859Y225948D02*
X335865Y225965D01*
G01X335854Y226012D02*
X335859Y225948D01*
G01X335866Y224988D02*
X335880Y225353D01*
G01X335859Y224965D02*
X335866Y224988D01*
G01X335851Y225050D02*
X335859Y224965D01*
G01X335787Y226524D02*
X335801Y226037D01*
G01X335781Y226913D02*
X335787Y226524D01*
G01X335776Y227384D02*
X335781Y226913D01*
G01X335772Y227925D02*
X335776Y227384D01*
G01X335769Y228520D02*
X335772Y227925D01*
G01X335767Y229153D02*
X335769Y228520D01*
G01X335766Y229807D02*
X335767Y229153D01*
G01X335762Y231677D02*
X335754Y231750D01*
G01X335765Y231547D02*
X335762Y231677D01*
G01X335769Y231359D02*
X335765Y231547D01*
G01X335772Y231120D02*
X335769Y231359D01*
G01X335774Y230838D02*
X335772Y231120D01*
G01X335776Y230521D02*
X335774Y230838D01*
G01X335777Y230180D02*
X335776Y230521D01*
G01X335777Y229826D02*
Y230180D01*
G01X335793Y227364D02*
X335803Y226999D01*
G01X335789Y227656D02*
X335793Y227364D01*
G01X335785Y228009D02*
X335789Y227656D01*
G01X335782Y228414D02*
X335785Y228009D01*
G01X335779Y228861D02*
X335782Y228414D01*
G01X335778Y229336D02*
X335779Y228861D01*
G01X335777Y229826D02*
X335778Y229336D01*
G01X334147Y225965D02*
X334158Y226012D01*
G01X334141Y226063D02*
X334147Y225965D01*
G01X334136Y226239D02*
X334141Y226063D01*
G01X334232Y228861D02*
X334234Y229826D01*
G01X334230Y228414D02*
X334232Y228861D01*
G01X334226Y228009D02*
X334230Y228414D01*
G01X334223Y227656D02*
X334226Y228009D01*
G01X334218Y227364D02*
X334223Y227656D01*
G01X334213Y227143D02*
X334218Y227364D01*
G01X334208Y226999D02*
X334213Y227143D01*
G01X334236Y230521D02*
X334234Y229826D01*
G01X334237Y230838D02*
X334236Y230521D01*
G01X334240Y231120D02*
X334237Y230838D01*
G01X334243Y231359D02*
X334240Y231120D01*
G01X334246Y231547D02*
X334243Y231359D01*
G01X334250Y231677D02*
X334246Y231547D01*
G01X334254Y231746D02*
X334250Y231677D01*
G01X334258Y231750D02*
X334254Y231746D01*
G01X334242Y228520D02*
X334245Y229807D01*
G01X334239Y227925D02*
X334242Y228520D01*
G01X334235Y227384D02*
X334239Y227925D01*
G01X334230Y226913D02*
X334235Y227384D01*
G01X334224Y226524D02*
X334230Y226913D01*
G01X334217Y226230D02*
X334224Y226524D01*
G01X334210Y226037D02*
X334217Y226230D01*
G01X334145Y224988D02*
X334160Y225050D01*
G01X334138Y225118D02*
X334145Y224988D01*
G01X334131Y225353D02*
X334138Y225118D01*
G01X334137Y220412D02*
X334127Y220138D01*
G01X334143Y220429D02*
X334137Y220412D01*
G01X334148Y220365D02*
X334143Y220429D01*
G01X334136Y221390D02*
X334122Y221024D01*
G01X334143Y221412D02*
X334136Y221390D01*
G01X334151Y221327D02*
X334143Y221412D01*
G01X334215Y219853D02*
X334201Y220340D01*
G01X334221Y219464D02*
X334215Y219853D01*
G01X334226Y218993D02*
X334221Y219464D01*
G01X334230Y218453D02*
X334226Y218993D01*
G01X334233Y217857D02*
X334230Y218453D01*
G01X334235Y217224D02*
X334233Y217857D01*
G01X334236Y216570D02*
X334235Y217224D01*
G01X334240Y214700D02*
X334248Y214627D01*
G01X334237Y214830D02*
X334240Y214700D01*
G01X334233Y215018D02*
X334237Y214830D01*
G01X334230Y215257D02*
X334233Y215018D01*
G01X334228Y215540D02*
X334230Y215257D01*
G01X334226Y215857D02*
X334228Y215540D01*
G01X334225Y216198D02*
X334226Y215857D01*
G01X334225Y216551D02*
Y216198D01*
G01X334209Y219013D02*
X334199Y219379D01*
G01X334213Y218722D02*
X334209Y219013D01*
G01X334217Y218368D02*
X334213Y218722D01*
G01X334220Y217963D02*
X334217Y218368D01*
G01X334223Y217516D02*
X334220Y217963D01*
G01X334224Y217041D02*
X334223Y217516D01*
G01X334225Y216551D02*
X334224Y217041D01*
G01X335855Y220412D02*
X335844Y220365D01*
G01X335861Y220314D02*
X335855Y220412D01*
G01X335866Y220138D02*
X335861Y220314D01*
G01X335770Y217516D02*
X335768Y216551D01*
G01X335772Y217963D02*
X335770Y217516D01*
G01X335775Y218368D02*
X335772Y217963D01*
G01X335779Y218722D02*
X335775Y218368D01*
G01X335784Y219013D02*
X335779Y218722D01*
G01X335789Y219234D02*
X335784Y219013D01*
G01X335794Y219379D02*
X335789Y219234D01*
G01X335766Y215857D02*
X335768Y216551D01*
G01X335765Y215540D02*
X335766Y215857D01*
G01X335762Y215257D02*
X335765Y215540D01*
G01X335759Y215018D02*
X335762Y215257D01*
G01X335756Y214830D02*
X335759Y215018D01*
G01X335752Y214700D02*
X335756Y214830D01*
G01X335748Y214632D02*
X335752Y214700D01*
G01X335744Y214627D02*
X335748Y214632D01*
G01X335760Y217857D02*
X335757Y216570D01*
G01X335763Y218453D02*
X335760Y217857D01*
G01X335767Y218993D02*
X335763Y218453D01*
G01X335772Y219464D02*
X335767Y218993D01*
G01X335778Y219853D02*
X335772Y219464D01*
G01X335785Y220148D02*
X335778Y219853D01*
G01X335792Y220340D02*
X335785Y220148D01*
G01X335857Y221390D02*
X335842Y221327D01*
G01X335864Y221259D02*
X335857Y221390D01*
G01X335870Y221024D02*
X335864Y221259D01*
G01X330205Y225965D02*
X330216Y226012D01*
G01X330200Y226063D02*
X330205Y225965D01*
G01X330195Y226239D02*
X330200Y226063D01*
G01X330290Y228861D02*
X330292Y229826D01*
G01X330288Y228414D02*
X330290Y228861D01*
G01X330285Y228009D02*
X330288Y228414D01*
G01X330281Y227656D02*
X330285Y228009D01*
G01X330277Y227364D02*
X330281Y227656D01*
G01X330272Y227143D02*
X330277Y227364D01*
G01X330266Y226999D02*
X330272Y227143D01*
G01X330301Y228520D02*
X330303Y229807D01*
G01X330297Y227925D02*
X330301Y228520D01*
G01X330293Y227384D02*
X330297Y227925D01*
G01X330288Y226913D02*
X330293Y227384D01*
G01X330282Y226524D02*
X330288Y226913D01*
G01X330276Y226230D02*
X330282Y226524D01*
G01X330269Y226037D02*
X330276Y226230D01*
G01X330204Y224988D02*
X330218Y225050D01*
G01X330197Y225118D02*
X330204Y224988D01*
G01X330190Y225353D02*
X330197Y225118D01*
G01X331924Y224988D02*
X331938Y225353D01*
G01X331917Y224965D02*
X331924Y224988D01*
G01X331910Y225050D02*
X331917Y224965D01*
G01X331846Y226524D02*
X331859Y226037D01*
G01X331840Y226913D02*
X331846Y226524D01*
G01X331835Y227384D02*
X331840Y226913D01*
G01X331830Y227925D02*
X331835Y227384D01*
G01X331827Y228520D02*
X331830Y227925D01*
G01X331825Y229153D02*
X331827Y228520D01*
G01X331825Y229807D02*
Y229153D01*
G01X331851Y227364D02*
X331862Y226999D01*
G01X331847Y227656D02*
X331851Y227364D01*
G01X331843Y228009D02*
X331847Y227656D01*
G01X331840Y228414D02*
X331843Y228009D01*
G01X331838Y228861D02*
X331840Y228414D01*
G01X331836Y229336D02*
X331838Y228861D01*
G01X331836Y229826D02*
Y229336D01*
G01X331923Y225965D02*
X331933Y226239D01*
G01X331917Y225948D02*
X331923Y225965D01*
G01X331912Y226012D02*
X331917Y225948D01*
G01X331923Y220412D02*
X331912Y220365D01*
G01X331928Y220314D02*
X331923Y220412D01*
G01X331933Y220138D02*
X331928Y220314D01*
G01X331838Y217516D02*
X331836Y216551D01*
G01X331840Y217963D02*
X331838Y217516D01*
G01X331843Y218368D02*
X331840Y217963D01*
G01X331847Y218722D02*
X331843Y218368D01*
G01X331851Y219013D02*
X331847Y218722D01*
G01X331856Y219234D02*
X331851Y219013D01*
G01X331862Y219379D02*
X331856Y219234D01*
G01X331827Y217857D02*
X331825Y216570D01*
G01X331830Y218453D02*
X331827Y217857D01*
G01X331835Y218993D02*
X331830Y218453D01*
G01X331840Y219464D02*
X331835Y218993D01*
G01X331846Y219853D02*
X331840Y219464D01*
G01X331852Y220148D02*
X331846Y219853D01*
G01X331859Y220340D02*
X331852Y220148D01*
G01X331924Y221390D02*
X331910Y221327D01*
G01X331931Y221259D02*
X331924Y221390D01*
G01X331938Y221024D02*
X331931Y221259D01*
G01X330204Y221390D02*
X330190Y221024D01*
G01X330211Y221412D02*
X330204Y221390D01*
G01X330218Y221327D02*
X330211Y221412D01*
G01X330282Y219853D02*
X330269Y220340D01*
G01X330288Y219464D02*
X330282Y219853D01*
G01X330293Y218993D02*
X330288Y219464D01*
G01X330297Y218453D02*
X330293Y218993D01*
G01X330301Y217857D02*
X330297Y218453D01*
G01X330302Y217224D02*
X330301Y217857D01*
G01X330303Y216570D02*
X330302Y217224D01*
G01X330277Y219013D02*
X330266Y219379D01*
G01X330281Y218722D02*
X330277Y219013D01*
G01X330285Y218368D02*
X330281Y218722D01*
G01X330288Y217963D02*
X330285Y218368D01*
G01X330290Y217516D02*
X330288Y217963D01*
G01X330292Y217041D02*
X330290Y217516D01*
G01X330292Y216551D02*
Y217041D01*
G01X330205Y220412D02*
X330195Y220138D01*
G01X330210Y220429D02*
X330205Y220412D01*
G01X330216Y220365D02*
X330210Y220429D01*
G01X326273Y225965D02*
X326284Y226012D01*
G01X326267Y226063D02*
X326273Y225965D01*
G01X326262Y226239D02*
X326267Y226063D01*
G01X326358Y228861D02*
X326360Y229826D01*
G01X326356Y228414D02*
X326358Y228861D01*
G01X326352Y228009D02*
X326356Y228414D01*
G01X326349Y227656D02*
X326352Y228009D01*
G01X326344Y227364D02*
X326349Y227656D01*
G01X326339Y227143D02*
X326344Y227364D01*
G01X326334Y226999D02*
X326339Y227143D01*
G01X326362Y230521D02*
X326360Y229826D01*
G01X326363Y230838D02*
X326362Y230521D01*
G01X326366Y231120D02*
X326363Y230838D01*
G01X326369Y231359D02*
X326366Y231120D01*
G01X326372Y231547D02*
X326369Y231359D01*
G01X326376Y231677D02*
X326372Y231547D01*
G01X326380Y231746D02*
X326376Y231677D01*
G01X326384Y231750D02*
X326380Y231746D01*
G01X326368Y228520D02*
X326371Y229807D01*
G01X326365Y227925D02*
X326368Y228520D01*
G01X326361Y227384D02*
X326365Y227925D01*
G01X326356Y226913D02*
X326361Y227384D01*
G01X326350Y226524D02*
X326356Y226913D01*
G01X326343Y226230D02*
X326350Y226524D01*
G01X326336Y226037D02*
X326343Y226230D01*
G01X326271Y224988D02*
X326286Y225050D01*
G01X326264Y225118D02*
X326271Y224988D01*
G01X326257Y225353D02*
X326264Y225118D01*
G01X327992Y224988D02*
X328006Y225353D01*
G01X327985Y224965D02*
X327992Y224988D01*
G01X327977Y225050D02*
X327985Y224965D01*
G01X327913Y226524D02*
X327927Y226037D01*
G01X327907Y226913D02*
X327913Y226524D01*
G01X327902Y227384D02*
X327907Y226913D01*
G01X327898Y227925D02*
X327902Y227384D01*
G01X327895Y228520D02*
X327898Y227925D01*
G01X327893Y229153D02*
X327895Y228520D01*
G01X327892Y229807D02*
X327893Y229153D01*
G01X327888Y231677D02*
X327880Y231750D01*
G01X327891Y231547D02*
X327888Y231677D01*
G01X327895Y231359D02*
X327891Y231547D01*
G01X327898Y231120D02*
X327895Y231359D01*
G01X327900Y230838D02*
X327898Y231120D01*
G01X327902Y230521D02*
X327900Y230838D01*
G01X327903Y230180D02*
X327902Y230521D01*
G01X327903Y229826D02*
Y230180D01*
G01X327919Y227364D02*
X327929Y226999D01*
G01X327915Y227656D02*
X327919Y227364D01*
G01X327911Y228009D02*
X327915Y227656D01*
G01X327908Y228414D02*
X327911Y228009D01*
G01X327905Y228861D02*
X327908Y228414D01*
G01X327904Y229336D02*
X327905Y228861D01*
G01X327903Y229826D02*
X327904Y229336D01*
G01X327991Y225965D02*
X328001Y226239D01*
G01X327985Y225948D02*
X327991Y225965D01*
G01X327980Y226012D02*
X327985Y225948D01*
G01X327981Y220412D02*
X327970Y220365D01*
G01X327987Y220314D02*
X327981Y220412D01*
G01X327992Y220138D02*
X327987Y220314D01*
G01X327896Y217516D02*
X327894Y216551D01*
G01X327898Y217963D02*
X327896Y217516D01*
G01X327901Y218368D02*
X327898Y217963D01*
G01X327905Y218722D02*
X327901Y218368D01*
G01X327910Y219013D02*
X327905Y218722D01*
G01X327915Y219234D02*
X327910Y219013D01*
G01X327920Y219379D02*
X327915Y219234D01*
G01X327892Y215857D02*
X327894Y216551D01*
G01X327891Y215540D02*
X327892Y215857D01*
G01X327888Y215257D02*
X327891Y215540D01*
G01X327885Y215018D02*
X327888Y215257D01*
G01X327882Y214830D02*
X327885Y215018D01*
G01X327878Y214700D02*
X327882Y214830D01*
G01X327874Y214632D02*
X327878Y214700D01*
G01X327870Y214627D02*
X327874Y214632D01*
G01X327886Y217857D02*
X327883Y216570D01*
G01X327889Y218453D02*
X327886Y217857D01*
G01X327893Y218993D02*
X327889Y218453D01*
G01X327898Y219464D02*
X327893Y218993D01*
G01X327904Y219853D02*
X327898Y219464D01*
G01X327911Y220148D02*
X327904Y219853D01*
G01X327918Y220340D02*
X327911Y220148D01*
G01X327983Y221390D02*
X327968Y221327D01*
G01X327990Y221259D02*
X327983Y221390D01*
G01X327996Y221024D02*
X327990Y221259D01*
G01X326262Y221390D02*
X326248Y221024D01*
G01X326269Y221412D02*
X326262Y221390D01*
G01X326277Y221327D02*
X326269Y221412D01*
G01X326341Y219853D02*
X326327Y220340D01*
G01X326346Y219464D02*
X326341Y219853D01*
G01X326352Y218993D02*
X326346Y219464D01*
G01X326356Y218453D02*
X326352Y218993D01*
G01X326359Y217857D02*
X326356Y218453D01*
G01X326361Y217224D02*
X326359Y217857D01*
G01X326362Y216570D02*
X326361Y217224D01*
G01X326366Y214700D02*
X326374Y214627D01*
G01X326363Y214830D02*
X326366Y214700D01*
G01X326359Y215018D02*
X326363Y214830D01*
G01X326356Y215257D02*
X326359Y215018D01*
G01X326354Y215540D02*
X326356Y215257D01*
G01X326352Y215857D02*
X326354Y215540D01*
G01X326351Y216198D02*
X326352Y215857D01*
G01X326351Y216551D02*
Y216198D01*
G01X326335Y219013D02*
X326325Y219379D01*
G01X326339Y218722D02*
X326335Y219013D01*
G01X326343Y218368D02*
X326339Y218722D01*
G01X326346Y217963D02*
X326343Y218368D01*
G01X326349Y217516D02*
X326346Y217963D01*
G01X326350Y217041D02*
X326349Y217516D01*
G01X326351Y216551D02*
X326350Y217041D01*
G01X326263Y220412D02*
X326253Y220138D01*
G01X326269Y220429D02*
X326263Y220412D01*
G01X326274Y220365D02*
X326269Y220429D01*
G01X322331Y225965D02*
X322342Y226012D01*
G01X322326Y226063D02*
X322331Y225965D01*
G01X322321Y226239D02*
X322326Y226063D01*
G01X322416Y228861D02*
X322418Y229826D01*
G01X322414Y228414D02*
X322416Y228861D01*
G01X322411Y228009D02*
X322414Y228414D01*
G01X322407Y227656D02*
X322411Y228009D01*
G01X322403Y227364D02*
X322407Y227656D01*
G01X322398Y227143D02*
X322403Y227364D01*
G01X322392Y226999D02*
X322398Y227143D01*
G01X322427Y228520D02*
X322429Y229807D01*
G01X322423Y227925D02*
X322427Y228520D01*
G01X322419Y227384D02*
X322423Y227925D01*
G01X322414Y226913D02*
X322419Y227384D01*
G01X322408Y226524D02*
X322414Y226913D01*
G01X322402Y226230D02*
X322408Y226524D01*
G01X322395Y226037D02*
X322402Y226230D01*
G01X322330Y224988D02*
X322344Y225050D01*
G01X322323Y225118D02*
X322330Y224988D01*
G01X322316Y225353D02*
X322323Y225118D01*
G01X324050Y224988D02*
X324064Y225353D01*
G01X324043Y224965D02*
X324050Y224988D01*
G01X324036Y225050D02*
X324043Y224965D01*
G01X323972Y226524D02*
X323985Y226037D01*
G01X323966Y226913D02*
X323972Y226524D01*
G01X323961Y227384D02*
X323966Y226913D01*
G01X323956Y227925D02*
X323961Y227384D01*
G01X323953Y228520D02*
X323956Y227925D01*
G01X323951Y229153D02*
X323953Y228520D01*
G01X323951Y229807D02*
Y229153D01*
G01X323977Y227364D02*
X323988Y226999D01*
G01X323973Y227656D02*
X323977Y227364D01*
G01X323969Y228009D02*
X323973Y227656D01*
G01X323966Y228414D02*
X323969Y228009D01*
G01X323964Y228861D02*
X323966Y228414D01*
G01X323962Y229336D02*
X323964Y228861D01*
G01X323962Y229826D02*
Y229336D01*
G01X324049Y225965D02*
X324059Y226239D01*
G01X324043Y225948D02*
X324049Y225965D01*
G01X324038Y226012D02*
X324043Y225948D01*
G01X324049Y220412D02*
X324038Y220365D01*
G01X324054Y220314D02*
X324049Y220412D01*
G01X324059Y220138D02*
X324054Y220314D01*
G01X323964Y217516D02*
X323962Y216551D01*
G01X323966Y217963D02*
X323964Y217516D01*
G01X323969Y218368D02*
X323966Y217963D01*
G01X323973Y218722D02*
X323969Y218368D01*
G01X323977Y219013D02*
X323973Y218722D01*
G01X323982Y219234D02*
X323977Y219013D01*
G01X323988Y219379D02*
X323982Y219234D01*
G01X323953Y217857D02*
X323951Y216570D01*
G01X323956Y218453D02*
X323953Y217857D01*
G01X323961Y218993D02*
X323956Y218453D01*
G01X323966Y219464D02*
X323961Y218993D01*
G01X323972Y219853D02*
X323966Y219464D01*
G01X323978Y220148D02*
X323972Y219853D01*
G01X323985Y220340D02*
X323978Y220148D01*
G01X324050Y221390D02*
X324036Y221327D01*
G01X324057Y221259D02*
X324050Y221390D01*
G01X324064Y221024D02*
X324057Y221259D01*
G01X322330Y221390D02*
X322316Y221024D01*
G01X322337Y221412D02*
X322330Y221390D01*
G01X322344Y221327D02*
X322337Y221412D01*
G01X322408Y219853D02*
X322395Y220340D01*
G01X322414Y219464D02*
X322408Y219853D01*
G01X322419Y218993D02*
X322414Y219464D01*
G01X322423Y218453D02*
X322419Y218993D01*
G01X322427Y217857D02*
X322423Y218453D01*
G01X322428Y217224D02*
X322427Y217857D01*
G01X322429Y216570D02*
X322428Y217224D01*
G01X322403Y219013D02*
X322392Y219379D01*
G01X322407Y218722D02*
X322403Y219013D01*
G01X322411Y218368D02*
X322407Y218722D01*
G01X322414Y217963D02*
X322411Y218368D01*
G01X322416Y217516D02*
X322414Y217963D01*
G01X322418Y217041D02*
X322416Y217516D01*
G01X322418Y216551D02*
Y217041D01*
G01X322331Y220412D02*
X322321Y220138D01*
G01X322336Y220429D02*
X322331Y220412D01*
G01X322342Y220365D02*
X322336Y220429D01*
G01X318399Y225965D02*
X318410Y226012D01*
G01X318393Y226063D02*
X318399Y225965D01*
G01X318388Y226239D02*
X318393Y226063D01*
G01X318484Y228861D02*
X318486Y229826D01*
G01X318482Y228414D02*
X318484Y228861D01*
G01X318478Y228009D02*
X318482Y228414D01*
G01X318475Y227656D02*
X318478Y228009D01*
G01X318470Y227364D02*
X318475Y227656D01*
G01X318465Y227143D02*
X318470Y227364D01*
G01X318460Y226999D02*
X318465Y227143D01*
G01X318487Y230521D02*
X318486Y229826D01*
G01X318489Y230838D02*
X318487Y230521D01*
G01X318492Y231120D02*
X318489Y230838D01*
G01X318495Y231359D02*
X318492Y231120D01*
G01X318498Y231547D02*
X318495Y231359D01*
G01X318502Y231677D02*
X318498Y231547D01*
G01X318506Y231746D02*
X318502Y231677D01*
G01X318510Y231750D02*
X318506Y231746D01*
G01X318494Y228520D02*
X318497Y229807D01*
G01X318491Y227925D02*
X318494Y228520D01*
G01X318487Y227384D02*
X318491Y227925D01*
G01X318482Y226913D02*
X318487Y227384D01*
G01X318476Y226524D02*
X318482Y226913D01*
G01X318469Y226230D02*
X318476Y226524D01*
G01X318462Y226037D02*
X318469Y226230D01*
G01X318397Y224988D02*
X318412Y225050D01*
G01X318390Y225118D02*
X318397Y224988D01*
G01X318383Y225353D02*
X318390Y225118D01*
G01X320118Y224988D02*
X320132Y225353D01*
G01X320111Y224965D02*
X320118Y224988D01*
G01X320103Y225050D02*
X320111Y224965D01*
G01X320039Y226524D02*
X320053Y226037D01*
G01X320033Y226913D02*
X320039Y226524D01*
G01X320028Y227384D02*
X320033Y226913D01*
G01X320024Y227925D02*
X320028Y227384D01*
G01X320021Y228520D02*
X320024Y227925D01*
G01X320019Y229153D02*
X320021Y228520D01*
G01X320018Y229807D02*
X320019Y229153D01*
G01X320013Y231677D02*
X320006Y231750D01*
G01X320017Y231547D02*
X320013Y231677D01*
G01X320021Y231359D02*
X320017Y231547D01*
G01X320023Y231120D02*
X320021Y231359D01*
G01X320026Y230838D02*
X320023Y231120D01*
G01X320028Y230521D02*
X320026Y230838D01*
G01X320029Y230180D02*
X320028Y230521D01*
G01X320029Y229826D02*
Y230180D01*
G01X320045Y227364D02*
X320055Y226999D01*
G01X320041Y227656D02*
X320045Y227364D01*
G01X320037Y228009D02*
X320041Y227656D01*
G01X320034Y228414D02*
X320037Y228009D01*
G01X320031Y228861D02*
X320034Y228414D01*
G01X320030Y229336D02*
X320031Y228861D01*
G01X320029Y229826D02*
X320030Y229336D01*
G01X320117Y225965D02*
X320127Y226239D01*
G01X320111Y225948D02*
X320117Y225965D01*
G01X320106Y226012D02*
X320111Y225948D01*
G01X320107Y220412D02*
X320096Y220365D01*
G01X320113Y220314D02*
X320107Y220412D01*
G01X320118Y220138D02*
X320113Y220314D01*
G01X320022Y217516D02*
X320020Y216551D01*
G01X320024Y217963D02*
X320022Y217516D01*
G01X320027Y218368D02*
X320024Y217963D01*
G01X320031Y218722D02*
X320027Y218368D01*
G01X320036Y219013D02*
X320031Y218722D01*
G01X320041Y219234D02*
X320036Y219013D01*
G01X320046Y219379D02*
X320041Y219234D01*
G01X320018Y215857D02*
X320020Y216551D01*
G01X320017Y215540D02*
X320018Y215857D01*
G01X320014Y215257D02*
X320017Y215540D01*
G01X320011Y215018D02*
X320014Y215257D01*
G01X320008Y214830D02*
X320011Y215018D01*
G01X320004Y214700D02*
X320008Y214830D01*
G01X320000Y214632D02*
X320004Y214700D01*
G01X319996Y214627D02*
X320000Y214632D01*
G01X320012Y217857D02*
X320009Y216570D01*
G01X320015Y218453D02*
X320012Y217857D01*
G01X320019Y218993D02*
X320015Y218453D01*
G01X320024Y219464D02*
X320019Y218993D01*
G01X320030Y219853D02*
X320024Y219464D01*
G01X320037Y220148D02*
X320030Y219853D01*
G01X320044Y220340D02*
X320037Y220148D01*
G01X320109Y221390D02*
X320094Y221327D01*
G01X320116Y221259D02*
X320109Y221390D01*
G01X320122Y221024D02*
X320116Y221259D01*
G01X318388Y221390D02*
X318374Y221024D01*
G01X318395Y221412D02*
X318388Y221390D01*
G01X318403Y221327D02*
X318395Y221412D01*
G01X318467Y219853D02*
X318453Y220340D01*
G01X318472Y219464D02*
X318467Y219853D01*
G01X318478Y218993D02*
X318472Y219464D01*
G01X318482Y218453D02*
X318478Y218993D01*
G01X318485Y217857D02*
X318482Y218453D01*
G01X318487Y217224D02*
X318485Y217857D01*
G01X318488Y216570D02*
X318487Y217224D01*
G01X318492Y214700D02*
X318500Y214627D01*
G01X318489Y214830D02*
X318492Y214700D01*
G01X318485Y215018D02*
X318489Y214830D01*
G01X318482Y215257D02*
X318485Y215018D01*
G01X318480Y215540D02*
X318482Y215257D01*
G01X318478Y215857D02*
X318480Y215540D01*
G01X318477Y216198D02*
X318478Y215857D01*
G01X318477Y216551D02*
Y216198D01*
G01X318461Y219013D02*
X318451Y219379D01*
G01X318465Y218722D02*
X318461Y219013D01*
G01X318469Y218368D02*
X318465Y218722D01*
G01X318472Y217963D02*
X318469Y218368D01*
G01X318475Y217516D02*
X318472Y217963D01*
G01X318476Y217041D02*
X318475Y217516D01*
G01X318477Y216551D02*
X318476Y217041D01*
G01X318389Y220412D02*
X318379Y220138D01*
G01X318395Y220429D02*
X318389Y220412D01*
G01X318400Y220365D02*
X318395Y220429D01*
G01X314457Y225965D02*
X314468Y226012D01*
G01X314452Y226063D02*
X314457Y225965D01*
G01X314447Y226239D02*
X314452Y226063D01*
G01X314542Y228861D02*
X314544Y229826D01*
G01X314540Y228414D02*
X314542Y228861D01*
G01X314537Y228009D02*
X314540Y228414D01*
G01X314533Y227656D02*
X314537Y228009D01*
G01X314529Y227364D02*
X314533Y227656D01*
G01X314524Y227143D02*
X314529Y227364D01*
G01X314518Y226999D02*
X314524Y227143D01*
G01X314553Y228520D02*
X314555Y229807D01*
G01X314549Y227925D02*
X314553Y228520D01*
G01X314545Y227384D02*
X314549Y227925D01*
G01X314540Y226913D02*
X314545Y227384D01*
G01X314534Y226524D02*
X314540Y226913D01*
G01X314528Y226230D02*
X314534Y226524D01*
G01X314521Y226037D02*
X314528Y226230D01*
G01X314456Y224988D02*
X314470Y225050D01*
G01X314449Y225118D02*
X314456Y224988D01*
G01X314442Y225353D02*
X314449Y225118D01*
G01X316175Y225965D02*
X316185Y226239D01*
G01X316169Y225948D02*
X316175Y225965D01*
G01X316164Y226012D02*
X316169Y225948D01*
G01X316176Y224988D02*
X316190Y225353D01*
G01X316169Y224965D02*
X316176Y224988D01*
G01X316162Y225050D02*
X316169Y224965D01*
G01X316098Y226524D02*
X316111Y226037D01*
G01X316092Y226913D02*
X316098Y226524D01*
G01X316087Y227384D02*
X316092Y226913D01*
G01X316082Y227925D02*
X316087Y227384D01*
G01X316079Y228520D02*
X316082Y227925D01*
G01X316077Y229153D02*
X316079Y228520D01*
G01X316077Y229807D02*
Y229153D01*
G01X316103Y227364D02*
X316114Y226999D01*
G01X316099Y227656D02*
X316103Y227364D01*
G01X316095Y228009D02*
X316099Y227656D01*
G01X316092Y228414D02*
X316095Y228009D01*
G01X316090Y228861D02*
X316092Y228414D01*
G01X316088Y229336D02*
X316090Y228861D01*
G01X316088Y229826D02*
Y229336D01*
G01X316175Y220412D02*
X316164Y220365D01*
G01X316180Y220314D02*
X316175Y220412D01*
G01X316185Y220138D02*
X316180Y220314D01*
G01X316090Y217516D02*
X316088Y216551D01*
G01X316092Y217963D02*
X316090Y217516D01*
G01X316095Y218368D02*
X316092Y217963D01*
G01X316099Y218722D02*
X316095Y218368D01*
G01X316103Y219013D02*
X316099Y218722D01*
G01X316108Y219234D02*
X316103Y219013D01*
G01X316114Y219379D02*
X316108Y219234D01*
G01X316079Y217857D02*
X316077Y216570D01*
G01X316082Y218453D02*
X316079Y217857D01*
G01X316087Y218993D02*
X316082Y218453D01*
G01X316092Y219464D02*
X316087Y218993D01*
G01X316098Y219853D02*
X316092Y219464D01*
G01X316104Y220148D02*
X316098Y219853D01*
G01X316111Y220340D02*
X316104Y220148D01*
G01X316176Y221390D02*
X316162Y221327D01*
G01X316183Y221259D02*
X316176Y221390D01*
G01X316190Y221024D02*
X316183Y221259D01*
G01X314457Y220412D02*
X314447Y220138D01*
G01X314462Y220429D02*
X314457Y220412D01*
G01X314468Y220365D02*
X314462Y220429D01*
G01X314456Y221390D02*
X314442Y221024D01*
G01X314463Y221412D02*
X314456Y221390D01*
G01X314470Y221327D02*
X314463Y221412D01*
G01X314534Y219853D02*
X314521Y220340D01*
G01X314540Y219464D02*
X314534Y219853D01*
G01X314545Y218993D02*
X314540Y219464D01*
G01X314549Y218453D02*
X314545Y218993D01*
G01X314553Y217857D02*
X314549Y218453D01*
G01X314554Y217224D02*
X314553Y217857D01*
G01X314555Y216570D02*
X314554Y217224D01*
G01X314529Y219013D02*
X314518Y219379D01*
G01X314533Y218722D02*
X314529Y219013D01*
G01X314537Y218368D02*
X314533Y218722D01*
G01X314540Y217963D02*
X314537Y218368D01*
G01X314542Y217516D02*
X314540Y217963D01*
G01X314544Y217041D02*
X314542Y217516D01*
G01X314544Y216551D02*
Y217041D01*
G01X312243Y225965D02*
X312253Y226239D01*
G01X312237Y225948D02*
X312243Y225965D01*
G01X312232Y226012D02*
X312237Y225948D01*
G01X312244Y224988D02*
X312258Y225353D01*
G01X312237Y224965D02*
X312244Y224988D01*
G01X312229Y225050D02*
X312237Y224965D01*
G01X312165Y226524D02*
X312179Y226037D01*
G01X312159Y226913D02*
X312165Y226524D01*
G01X312154Y227384D02*
X312159Y226913D01*
G01X312150Y227925D02*
X312154Y227384D01*
G01X312147Y228520D02*
X312150Y227925D01*
G01X312145Y229153D02*
X312147Y228520D01*
G01X312144Y229807D02*
X312145Y229153D01*
G01X312139Y231677D02*
X312132Y231750D01*
G01X312143Y231547D02*
X312139Y231677D01*
G01X312147Y231359D02*
X312143Y231547D01*
G01X312149Y231120D02*
X312147Y231359D01*
G01X312152Y230838D02*
X312149Y231120D01*
G01X312154Y230521D02*
X312152Y230838D01*
G01X312155Y230180D02*
X312154Y230521D01*
G01X312155Y229826D02*
Y230180D01*
G01X312171Y227364D02*
X312181Y226999D01*
G01X312167Y227656D02*
X312171Y227364D01*
G01X312163Y228009D02*
X312167Y227656D01*
G01X312160Y228414D02*
X312163Y228009D01*
G01X312157Y228861D02*
X312160Y228414D01*
G01X312156Y229336D02*
X312157Y228861D01*
G01X312155Y229826D02*
X312156Y229336D01*
G01X310525Y225965D02*
X310536Y226012D01*
G01X310519Y226063D02*
X310525Y225965D01*
G01X310514Y226239D02*
X310519Y226063D01*
G01X310610Y228861D02*
X310612Y229826D01*
G01X310608Y228414D02*
X310610Y228861D01*
G01X310604Y228009D02*
X310608Y228414D01*
G01X310601Y227656D02*
X310604Y228009D01*
G01X310596Y227364D02*
X310601Y227656D01*
G01X310591Y227143D02*
X310596Y227364D01*
G01X310586Y226999D02*
X310591Y227143D01*
G01X310613Y230521D02*
X310612Y229826D01*
G01X310615Y230838D02*
X310613Y230521D01*
G01X310618Y231120D02*
X310615Y230838D01*
G01X310621Y231359D02*
X310618Y231120D01*
G01X310624Y231547D02*
X310621Y231359D01*
G01X310628Y231677D02*
X310624Y231547D01*
G01X310632Y231746D02*
X310628Y231677D01*
G01X310636Y231750D02*
X310632Y231746D01*
G01X310620Y228520D02*
X310623Y229807D01*
G01X310617Y227925D02*
X310620Y228520D01*
G01X310613Y227384D02*
X310617Y227925D01*
G01X310608Y226913D02*
X310613Y227384D01*
G01X310602Y226524D02*
X310608Y226913D01*
G01X310595Y226230D02*
X310602Y226524D01*
G01X310588Y226037D02*
X310595Y226230D01*
G01X310523Y224988D02*
X310538Y225050D01*
G01X310516Y225118D02*
X310523Y224988D01*
G01X310509Y225353D02*
X310516Y225118D01*
G01X310515Y220412D02*
X310505Y220138D01*
G01X310521Y220429D02*
X310515Y220412D01*
G01X310526Y220365D02*
X310521Y220429D01*
G01X310514Y221390D02*
X310500Y221024D01*
G01X310521Y221412D02*
X310514Y221390D01*
G01X310529Y221327D02*
X310521Y221412D01*
G01X310593Y219853D02*
X310579Y220340D01*
G01X310598Y219464D02*
X310593Y219853D01*
G01X310604Y218993D02*
X310598Y219464D01*
G01X310608Y218453D02*
X310604Y218993D01*
G01X310611Y217857D02*
X310608Y218453D01*
G01X310613Y217224D02*
X310611Y217857D01*
G01X310614Y216570D02*
X310613Y217224D01*
G01X310618Y214700D02*
X310626Y214627D01*
G01X310615Y214830D02*
X310618Y214700D01*
G01X310611Y215018D02*
X310615Y214830D01*
G01X310608Y215257D02*
X310611Y215018D01*
G01X310606Y215540D02*
X310608Y215257D01*
G01X310604Y215857D02*
X310606Y215540D01*
G01X310603Y216198D02*
X310604Y215857D01*
G01X310603Y216551D02*
Y216198D01*
G01X310587Y219013D02*
X310577Y219379D01*
G01X310591Y218722D02*
X310587Y219013D01*
G01X310595Y218368D02*
X310591Y218722D01*
G01X310598Y217963D02*
X310595Y218368D01*
G01X310601Y217516D02*
X310598Y217963D01*
G01X310602Y217041D02*
X310601Y217516D01*
G01X310603Y216551D02*
X310602Y217041D01*
G01X312233Y220412D02*
X312222Y220365D01*
G01X312239Y220314D02*
X312233Y220412D01*
G01X312244Y220138D02*
X312239Y220314D01*
G01X312148Y217516D02*
X312146Y216551D01*
G01X312150Y217963D02*
X312148Y217516D01*
G01X312153Y218368D02*
X312150Y217963D01*
G01X312157Y218722D02*
X312153Y218368D01*
G01X312162Y219013D02*
X312157Y218722D01*
G01X312167Y219234D02*
X312162Y219013D01*
G01X312172Y219379D02*
X312167Y219234D01*
G01X312144Y215857D02*
X312146Y216551D01*
G01X312143Y215540D02*
X312144Y215857D01*
G01X312140Y215257D02*
X312143Y215540D01*
G01X312137Y215018D02*
X312140Y215257D01*
G01X312134Y214830D02*
X312137Y215018D01*
G01X312130Y214700D02*
X312134Y214830D01*
G01X312126Y214632D02*
X312130Y214700D01*
G01X312122Y214627D02*
X312126Y214632D01*
G01X312138Y217857D02*
X312135Y216570D01*
G01X312141Y218453D02*
X312138Y217857D01*
G01X312145Y218993D02*
X312141Y218453D01*
G01X312150Y219464D02*
X312145Y218993D01*
G01X312156Y219853D02*
X312150Y219464D01*
G01X312162Y220148D02*
X312156Y219853D01*
G01X312169Y220340D02*
X312162Y220148D01*
G01X312234Y221390D02*
X312220Y221327D01*
G01X312242Y221259D02*
X312234Y221390D01*
G01X312248Y221024D02*
X312242Y221259D01*
G01X306583Y225965D02*
X306594Y226012D01*
G01X306578Y226063D02*
X306583Y225965D01*
G01X306573Y226239D02*
X306578Y226063D01*
G01X306668Y228861D02*
X306670Y229826D01*
G01X306666Y228414D02*
X306668Y228861D01*
G01X306663Y228009D02*
X306666Y228414D01*
G01X306659Y227656D02*
X306663Y228009D01*
G01X306654Y227364D02*
X306659Y227656D01*
G01X306650Y227143D02*
X306654Y227364D01*
G01X306644Y226999D02*
X306650Y227143D01*
G01X306678Y228520D02*
X306681Y229807D01*
G01X306675Y227925D02*
X306678Y228520D01*
G01X306671Y227384D02*
X306675Y227925D01*
G01X306666Y226913D02*
X306671Y227384D01*
G01X306660Y226524D02*
X306666Y226913D01*
G01X306654Y226230D02*
X306660Y226524D01*
G01X306647Y226037D02*
X306654Y226230D01*
G01X306582Y224988D02*
X306596Y225050D01*
G01X306575Y225118D02*
X306582Y224988D01*
G01X306568Y225353D02*
X306575Y225118D01*
G01X308301Y225965D02*
X308311Y226239D01*
G01X308295Y225948D02*
X308301Y225965D01*
G01X308290Y226012D02*
X308295Y225948D01*
G01X308302Y224988D02*
X308316Y225353D01*
G01X308295Y224965D02*
X308302Y224988D01*
G01X308288Y225050D02*
X308295Y224965D01*
G01X308224Y226524D02*
X308237Y226037D01*
G01X308218Y226913D02*
X308224Y226524D01*
G01X308213Y227384D02*
X308218Y226913D01*
G01X308208Y227925D02*
X308213Y227384D01*
G01X308205Y228520D02*
X308208Y227925D01*
G01X308203Y229153D02*
X308205Y228520D01*
G01X308203Y229807D02*
Y229153D01*
G01X308229Y227364D02*
X308239Y226999D01*
G01X308225Y227656D02*
X308229Y227364D01*
G01X308221Y228009D02*
X308225Y227656D01*
G01X308218Y228414D02*
X308221Y228009D01*
G01X308216Y228861D02*
X308218Y228414D01*
G01X308214Y229336D02*
X308216Y228861D01*
G01X308214Y229826D02*
Y229336D01*
G01X308301Y220412D02*
X308290Y220365D01*
G01X308306Y220314D02*
X308301Y220412D01*
G01X308311Y220138D02*
X308306Y220314D01*
G01X308216Y217516D02*
X308214Y216551D01*
G01X308218Y217963D02*
X308216Y217516D01*
G01X308221Y218368D02*
X308218Y217963D01*
G01X308225Y218722D02*
X308221Y218368D01*
G01X308229Y219013D02*
X308225Y218722D01*
G01X308234Y219234D02*
X308229Y219013D01*
G01X308239Y219379D02*
X308234Y219234D01*
G01X308205Y217857D02*
X308203Y216570D01*
G01X308208Y218453D02*
X308205Y217857D01*
G01X308213Y218993D02*
X308208Y218453D01*
G01X308218Y219464D02*
X308213Y218993D01*
G01X308224Y219853D02*
X308218Y219464D01*
G01X308230Y220148D02*
X308224Y219853D01*
G01X308237Y220340D02*
X308230Y220148D01*
G01X308302Y221390D02*
X308288Y221327D01*
G01X308309Y221259D02*
X308302Y221390D01*
G01X308316Y221024D02*
X308309Y221259D01*
G01X306583Y220412D02*
X306573Y220138D01*
G01X306588Y220429D02*
X306583Y220412D01*
G01X306594Y220365D02*
X306588Y220429D01*
G01X306582Y221390D02*
X306568Y221024D01*
G01X306589Y221412D02*
X306582Y221390D01*
G01X306596Y221327D02*
X306589Y221412D01*
G01X306660Y219853D02*
X306647Y220340D01*
G01X306666Y219464D02*
X306660Y219853D01*
G01X306671Y218993D02*
X306666Y219464D01*
G01X306675Y218453D02*
X306671Y218993D01*
G01X306678Y217857D02*
X306675Y218453D01*
G01X306680Y217224D02*
X306678Y217857D01*
G01X306681Y216570D02*
X306680Y217224D01*
G01X306654Y219013D02*
X306644Y219379D01*
G01X306659Y218722D02*
X306654Y219013D01*
G01X306663Y218368D02*
X306659Y218722D01*
G01X306666Y217963D02*
X306663Y218368D01*
G01X306668Y217516D02*
X306666Y217963D01*
G01X306670Y217041D02*
X306668Y217516D01*
G01X306670Y216551D02*
Y217041D01*
G01X304369Y225965D02*
X304379Y226239D01*
G01X304363Y225948D02*
X304369Y225965D01*
G01X304358Y226012D02*
X304363Y225948D01*
G01X304370Y224988D02*
X304384Y225353D01*
G01X304363Y224965D02*
X304370Y224988D01*
G01X304355Y225050D02*
X304363Y224965D01*
G01X304291Y226524D02*
X304305Y226037D01*
G01X304285Y226913D02*
X304291Y226524D01*
G01X304280Y227384D02*
X304285Y226913D01*
G01X304276Y227925D02*
X304280Y227384D01*
G01X304273Y228520D02*
X304276Y227925D01*
G01X304271Y229153D02*
X304273Y228520D01*
G01X304270Y229807D02*
X304271Y229153D01*
G01X304265Y231677D02*
X304258Y231750D01*
G01X304269Y231547D02*
X304265Y231677D01*
G01X304273Y231359D02*
X304269Y231547D01*
G01X304275Y231120D02*
X304273Y231359D01*
G01X304278Y230838D02*
X304275Y231120D01*
G01X304280Y230521D02*
X304278Y230838D01*
G01X304281Y230180D02*
X304280Y230521D01*
G01X304281Y229826D02*
Y230180D01*
G01X304297Y227364D02*
X304307Y226999D01*
G01X304293Y227656D02*
X304297Y227364D01*
G01X304289Y228009D02*
X304293Y227656D01*
G01X304286Y228414D02*
X304289Y228009D01*
G01X304283Y228861D02*
X304286Y228414D01*
G01X304282Y229336D02*
X304283Y228861D01*
G01X304281Y229826D02*
X304282Y229336D01*
G01X302651Y225965D02*
X302661Y226012D01*
G01X302645Y226063D02*
X302651Y225965D01*
G01X302640Y226239D02*
X302645Y226063D01*
G01X302736Y228861D02*
X302738Y229826D01*
G01X302734Y228414D02*
X302736Y228861D01*
G01X302730Y228009D02*
X302734Y228414D01*
G01X302727Y227656D02*
X302730Y228009D01*
G01X302722Y227364D02*
X302727Y227656D01*
G01X302717Y227143D02*
X302722Y227364D01*
G01X302712Y226999D02*
X302717Y227143D01*
G01X302739Y230521D02*
X302738Y229826D01*
G01X302741Y230838D02*
X302739Y230521D01*
G01X302744Y231120D02*
X302741Y230838D01*
G01X302747Y231359D02*
X302744Y231120D01*
G01X302750Y231547D02*
X302747Y231359D01*
G01X302754Y231677D02*
X302750Y231547D01*
G01X302758Y231746D02*
X302754Y231677D01*
G01X302762Y231750D02*
X302758Y231746D01*
G01X302746Y228520D02*
X302749Y229807D01*
G01X302743Y227925D02*
X302746Y228520D01*
G01X302739Y227384D02*
X302743Y227925D01*
G01X302734Y226913D02*
X302739Y227384D01*
G01X302728Y226524D02*
X302734Y226913D01*
G01X302721Y226230D02*
X302728Y226524D01*
G01X302714Y226037D02*
X302721Y226230D01*
G01X302649Y224988D02*
X302664Y225050D01*
G01X302642Y225118D02*
X302649Y224988D01*
G01X302635Y225353D02*
X302642Y225118D01*
G01X302641Y220412D02*
X302631Y220138D01*
G01X302647Y220429D02*
X302641Y220412D01*
G01X302652Y220365D02*
X302647Y220429D01*
G01X302640Y221390D02*
X302626Y221024D01*
G01X302647Y221412D02*
X302640Y221390D01*
G01X302654Y221327D02*
X302647Y221412D01*
G01X302719Y219853D02*
X302705Y220340D01*
G01X302724Y219464D02*
X302719Y219853D01*
G01X302730Y218993D02*
X302724Y219464D01*
G01X302734Y218453D02*
X302730Y218993D01*
G01X302737Y217857D02*
X302734Y218453D01*
G01X302739Y217224D02*
X302737Y217857D01*
G01X302740Y216570D02*
X302739Y217224D01*
G01X302744Y214700D02*
X302752Y214627D01*
G01X302741Y214830D02*
X302744Y214700D01*
G01X302737Y215018D02*
X302741Y214830D01*
G01X302734Y215257D02*
X302737Y215018D01*
G01X302732Y215540D02*
X302734Y215257D01*
G01X302730Y215857D02*
X302732Y215540D01*
G01X302729Y216198D02*
X302730Y215857D01*
G01X302729Y216551D02*
Y216198D01*
G01X302713Y219013D02*
X302703Y219379D01*
G01X302717Y218722D02*
X302713Y219013D01*
G01X302721Y218368D02*
X302717Y218722D01*
G01X302724Y217963D02*
X302721Y218368D01*
G01X302727Y217516D02*
X302724Y217963D01*
G01X302728Y217041D02*
X302727Y217516D01*
G01X302729Y216551D02*
X302728Y217041D01*
G01X304359Y220412D02*
X304348Y220365D01*
G01X304365Y220314D02*
X304359Y220412D01*
G01X304370Y220138D02*
X304365Y220314D01*
G01X304274Y217516D02*
X304272Y216551D01*
G01X304276Y217963D02*
X304274Y217516D01*
G01X304279Y218368D02*
X304276Y217963D01*
G01X304283Y218722D02*
X304279Y218368D01*
G01X304288Y219013D02*
X304283Y218722D01*
G01X304293Y219234D02*
X304288Y219013D01*
G01X304298Y219379D02*
X304293Y219234D01*
G01X304270Y215857D02*
X304272Y216551D01*
G01X304269Y215540D02*
X304270Y215857D01*
G01X304266Y215257D02*
X304269Y215540D01*
G01X304263Y215018D02*
X304266Y215257D01*
G01X304260Y214830D02*
X304263Y215018D01*
G01X304256Y214700D02*
X304260Y214830D01*
G01X304252Y214632D02*
X304256Y214700D01*
G01X304248Y214627D02*
X304252Y214632D01*
G01X304264Y217857D02*
X304261Y216570D01*
G01X304267Y218453D02*
X304264Y217857D01*
G01X304271Y218993D02*
X304267Y218453D01*
G01X304276Y219464D02*
X304271Y218993D01*
G01X304282Y219853D02*
X304276Y219464D01*
G01X304288Y220148D02*
X304282Y219853D01*
G01X304295Y220340D02*
X304288Y220148D01*
G01X304360Y221390D02*
X304346Y221327D01*
G01X304368Y221259D02*
X304360Y221390D01*
G01X304374Y221024D02*
X304368Y221259D01*
G01X298709Y225965D02*
X298720Y226012D01*
G01X298704Y226063D02*
X298709Y225965D01*
G01X298698Y226239D02*
X298704Y226063D01*
G01X298794Y228861D02*
X298796Y229826D01*
G01X298792Y228414D02*
X298794Y228861D01*
G01X298789Y228009D02*
X298792Y228414D01*
G01X298785Y227656D02*
X298789Y228009D01*
G01X298780Y227364D02*
X298785Y227656D01*
G01X298776Y227143D02*
X298780Y227364D01*
G01X298770Y226999D02*
X298776Y227143D01*
G01X298804Y228520D02*
X298807Y229807D01*
G01X298801Y227925D02*
X298804Y228520D01*
G01X298797Y227384D02*
X298801Y227925D01*
G01X298792Y226913D02*
X298797Y227384D01*
G01X298786Y226524D02*
X298792Y226913D01*
G01X298780Y226230D02*
X298786Y226524D01*
G01X298773Y226037D02*
X298780Y226230D01*
G01X298708Y224988D02*
X298722Y225050D01*
G01X298701Y225118D02*
X298708Y224988D01*
G01X298694Y225353D02*
X298701Y225118D01*
G01X300427Y225965D02*
X300437Y226239D01*
G01X300421Y225948D02*
X300427Y225965D01*
G01X300416Y226012D02*
X300421Y225948D01*
G01X300428Y224988D02*
X300442Y225353D01*
G01X300421Y224965D02*
X300428Y224988D01*
G01X300414Y225050D02*
X300421Y224965D01*
G01X300350Y226524D02*
X300363Y226037D01*
G01X300344Y226913D02*
X300350Y226524D01*
G01X300339Y227384D02*
X300344Y226913D01*
G01X300334Y227925D02*
X300339Y227384D01*
G01X300331Y228520D02*
X300334Y227925D01*
G01X300329Y229153D02*
X300331Y228520D01*
G01X300329Y229807D02*
Y229153D01*
G01X300355Y227364D02*
X300365Y226999D01*
G01X300351Y227656D02*
X300355Y227364D01*
G01X300347Y228009D02*
X300351Y227656D01*
G01X300344Y228414D02*
X300347Y228009D01*
G01X300342Y228861D02*
X300344Y228414D01*
G01X300340Y229336D02*
X300342Y228861D01*
G01X300340Y229826D02*
Y229336D01*
G01X300427Y220412D02*
X300416Y220365D01*
G01X300432Y220314D02*
X300427Y220412D01*
G01X300437Y220138D02*
X300432Y220314D01*
G01X300342Y217516D02*
X300340Y216551D01*
G01X300344Y217963D02*
X300342Y217516D01*
G01X300347Y218368D02*
X300344Y217963D01*
G01X300351Y218722D02*
X300347Y218368D01*
G01X300355Y219013D02*
X300351Y218722D01*
G01X300360Y219234D02*
X300355Y219013D01*
G01X300365Y219379D02*
X300360Y219234D01*
G01X300331Y217857D02*
X300329Y216570D01*
G01X300334Y218453D02*
X300331Y217857D01*
G01X300339Y218993D02*
X300334Y218453D01*
G01X300344Y219464D02*
X300339Y218993D01*
G01X300350Y219853D02*
X300344Y219464D01*
G01X300356Y220148D02*
X300350Y219853D01*
G01X300363Y220340D02*
X300356Y220148D01*
G01X300428Y221390D02*
X300414Y221327D01*
G01X300435Y221259D02*
X300428Y221390D01*
G01X300442Y221024D02*
X300435Y221259D01*
G01X298709Y220412D02*
X298698Y220138D01*
G01X298714Y220429D02*
X298709Y220412D01*
G01X298720Y220365D02*
X298714Y220429D01*
G01X298708Y221390D02*
X298694Y221024D01*
G01X298715Y221412D02*
X298708Y221390D01*
G01X298722Y221327D02*
X298715Y221412D01*
G01X298786Y219853D02*
X298773Y220340D01*
G01X298792Y219464D02*
X298786Y219853D01*
G01X298797Y218993D02*
X298792Y219464D01*
G01X298801Y218453D02*
X298797Y218993D01*
G01X298804Y217857D02*
X298801Y218453D01*
G01X298806Y217224D02*
X298804Y217857D01*
G01X298807Y216570D02*
X298806Y217224D01*
G01X298780Y219013D02*
X298770Y219379D01*
G01X298785Y218722D02*
X298780Y219013D01*
G01X298789Y218368D02*
X298785Y218722D01*
G01X298792Y217963D02*
X298789Y218368D01*
G01X298794Y217516D02*
X298792Y217963D01*
G01X298796Y217041D02*
X298794Y217516D01*
G01X298796Y216551D02*
Y217041D01*
G01X296495Y225965D02*
X296505Y226239D01*
G01X296489Y225948D02*
X296495Y225965D01*
G01X296484Y226012D02*
X296489Y225948D01*
G01X296496Y224988D02*
X296510Y225353D01*
G01X296489Y224965D02*
X296496Y224988D01*
G01X296481Y225050D02*
X296489Y224965D01*
G01X296417Y226524D02*
X296431Y226037D01*
G01X296411Y226913D02*
X296417Y226524D01*
G01X296406Y227384D02*
X296411Y226913D01*
G01X296402Y227925D02*
X296406Y227384D01*
G01X296399Y228520D02*
X296402Y227925D01*
G01X296397Y229153D02*
X296399Y228520D01*
G01X296396Y229807D02*
X296397Y229153D01*
G01X296391Y231677D02*
X296384Y231750D01*
G01X296395Y231547D02*
X296391Y231677D01*
G01X296399Y231359D02*
X296395Y231547D01*
G01X296401Y231120D02*
X296399Y231359D01*
G01X296404Y230838D02*
X296401Y231120D01*
G01X296406Y230521D02*
X296404Y230838D01*
G01X296407Y230180D02*
X296406Y230521D01*
G01X296407Y229826D02*
Y230180D01*
G01X296423Y227364D02*
X296433Y226999D01*
G01X296419Y227656D02*
X296423Y227364D01*
G01X296415Y228009D02*
X296419Y227656D01*
G01X296412Y228414D02*
X296415Y228009D01*
G01X296409Y228861D02*
X296412Y228414D01*
G01X296408Y229336D02*
X296409Y228861D01*
G01X296407Y229826D02*
X296408Y229336D01*
G01X294777Y225965D02*
X294787Y226012D01*
G01X294771Y226063D02*
X294777Y225965D01*
G01X294766Y226239D02*
X294771Y226063D01*
G01X294862Y228861D02*
X294864Y229826D01*
G01X294860Y228414D02*
X294862Y228861D01*
G01X294856Y228009D02*
X294860Y228414D01*
G01X294853Y227656D02*
X294856Y228009D01*
G01X294848Y227364D02*
X294853Y227656D01*
G01X294843Y227143D02*
X294848Y227364D01*
G01X294838Y226999D02*
X294843Y227143D01*
G01X294865Y230521D02*
X294864Y229826D01*
G01X294867Y230838D02*
X294865Y230521D01*
G01X294870Y231120D02*
X294867Y230838D01*
G01X294873Y231359D02*
X294870Y231120D01*
G01X294876Y231547D02*
X294873Y231359D01*
G01X294880Y231677D02*
X294876Y231547D01*
G01X294884Y231746D02*
X294880Y231677D01*
G01X294888Y231750D02*
X294884Y231746D01*
G01X294872Y228520D02*
X294875Y229807D01*
G01X294869Y227925D02*
X294872Y228520D01*
G01X294865Y227384D02*
X294869Y227925D01*
G01X294860Y226913D02*
X294865Y227384D01*
G01X294854Y226524D02*
X294860Y226913D01*
G01X294847Y226230D02*
X294854Y226524D01*
G01X294840Y226037D02*
X294847Y226230D01*
G01X294775Y224988D02*
X294790Y225050D01*
G01X294768Y225118D02*
X294775Y224988D01*
G01X294761Y225353D02*
X294768Y225118D01*
G01X294767Y220412D02*
X294757Y220138D01*
G01X294773Y220429D02*
X294767Y220412D01*
G01X294778Y220365D02*
X294773Y220429D01*
G01X294766Y221390D02*
X294752Y221024D01*
G01X294773Y221412D02*
X294766Y221390D01*
G01X294780Y221327D02*
X294773Y221412D01*
G01X294845Y219853D02*
X294831Y220340D01*
G01X294850Y219464D02*
X294845Y219853D01*
G01X294856Y218993D02*
X294850Y219464D01*
G01X294860Y218453D02*
X294856Y218993D01*
G01X294863Y217857D02*
X294860Y218453D01*
G01X294865Y217224D02*
X294863Y217857D01*
G01X294865Y216570D02*
Y217224D01*
G01X294870Y214700D02*
X294878Y214627D01*
G01X294867Y214830D02*
X294870Y214700D01*
G01X294863Y215018D02*
X294867Y214830D01*
G01X294860Y215257D02*
X294863Y215018D01*
G01X294858Y215540D02*
X294860Y215257D01*
G01X294856Y215857D02*
X294858Y215540D01*
G01X294855Y216198D02*
X294856Y215857D01*
G01X294855Y216551D02*
Y216198D01*
G01X294839Y219013D02*
X294829Y219379D01*
G01X294843Y218722D02*
X294839Y219013D01*
G01X294847Y218368D02*
X294843Y218722D01*
G01X294850Y217963D02*
X294847Y218368D01*
G01X294853Y217516D02*
X294850Y217963D01*
G01X294854Y217041D02*
X294853Y217516D01*
G01X294855Y216551D02*
X294854Y217041D01*
G01X296485Y220412D02*
X296474Y220365D01*
G01X296491Y220314D02*
X296485Y220412D01*
G01X296496Y220138D02*
X296491Y220314D01*
G01X296400Y217516D02*
X296398Y216551D01*
G01X296402Y217963D02*
X296400Y217516D01*
G01X296405Y218368D02*
X296402Y217963D01*
G01X296409Y218722D02*
X296405Y218368D01*
G01X296414Y219013D02*
X296409Y218722D01*
G01X296419Y219234D02*
X296414Y219013D01*
G01X296424Y219379D02*
X296419Y219234D01*
G01X296396Y215857D02*
X296398Y216551D01*
G01X296395Y215540D02*
X296396Y215857D01*
G01X296392Y215257D02*
X296395Y215540D01*
G01X296389Y215018D02*
X296392Y215257D01*
G01X296386Y214830D02*
X296389Y215018D01*
G01X296382Y214700D02*
X296386Y214830D01*
G01X296378Y214632D02*
X296382Y214700D01*
G01X296374Y214627D02*
X296378Y214632D01*
G01X296390Y217857D02*
X296387Y216570D01*
G01X296393Y218453D02*
X296390Y217857D01*
G01X296397Y218993D02*
X296393Y218453D01*
G01X296402Y219464D02*
X296397Y218993D01*
G01X296408Y219853D02*
X296402Y219464D01*
G01X296414Y220148D02*
X296408Y219853D01*
G01X296421Y220340D02*
X296414Y220148D01*
G01X296486Y221390D02*
X296472Y221327D01*
G01X296494Y221259D02*
X296486Y221390D01*
G01X296500Y221024D02*
X296494Y221259D01*
G01X290835Y225965D02*
X290846Y226012D01*
G01X290830Y226063D02*
X290835Y225965D01*
G01X290824Y226239D02*
X290830Y226063D01*
G01X290920Y228861D02*
X290922Y229826D01*
G01X290918Y228414D02*
X290920Y228861D01*
G01X290915Y228009D02*
X290918Y228414D01*
G01X290911Y227656D02*
X290915Y228009D01*
G01X290906Y227364D02*
X290911Y227656D01*
G01X290902Y227143D02*
X290906Y227364D01*
G01X290896Y226999D02*
X290902Y227143D01*
G01X290930Y228520D02*
X290933Y229807D01*
G01X290927Y227925D02*
X290930Y228520D01*
G01X290923Y227384D02*
X290927Y227925D01*
G01X290918Y226913D02*
X290923Y227384D01*
G01X290912Y226524D02*
X290918Y226913D01*
G01X290906Y226230D02*
X290912Y226524D01*
G01X290899Y226037D02*
X290906Y226230D01*
G01X290834Y224988D02*
X290848Y225050D01*
G01X290826Y225118D02*
X290834Y224988D01*
G01X290820Y225353D02*
X290826Y225118D01*
G01X292553Y225965D02*
X292563Y226239D01*
G01X292547Y225948D02*
X292553Y225965D01*
G01X292542Y226012D02*
X292547Y225948D01*
G01X292554Y224988D02*
X292568Y225353D01*
G01X292547Y224965D02*
X292554Y224988D01*
G01X292540Y225050D02*
X292547Y224965D01*
G01X292476Y226524D02*
X292489Y226037D01*
G01X292470Y226913D02*
X292476Y226524D01*
G01X292465Y227384D02*
X292470Y226913D01*
G01X292460Y227925D02*
X292465Y227384D01*
G01X292457Y228520D02*
X292460Y227925D01*
G01X292455Y229153D02*
X292457Y228520D01*
G01X292455Y229807D02*
Y229153D01*
G01X292481Y227364D02*
X292491Y226999D01*
G01X292477Y227656D02*
X292481Y227364D01*
G01X292473Y228009D02*
X292477Y227656D01*
G01X292470Y228414D02*
X292473Y228009D01*
G01X292468Y228861D02*
X292470Y228414D01*
G01X292466Y229336D02*
X292468Y228861D01*
G01X292466Y229826D02*
Y229336D01*
G01X292553Y220412D02*
X292542Y220365D01*
G01X292558Y220314D02*
X292553Y220412D01*
G01X292563Y220138D02*
X292558Y220314D01*
G01X292468Y217516D02*
X292466Y216551D01*
G01X292470Y217963D02*
X292468Y217516D01*
G01X292473Y218368D02*
X292470Y217963D01*
G01X292477Y218722D02*
X292473Y218368D01*
G01X292481Y219013D02*
X292477Y218722D01*
G01X292486Y219234D02*
X292481Y219013D01*
G01X292491Y219379D02*
X292486Y219234D01*
G01X292457Y217857D02*
X292455Y216570D01*
G01X292460Y218453D02*
X292457Y217857D01*
G01X292465Y218993D02*
X292460Y218453D01*
G01X292470Y219464D02*
X292465Y218993D01*
G01X292476Y219853D02*
X292470Y219464D01*
G01X292482Y220148D02*
X292476Y219853D01*
G01X292489Y220340D02*
X292482Y220148D01*
G01X292554Y221390D02*
X292540Y221327D01*
G01X292561Y221259D02*
X292554Y221390D01*
G01X292568Y221024D02*
X292561Y221259D01*
G01X290835Y220412D02*
X290824Y220138D01*
G01X290840Y220429D02*
X290835Y220412D01*
G01X290846Y220365D02*
X290840Y220429D01*
G01X290834Y221390D02*
X290820Y221024D01*
G01X290841Y221412D02*
X290834Y221390D01*
G01X290848Y221327D02*
X290841Y221412D01*
G01X290912Y219853D02*
X290899Y220340D01*
G01X290918Y219464D02*
X290912Y219853D01*
G01X290923Y218993D02*
X290918Y219464D01*
G01X290927Y218453D02*
X290923Y218993D01*
G01X290930Y217857D02*
X290927Y218453D01*
G01X290932Y217224D02*
X290930Y217857D01*
G01X290933Y216570D02*
X290932Y217224D01*
G01X290906Y219013D02*
X290896Y219379D01*
G01X290911Y218722D02*
X290906Y219013D01*
G01X290915Y218368D02*
X290911Y218722D01*
G01X290918Y217963D02*
X290915Y218368D01*
G01X290920Y217516D02*
X290918Y217963D01*
G01X290922Y217041D02*
X290920Y217516D01*
G01X290922Y216551D02*
Y217041D01*
G01X288620Y225965D02*
X288631Y226239D01*
G01X288615Y225948D02*
X288620Y225965D01*
G01X288610Y226012D02*
X288615Y225948D01*
G01X288622Y224988D02*
X288636Y225353D01*
G01X288615Y224965D02*
X288622Y224988D01*
G01X288607Y225050D02*
X288615Y224965D01*
G01X288543Y226524D02*
X288557Y226037D01*
G01X288537Y226913D02*
X288543Y226524D01*
G01X288532Y227384D02*
X288537Y226913D01*
G01X288528Y227925D02*
X288532Y227384D01*
G01X288525Y228520D02*
X288528Y227925D01*
G01X288523Y229153D02*
X288525Y228520D01*
G01X288522Y229807D02*
X288523Y229153D01*
G01X288517Y231677D02*
X288510Y231750D01*
G01X288521Y231547D02*
X288517Y231677D01*
G01X288524Y231359D02*
X288521Y231547D01*
G01X288527Y231120D02*
X288524Y231359D01*
G01X288530Y230838D02*
X288527Y231120D01*
G01X288532Y230521D02*
X288530Y230838D01*
G01X288533Y230180D02*
X288532Y230521D01*
G01X288533Y229826D02*
Y230180D01*
G01X288549Y227364D02*
X288559Y226999D01*
G01X288545Y227656D02*
X288549Y227364D01*
G01X288541Y228009D02*
X288545Y227656D01*
G01X288538Y228414D02*
X288541Y228009D01*
G01X288535Y228861D02*
X288538Y228414D01*
G01X288534Y229336D02*
X288535Y228861D01*
G01X288533Y229826D02*
X288534Y229336D01*
G01X286903Y225965D02*
X286913Y226012D01*
G01X286897Y226063D02*
X286903Y225965D01*
G01X286892Y226239D02*
X286897Y226063D01*
G01X286988Y228861D02*
X286990Y229826D01*
G01X286985Y228414D02*
X286988Y228861D01*
G01X286982Y228009D02*
X286985Y228414D01*
G01X286979Y227656D02*
X286982Y228009D01*
G01X286974Y227364D02*
X286979Y227656D01*
G01X286969Y227143D02*
X286974Y227364D01*
G01X286964Y226999D02*
X286969Y227143D01*
G01X286991Y230521D02*
X286990Y229826D01*
G01X286993Y230838D02*
X286991Y230521D01*
G01X286996Y231120D02*
X286993Y230838D01*
G01X286999Y231359D02*
X286996Y231120D01*
G01X287002Y231547D02*
X286999Y231359D01*
G01X287006Y231677D02*
X287002Y231547D01*
G01X287010Y231746D02*
X287006Y231677D01*
G01X287014Y231750D02*
X287010Y231746D01*
G01X286998Y228520D02*
X287001Y229807D01*
G01X286995Y227925D02*
X286998Y228520D01*
G01X286991Y227384D02*
X286995Y227925D01*
G01X286986Y226913D02*
X286991Y227384D01*
G01X286980Y226524D02*
X286986Y226913D01*
G01X286973Y226230D02*
X286980Y226524D01*
G01X286966Y226037D02*
X286973Y226230D01*
G01X286901Y224988D02*
X286916Y225050D01*
G01X286894Y225118D02*
X286901Y224988D01*
G01X286887Y225353D02*
X286894Y225118D01*
G01X286893Y220412D02*
X286883Y220138D01*
G01X286899Y220429D02*
X286893Y220412D01*
G01X286904Y220365D02*
X286899Y220429D01*
G01X286892Y221390D02*
X286878Y221024D01*
G01X286899Y221412D02*
X286892Y221390D01*
G01X286906Y221327D02*
X286899Y221412D01*
G01X286971Y219853D02*
X286957Y220340D01*
G01X286976Y219464D02*
X286971Y219853D01*
G01X286982Y218993D02*
X286976Y219464D01*
G01X286986Y218453D02*
X286982Y218993D01*
G01X286989Y217857D02*
X286986Y218453D01*
G01X286991Y217224D02*
X286989Y217857D01*
G01X286991Y216570D02*
Y217224D01*
G01X286996Y214700D02*
X287004Y214627D01*
G01X286993Y214830D02*
X286996Y214700D01*
G01X286989Y215018D02*
X286993Y214830D01*
G01X286986Y215257D02*
X286989Y215018D01*
G01X286984Y215540D02*
X286986Y215257D01*
G01X286982Y215857D02*
X286984Y215540D01*
G01X286981Y216198D02*
X286982Y215857D01*
G01X286981Y216551D02*
Y216198D01*
G01X286965Y219013D02*
X286955Y219379D01*
G01X286969Y218722D02*
X286965Y219013D01*
G01X286973Y218368D02*
X286969Y218722D01*
G01X286976Y217963D02*
X286973Y218368D01*
G01X286978Y217516D02*
X286976Y217963D01*
G01X286980Y217041D02*
X286978Y217516D01*
G01X286981Y216551D02*
X286980Y217041D01*
G01X288611Y220412D02*
X288600Y220365D01*
G01X288617Y220314D02*
X288611Y220412D01*
G01X288622Y220138D02*
X288617Y220314D01*
G01X288526Y217516D02*
X288524Y216551D01*
G01X288528Y217963D02*
X288526Y217516D01*
G01X288531Y218368D02*
X288528Y217963D01*
G01X288535Y218722D02*
X288531Y218368D01*
G01X288540Y219013D02*
X288535Y218722D01*
G01X288545Y219234D02*
X288540Y219013D01*
G01X288550Y219379D02*
X288545Y219234D01*
G01X288522Y215857D02*
X288524Y216551D01*
G01X288521Y215540D02*
X288522Y215857D01*
G01X288518Y215257D02*
X288521Y215540D01*
G01X288515Y215018D02*
X288518Y215257D01*
G01X288512Y214830D02*
X288515Y215018D01*
G01X288508Y214700D02*
X288512Y214830D01*
G01X288504Y214632D02*
X288508Y214700D01*
G01X288500Y214627D02*
X288504Y214632D01*
G01X288516Y217857D02*
X288513Y216570D01*
G01X288519Y218453D02*
X288516Y217857D01*
G01X288523Y218993D02*
X288519Y218453D01*
G01X288528Y219464D02*
X288523Y218993D01*
G01X288534Y219853D02*
X288528Y219464D01*
G01X288540Y220148D02*
X288534Y219853D01*
G01X288547Y220340D02*
X288540Y220148D01*
G01X288612Y221390D02*
X288598Y221327D01*
G01X288620Y221259D02*
X288612Y221390D01*
G01X288626Y221024D02*
X288620Y221259D01*
G01X282961Y225965D02*
X282972Y226012D01*
G01X282956Y226063D02*
X282961Y225965D01*
G01X282950Y226239D02*
X282956Y226063D01*
G01X283046Y228861D02*
X283048Y229826D01*
G01X283044Y228414D02*
X283046Y228861D01*
G01X283041Y228009D02*
X283044Y228414D01*
G01X283037Y227656D02*
X283041Y228009D01*
G01X283032Y227364D02*
X283037Y227656D01*
G01X283028Y227143D02*
X283032Y227364D01*
G01X283022Y226999D02*
X283028Y227143D01*
G01X283056Y228520D02*
X283059Y229807D01*
G01X283053Y227925D02*
X283056Y228520D01*
G01X283049Y227384D02*
X283053Y227925D01*
G01X283044Y226913D02*
X283049Y227384D01*
G01X283038Y226524D02*
X283044Y226913D01*
G01X283032Y226230D02*
X283038Y226524D01*
G01X283025Y226037D02*
X283032Y226230D01*
G01X282960Y224988D02*
X282974Y225050D01*
G01X282952Y225118D02*
X282960Y224988D01*
G01X282946Y225353D02*
X282952Y225118D01*
G01X284679Y225965D02*
X284689Y226239D01*
G01X284673Y225948D02*
X284679Y225965D01*
G01X284668Y226012D02*
X284673Y225948D01*
G01X284680Y224988D02*
X284694Y225353D01*
G01X284673Y224965D02*
X284680Y224988D01*
G01X284666Y225050D02*
X284673Y224965D01*
G01X284602Y226524D02*
X284615Y226037D01*
G01X284596Y226913D02*
X284602Y226524D01*
G01X284591Y227384D02*
X284596Y226913D01*
G01X284586Y227925D02*
X284591Y227384D01*
G01X284583Y228520D02*
X284586Y227925D01*
G01X284581Y229153D02*
X284583Y228520D01*
G01X284581Y229807D02*
Y229153D01*
G01X284607Y227364D02*
X284617Y226999D01*
G01X284603Y227656D02*
X284607Y227364D01*
G01X284599Y228009D02*
X284603Y227656D01*
G01X284596Y228414D02*
X284599Y228009D01*
G01X284594Y228861D02*
X284596Y228414D01*
G01X284592Y229336D02*
X284594Y228861D01*
G01X284592Y229826D02*
Y229336D01*
G01X284679Y220412D02*
X284668Y220365D01*
G01X284684Y220314D02*
X284679Y220412D01*
G01X284689Y220138D02*
X284684Y220314D01*
G01X284594Y217516D02*
X284592Y216551D01*
G01X284596Y217963D02*
X284594Y217516D01*
G01X284599Y218368D02*
X284596Y217963D01*
G01X284603Y218722D02*
X284599Y218368D01*
G01X284607Y219013D02*
X284603Y218722D01*
G01X284612Y219234D02*
X284607Y219013D01*
G01X284617Y219379D02*
X284612Y219234D01*
G01X284583Y217857D02*
X284581Y216570D01*
G01X284586Y218453D02*
X284583Y217857D01*
G01X284591Y218993D02*
X284586Y218453D01*
G01X284596Y219464D02*
X284591Y218993D01*
G01X284602Y219853D02*
X284596Y219464D01*
G01X284608Y220148D02*
X284602Y219853D01*
G01X284615Y220340D02*
X284608Y220148D01*
G01X284680Y221390D02*
X284666Y221327D01*
G01X284687Y221259D02*
X284680Y221390D01*
G01X284694Y221024D02*
X284687Y221259D01*
G01X282961Y220412D02*
X282950Y220138D01*
G01X282966Y220429D02*
X282961Y220412D01*
G01X282972Y220365D02*
X282966Y220429D01*
G01X282960Y221390D02*
X282946Y221024D01*
G01X282967Y221412D02*
X282960Y221390D01*
G01X282974Y221327D02*
X282967Y221412D01*
G01X283038Y219853D02*
X283025Y220340D01*
G01X283044Y219464D02*
X283038Y219853D01*
G01X283049Y218993D02*
X283044Y219464D01*
G01X283053Y218453D02*
X283049Y218993D01*
G01X283056Y217857D02*
X283053Y218453D01*
G01X283058Y217224D02*
X283056Y217857D01*
G01X283059Y216570D02*
X283058Y217224D01*
G01X283032Y219013D02*
X283022Y219379D01*
G01X283037Y218722D02*
X283032Y219013D01*
G01X283041Y218368D02*
X283037Y218722D01*
G01X283044Y217963D02*
X283041Y218368D01*
G01X283046Y217516D02*
X283044Y217963D01*
G01X283048Y217041D02*
X283046Y217516D01*
G01X283048Y216551D02*
Y217041D01*
G01X280746Y225965D02*
X280757Y226239D01*
G01X280741Y225948D02*
X280746Y225965D01*
G01X280736Y226012D02*
X280741Y225948D01*
G01X280748Y224988D02*
X280762Y225353D01*
G01X280740Y224965D02*
X280748Y224988D01*
G01X280733Y225050D02*
X280740Y224965D01*
G01X280669Y226524D02*
X280683Y226037D01*
G01X280663Y226913D02*
X280669Y226524D01*
G01X280658Y227384D02*
X280663Y226913D01*
G01X280654Y227925D02*
X280658Y227384D01*
G01X280651Y228520D02*
X280654Y227925D01*
G01X280649Y229153D02*
X280651Y228520D01*
G01X280648Y229807D02*
X280649Y229153D01*
G01X280643Y231677D02*
X280636Y231750D01*
G01X280647Y231547D02*
X280643Y231677D01*
G01X280650Y231359D02*
X280647Y231547D01*
G01X280653Y231120D02*
X280650Y231359D01*
G01X280656Y230838D02*
X280653Y231120D01*
G01X280658Y230521D02*
X280656Y230838D01*
G01X280659Y230180D02*
X280658Y230521D01*
G01X280659Y229826D02*
Y230180D01*
G01X280675Y227364D02*
X280685Y226999D01*
G01X280671Y227656D02*
X280675Y227364D01*
G01X280667Y228009D02*
X280671Y227656D01*
G01X280664Y228414D02*
X280667Y228009D01*
G01X280661Y228861D02*
X280664Y228414D01*
G01X280660Y229336D02*
X280661Y228861D01*
G01X280659Y229826D02*
X280660Y229336D01*
G01X279029Y225965D02*
X279039Y226012D01*
G01X279023Y226063D02*
X279029Y225965D01*
G01X279018Y226239D02*
X279023Y226063D01*
G01X279114Y228861D02*
X279116Y229826D01*
G01X279111Y228414D02*
X279114Y228861D01*
G01X279108Y228009D02*
X279111Y228414D01*
G01X279105Y227656D02*
X279108Y228009D01*
G01X279100Y227364D02*
X279105Y227656D01*
G01X279095Y227143D02*
X279100Y227364D01*
G01X279090Y226999D02*
X279095Y227143D01*
G01X279117Y230521D02*
X279116Y229826D01*
G01X279119Y230838D02*
X279117Y230521D01*
G01X279122Y231120D02*
X279119Y230838D01*
G01X279125Y231359D02*
X279122Y231120D01*
G01X279128Y231547D02*
X279125Y231359D01*
G01X279132Y231677D02*
X279128Y231547D01*
G01X279136Y231746D02*
X279132Y231677D01*
G01X279139Y231750D02*
X279136Y231746D01*
G01X279124Y228520D02*
X279127Y229807D01*
G01X279121Y227925D02*
X279124Y228520D01*
G01X279117Y227384D02*
X279121Y227925D01*
G01X279112Y226913D02*
X279117Y227384D01*
G01X279106Y226524D02*
X279112Y226913D01*
G01X279099Y226230D02*
X279106Y226524D01*
G01X279092Y226037D02*
X279099Y226230D01*
G01X279027Y224988D02*
X279042Y225050D01*
G01X279020Y225118D02*
X279027Y224988D01*
G01X279013Y225353D02*
X279020Y225118D01*
G01X279019Y220412D02*
X279009Y220138D01*
G01X279025Y220429D02*
X279019Y220412D01*
G01X279030Y220365D02*
X279025Y220429D01*
G01X279018Y221390D02*
X279004Y221024D01*
G01X279025Y221412D02*
X279018Y221390D01*
G01X279032Y221327D02*
X279025Y221412D01*
G01X279096Y219853D02*
X279083Y220340D01*
G01X279102Y219464D02*
X279096Y219853D01*
G01X279107Y218993D02*
X279102Y219464D01*
G01X279112Y218453D02*
X279107Y218993D01*
G01X279115Y217857D02*
X279112Y218453D01*
G01X279117Y217224D02*
X279115Y217857D01*
G01X279117Y216570D02*
Y217224D01*
G01X279122Y214700D02*
X279130Y214627D01*
G01X279119Y214830D02*
X279122Y214700D01*
G01X279115Y215018D02*
X279119Y214830D01*
G01X279112Y215257D02*
X279115Y215018D01*
G01X279110Y215540D02*
X279112Y215257D01*
G01X279108Y215857D02*
X279110Y215540D01*
G01X279107Y216198D02*
X279108Y215857D01*
G01X279107Y216551D02*
Y216198D01*
G01X279091Y219013D02*
X279081Y219379D01*
G01X279095Y218722D02*
X279091Y219013D01*
G01X279099Y218368D02*
X279095Y218722D01*
G01X279102Y217963D02*
X279099Y218368D01*
G01X279104Y217516D02*
X279102Y217963D01*
G01X279106Y217041D02*
X279104Y217516D01*
G01X279107Y216551D02*
X279106Y217041D01*
G01X280737Y220412D02*
X280726Y220365D01*
G01X280742Y220314D02*
X280737Y220412D01*
G01X280748Y220138D02*
X280742Y220314D01*
G01X280652Y217516D02*
X280650Y216551D01*
G01X280654Y217963D02*
X280652Y217516D01*
G01X280657Y218368D02*
X280654Y217963D01*
G01X280661Y218722D02*
X280657Y218368D01*
G01X280666Y219013D02*
X280661Y218722D01*
G01X280671Y219234D02*
X280666Y219013D01*
G01X280676Y219379D02*
X280671Y219234D01*
G01X280648Y215857D02*
X280650Y216551D01*
G01X280646Y215540D02*
X280648Y215857D01*
G01X280644Y215257D02*
X280646Y215540D01*
G01X280641Y215018D02*
X280644Y215257D01*
G01X280638Y214830D02*
X280641Y215018D01*
G01X280634Y214700D02*
X280638Y214830D01*
G01X280630Y214632D02*
X280634Y214700D01*
G01X280626Y214627D02*
X280630Y214632D01*
G01X280642Y217857D02*
X280639Y216570D01*
G01X280645Y218453D02*
X280642Y217857D01*
G01X280649Y218993D02*
X280645Y218453D01*
G01X280654Y219464D02*
X280649Y218993D01*
G01X280660Y219853D02*
X280654Y219464D01*
G01X280666Y220148D02*
X280660Y219853D01*
G01X280673Y220340D02*
X280666Y220148D01*
G01X280738Y221390D02*
X280724Y221327D01*
G01X280746Y221259D02*
X280738Y221390D01*
G01X280752Y221024D02*
X280746Y221259D01*
G01X275087Y225965D02*
X275098Y226012D01*
G01X275082Y226063D02*
X275087Y225965D01*
G01X275076Y226239D02*
X275082Y226063D01*
G01X275172Y228861D02*
X275174Y229826D01*
G01X275170Y228414D02*
X275172Y228861D01*
G01X275167Y228009D02*
X275170Y228414D01*
G01X275163Y227656D02*
X275167Y228009D01*
G01X275158Y227364D02*
X275163Y227656D01*
G01X275154Y227143D02*
X275158Y227364D01*
G01X275148Y226999D02*
X275154Y227143D01*
G01X275182Y228520D02*
X275185Y229807D01*
G01X275179Y227925D02*
X275182Y228520D01*
G01X275175Y227384D02*
X275179Y227925D01*
G01X275170Y226913D02*
X275175Y227384D01*
G01X275164Y226524D02*
X275170Y226913D01*
G01X275158Y226230D02*
X275164Y226524D01*
G01X275151Y226037D02*
X275158Y226230D01*
G01X275086Y224988D02*
X275100Y225050D01*
G01X275078Y225118D02*
X275086Y224988D01*
G01X275072Y225353D02*
X275078Y225118D01*
G01X276805Y225965D02*
X276815Y226239D01*
G01X276799Y225948D02*
X276805Y225965D01*
G01X276794Y226012D02*
X276799Y225948D01*
G01X276806Y224988D02*
X276820Y225353D01*
G01X276799Y224965D02*
X276806Y224988D01*
G01X276792Y225050D02*
X276799Y224965D01*
G01X276728Y226524D02*
X276741Y226037D01*
G01X276722Y226913D02*
X276728Y226524D01*
G01X276717Y227384D02*
X276722Y226913D01*
G01X276712Y227925D02*
X276717Y227384D01*
G01X276709Y228520D02*
X276712Y227925D01*
G01X276707Y229153D02*
X276709Y228520D01*
G01X276707Y229807D02*
Y229153D01*
G01X276733Y227364D02*
X276743Y226999D01*
G01X276729Y227656D02*
X276733Y227364D01*
G01X276725Y228009D02*
X276729Y227656D01*
G01X276722Y228414D02*
X276725Y228009D01*
G01X276720Y228861D02*
X276722Y228414D01*
G01X276718Y229336D02*
X276720Y228861D01*
G01X276718Y229826D02*
Y229336D01*
G01X276805Y220412D02*
X276794Y220365D01*
G01X276810Y220314D02*
X276805Y220412D01*
G01X276815Y220138D02*
X276810Y220314D01*
G01X276720Y217516D02*
X276718Y216551D01*
G01X276722Y217963D02*
X276720Y217516D01*
G01X276725Y218368D02*
X276722Y217963D01*
G01X276729Y218722D02*
X276725Y218368D01*
G01X276733Y219013D02*
X276729Y218722D01*
G01X276738Y219234D02*
X276733Y219013D01*
G01X276743Y219379D02*
X276738Y219234D01*
G01X276709Y217857D02*
X276707Y216570D01*
G01X276712Y218453D02*
X276709Y217857D01*
G01X276717Y218993D02*
X276712Y218453D01*
G01X276722Y219464D02*
X276717Y218993D01*
G01X276728Y219853D02*
X276722Y219464D01*
G01X276734Y220148D02*
X276728Y219853D01*
G01X276741Y220340D02*
X276734Y220148D01*
G01X276806Y221390D02*
X276792Y221327D01*
G01X276813Y221259D02*
X276806Y221390D01*
G01X276820Y221024D02*
X276813Y221259D01*
G01X275087Y220412D02*
X275076Y220138D01*
G01X275092Y220429D02*
X275087Y220412D01*
G01X275098Y220365D02*
X275092Y220429D01*
G01X275086Y221390D02*
X275072Y221024D01*
G01X275093Y221412D02*
X275086Y221390D01*
G01X275100Y221327D02*
X275093Y221412D01*
G01X275164Y219853D02*
X275151Y220340D01*
G01X275170Y219464D02*
X275164Y219853D01*
G01X275175Y218993D02*
X275170Y219464D01*
G01X275179Y218453D02*
X275175Y218993D01*
G01X275182Y217857D02*
X275179Y218453D01*
G01X275184Y217224D02*
X275182Y217857D01*
G01X275185Y216570D02*
X275184Y217224D01*
G01X275158Y219013D02*
X275148Y219379D01*
G01X275163Y218722D02*
X275158Y219013D01*
G01X275167Y218368D02*
X275163Y218722D01*
G01X275170Y217963D02*
X275167Y218368D01*
G01X275172Y217516D02*
X275170Y217963D01*
G01X275174Y217041D02*
X275172Y217516D01*
G01X275174Y216551D02*
Y217041D01*
G01X272872Y225965D02*
X272883Y226239D01*
G01X272867Y225948D02*
X272872Y225965D01*
G01X272862Y226012D02*
X272867Y225948D01*
G01X272874Y224988D02*
X272888Y225353D01*
G01X272866Y224965D02*
X272874Y224988D01*
G01X272859Y225050D02*
X272866Y224965D01*
G01X272795Y226524D02*
X272809Y226037D01*
G01X272789Y226913D02*
X272795Y226524D01*
G01X272784Y227384D02*
X272789Y226913D01*
G01X272780Y227925D02*
X272784Y227384D01*
G01X272777Y228520D02*
X272780Y227925D01*
G01X272775Y229153D02*
X272777Y228520D01*
G01X272774Y229807D02*
X272775Y229153D01*
G01X272769Y231677D02*
X272762Y231750D01*
G01X272773Y231547D02*
X272769Y231677D01*
G01X272776Y231359D02*
X272773Y231547D01*
G01X272779Y231120D02*
X272776Y231359D01*
G01X272782Y230838D02*
X272779Y231120D01*
G01X272784Y230521D02*
X272782Y230838D01*
G01X272785Y230180D02*
X272784Y230521D01*
G01X272785Y229826D02*
Y230180D01*
G01X272801Y227364D02*
X272811Y226999D01*
G01X272797Y227656D02*
X272801Y227364D01*
G01X272793Y228009D02*
X272797Y227656D01*
G01X272790Y228414D02*
X272793Y228009D01*
G01X272787Y228861D02*
X272790Y228414D01*
G01X272786Y229336D02*
X272787Y228861D01*
G01X272785Y229826D02*
X272786Y229336D01*
G01X271155Y225965D02*
X271165Y226012D01*
G01X271149Y226063D02*
X271155Y225965D01*
G01X271144Y226239D02*
X271149Y226063D01*
G01X271240Y228861D02*
X271242Y229826D01*
G01X271237Y228414D02*
X271240Y228861D01*
G01X271234Y228009D02*
X271237Y228414D01*
G01X271231Y227656D02*
X271234Y228009D01*
G01X271226Y227364D02*
X271231Y227656D01*
G01X271221Y227143D02*
X271226Y227364D01*
G01X271216Y226999D02*
X271221Y227143D01*
G01X271243Y230521D02*
X271242Y229826D01*
G01X271245Y230838D02*
X271243Y230521D01*
G01X271248Y231120D02*
X271245Y230838D01*
G01X271251Y231359D02*
X271248Y231120D01*
G01X271254Y231547D02*
X271251Y231359D01*
G01X271258Y231677D02*
X271254Y231547D01*
G01X271262Y231746D02*
X271258Y231677D01*
G01X271265Y231750D02*
X271262Y231746D01*
G01X271250Y228520D02*
X271253Y229807D01*
G01X271247Y227925D02*
X271250Y228520D01*
G01X271243Y227384D02*
X271247Y227925D01*
G01X271238Y226913D02*
X271243Y227384D01*
G01X271232Y226524D02*
X271238Y226913D01*
G01X271225Y226230D02*
X271232Y226524D01*
G01X271218Y226037D02*
X271225Y226230D01*
G01X271153Y224988D02*
X271168Y225050D01*
G01X271146Y225118D02*
X271153Y224988D01*
G01X271139Y225353D02*
X271146Y225118D01*
G01X271145Y220412D02*
X271135Y220138D01*
G01X271151Y220429D02*
X271145Y220412D01*
G01X271156Y220365D02*
X271151Y220429D01*
G01X271144Y221390D02*
X271130Y221024D01*
G01X271151Y221412D02*
X271144Y221390D01*
G01X271158Y221327D02*
X271151Y221412D01*
G01X271222Y219853D02*
X271209Y220340D01*
G01X271228Y219464D02*
X271222Y219853D01*
G01X271233Y218993D02*
X271228Y219464D01*
G01X271238Y218453D02*
X271233Y218993D01*
G01X271241Y217857D02*
X271238Y218453D01*
G01X271243Y217224D02*
X271241Y217857D01*
G01X271243Y216570D02*
Y217224D01*
G01X271248Y214700D02*
X271256Y214627D01*
G01X271245Y214830D02*
X271248Y214700D01*
G01X271241Y215018D02*
X271245Y214830D01*
G01X271238Y215257D02*
X271241Y215018D01*
G01X271236Y215540D02*
X271238Y215257D01*
G01X271234Y215857D02*
X271236Y215540D01*
G01X271233Y216198D02*
X271234Y215857D01*
G01X271232Y216551D02*
X271233Y216198D01*
G01X271217Y219013D02*
X271207Y219379D01*
G01X271221Y218722D02*
X271217Y219013D01*
G01X271225Y218368D02*
X271221Y218722D01*
G01X271228Y217963D02*
X271225Y218368D01*
G01X271230Y217516D02*
X271228Y217963D01*
G01X271232Y217041D02*
X271230Y217516D01*
G01X271232Y216551D02*
Y217041D01*
G01X272863Y220412D02*
X272852Y220365D01*
G01X272868Y220314D02*
X272863Y220412D01*
G01X272874Y220138D02*
X272868Y220314D01*
G01X272778Y217516D02*
X272776Y216551D01*
G01X272780Y217963D02*
X272778Y217516D01*
G01X272783Y218368D02*
X272780Y217963D01*
G01X272787Y218722D02*
X272783Y218368D01*
G01X272792Y219013D02*
X272787Y218722D01*
G01X272797Y219234D02*
X272792Y219013D01*
G01X272802Y219379D02*
X272797Y219234D01*
G01X272774Y215857D02*
X272776Y216551D01*
G01X272772Y215540D02*
X272774Y215857D01*
G01X272770Y215257D02*
X272772Y215540D01*
G01X272767Y215018D02*
X272770Y215257D01*
G01X272764Y214830D02*
X272767Y215018D01*
G01X272760Y214700D02*
X272764Y214830D01*
G01X272756Y214632D02*
X272760Y214700D01*
G01X272752Y214627D02*
X272756Y214632D01*
G01X272768Y217857D02*
X272765Y216570D01*
G01X272771Y218453D02*
X272768Y217857D01*
G01X272775Y218993D02*
X272771Y218453D01*
G01X272780Y219464D02*
X272775Y218993D01*
G01X272786Y219853D02*
X272780Y219464D01*
G01X272792Y220148D02*
X272786Y219853D01*
G01X272799Y220340D02*
X272792Y220148D01*
G01X272864Y221390D02*
X272850Y221327D01*
G01X272872Y221259D02*
X272864Y221390D01*
G01X272878Y221024D02*
X272872Y221259D01*
G01X267213Y225965D02*
X267224Y226012D01*
G01X267208Y226063D02*
X267213Y225965D01*
G01X267202Y226239D02*
X267208Y226063D01*
G01X267298Y228861D02*
X267300Y229826D01*
G01X267296Y228414D02*
X267298Y228861D01*
G01X267293Y228009D02*
X267296Y228414D01*
G01X267289Y227656D02*
X267293Y228009D01*
G01X267284Y227364D02*
X267289Y227656D01*
G01X267279Y227143D02*
X267284Y227364D01*
G01X267274Y226999D02*
X267279Y227143D01*
G01X267308Y228520D02*
X267311Y229807D01*
G01X267305Y227925D02*
X267308Y228520D01*
G01X267301Y227384D02*
X267305Y227925D01*
G01X267296Y226913D02*
X267301Y227384D01*
G01X267290Y226524D02*
X267296Y226913D01*
G01X267284Y226230D02*
X267290Y226524D01*
G01X267277Y226037D02*
X267284Y226230D01*
G01X267212Y224988D02*
X267226Y225050D01*
G01X267204Y225118D02*
X267212Y224988D01*
G01X267198Y225353D02*
X267204Y225118D01*
G01X268931Y225965D02*
X268941Y226239D01*
G01X268925Y225948D02*
X268931Y225965D01*
G01X268920Y226012D02*
X268925Y225948D01*
G01X268932Y224988D02*
X268946Y225353D01*
G01X268925Y224965D02*
X268932Y224988D01*
G01X268918Y225050D02*
X268925Y224965D01*
G01X268854Y226524D02*
X268867Y226037D01*
G01X268848Y226913D02*
X268854Y226524D01*
G01X268843Y227384D02*
X268848Y226913D01*
G01X268838Y227925D02*
X268843Y227384D01*
G01X268835Y228520D02*
X268838Y227925D01*
G01X268833Y229153D02*
X268835Y228520D01*
G01X268833Y229807D02*
Y229153D01*
G01X268859Y227364D02*
X268869Y226999D01*
G01X268855Y227656D02*
X268859Y227364D01*
G01X268851Y228009D02*
X268855Y227656D01*
G01X268848Y228414D02*
X268851Y228009D01*
G01X268846Y228861D02*
X268848Y228414D01*
G01X268844Y229336D02*
X268846Y228861D01*
G01X268844Y229826D02*
Y229336D01*
G01X268931Y220412D02*
X268920Y220365D01*
G01X268936Y220314D02*
X268931Y220412D01*
G01X268941Y220138D02*
X268936Y220314D01*
G01X268846Y217516D02*
X268844Y216551D01*
G01X268848Y217963D02*
X268846Y217516D01*
G01X268851Y218368D02*
X268848Y217963D01*
G01X268855Y218722D02*
X268851Y218368D01*
G01X268859Y219013D02*
X268855Y218722D01*
G01X268864Y219234D02*
X268859Y219013D01*
G01X268869Y219379D02*
X268864Y219234D01*
G01X268835Y217857D02*
X268833Y216570D01*
G01X268838Y218453D02*
X268835Y217857D01*
G01X268843Y218993D02*
X268838Y218453D01*
G01X268848Y219464D02*
X268843Y218993D01*
G01X268854Y219853D02*
X268848Y219464D01*
G01X268860Y220148D02*
X268854Y219853D01*
G01X268867Y220340D02*
X268860Y220148D01*
G01X268932Y221390D02*
X268918Y221327D01*
G01X268939Y221259D02*
X268932Y221390D01*
G01X268946Y221024D02*
X268939Y221259D01*
G01X267213Y220412D02*
X267202Y220138D01*
G01X267218Y220429D02*
X267213Y220412D01*
G01X267224Y220365D02*
X267218Y220429D01*
G01X267212Y221390D02*
X267198Y221024D01*
G01X267219Y221412D02*
X267212Y221390D01*
G01X267226Y221327D02*
X267219Y221412D01*
G01X267290Y219853D02*
X267277Y220340D01*
G01X267296Y219464D02*
X267290Y219853D01*
G01X267301Y218993D02*
X267296Y219464D01*
G01X267305Y218453D02*
X267301Y218993D01*
G01X267308Y217857D02*
X267305Y218453D01*
G01X267310Y217224D02*
X267308Y217857D01*
G01X267311Y216570D02*
X267310Y217224D01*
G01X267284Y219013D02*
X267274Y219379D01*
G01X267289Y218722D02*
X267284Y219013D01*
G01X267293Y218368D02*
X267289Y218722D01*
G01X267296Y217963D02*
X267293Y218368D01*
G01X267298Y217516D02*
X267296Y217963D01*
G01X267300Y217041D02*
X267298Y217516D01*
G01X267300Y216551D02*
Y217041D01*
G01X268820Y231754D02*
Y231750D01*
G01X268821Y231756D02*
X268820Y231754D01*
G01X268822Y231756D02*
X268821D01*
G01X276694Y231754D02*
Y231750D01*
G01X276695Y231756D02*
X276694Y231754D01*
G01X276696Y231756D02*
X276695D01*
G01X267323Y214624D02*
X267324Y214627D01*
G01X267323Y214622D02*
Y214624D01*
G01X267322Y214621D02*
X267323Y214622D01*
G01X284568Y231754D02*
Y231750D01*
G01X284569Y231756D02*
X284568Y231754D01*
G01X284570Y231756D02*
X284569D01*
G01X275197Y214624D02*
X275198Y214627D01*
G01X275197Y214622D02*
Y214624D01*
G01X275196Y214621D02*
X275197Y214622D01*
G01X292442Y231754D02*
Y231750D01*
G01X292443Y231756D02*
X292442Y231754D01*
G01X292444Y231756D02*
X292443D01*
G01X268821Y230768D02*
X268820Y230762D01*
G01X268821Y230771D02*
Y230768D01*
G01X268822Y230772D02*
X268821Y230771D01*
G01X267323Y215610D02*
X267324Y215615D01*
G01X267323Y215606D02*
Y215610D01*
G01X267322Y215605D02*
X267323Y215606D01*
G01X276695Y230768D02*
X276694Y230762D01*
G01X276695Y230771D02*
Y230768D01*
G01X276696Y230772D02*
X276695Y230771D01*
G01X275197Y215610D02*
X275198Y215615D01*
G01X275197Y215606D02*
Y215610D01*
G01X275196Y215605D02*
X275197Y215606D01*
G01X284569Y230768D02*
X284568Y230762D01*
G01X284569Y230771D02*
Y230768D01*
G01X284570Y230772D02*
X284569Y230771D01*
G01X283071Y215610D02*
X283072Y215615D01*
G01X283071Y215606D02*
Y215610D01*
G01X283070Y215605D02*
X283071Y215606D01*
G01X292443Y230768D02*
X292442Y230762D01*
G01X292443Y230771D02*
Y230768D01*
G01X292444Y230772D02*
X292443Y230771D01*
G01X283071Y214624D02*
X283072Y214627D01*
G01X283071Y214622D02*
Y214624D01*
G01X283070Y214621D02*
X283071Y214622D01*
G01X300316Y231754D02*
Y231750D01*
G01X300317Y231756D02*
X300316Y231754D01*
G01X300318Y231756D02*
X300317D01*
G01X290945Y214624D02*
X290946Y214627D01*
G01X290945Y214622D02*
Y214624D01*
G01X290944Y214621D02*
X290945Y214622D01*
G01X308191Y231754D02*
X308190Y231750D01*
G01X308191Y231756D02*
Y231754D01*
G01X308192Y231756D02*
X308191D01*
G01X298819Y214624D02*
X298820Y214627D01*
G01X298819Y214622D02*
Y214624D01*
G01X298818Y214621D02*
X298819Y214622D01*
G01X316065Y231754D02*
X316064Y231750D01*
G01X316065Y231756D02*
Y231754D01*
G01X316066Y231756D02*
X316065D01*
G01X306693Y214624D02*
X306694Y214627D01*
G01X306693Y214622D02*
Y214624D01*
G01X306692Y214621D02*
X306693Y214622D01*
G01X323939Y231754D02*
X323938Y231750D01*
G01X323939Y231756D02*
Y231754D01*
G01X323940Y231756D02*
X323939D01*
G01X267057Y214965D02*
X267061Y215117D01*
G01X267053Y214866D02*
X267057Y214965D01*
G01X267048Y214824D02*
X267053Y214866D01*
G01X269086Y231413D02*
X269082Y231260D01*
G01X269091Y231511D02*
X269086Y231413D01*
G01X269095Y231553D02*
X269091Y231511D01*
G01X269083Y232353D02*
X269077Y232147D01*
G01X269089Y232484D02*
X269083Y232353D01*
G01X269095Y232538D02*
X269089Y232484D01*
G01X267060Y214024D02*
X267066Y214231D01*
G01X267054Y213893D02*
X267060Y214024D01*
G01X267048Y213840D02*
X267054Y213893D01*
G01X273025Y232353D02*
X273019Y232147D01*
G01X273031Y232484D02*
X273025Y232353D01*
G01X273037Y232538D02*
X273031Y232484D01*
G01X270993Y214024D02*
X270999Y214231D01*
G01X270987Y213893D02*
X270993Y214024D01*
G01X270981Y213840D02*
X270987Y213893D01*
G01X271254Y230209D02*
X271253Y229807D01*
G01X271257Y230537D02*
X271254Y230209D01*
G01X271261Y230733D02*
X271257Y230537D01*
G01X271265Y230762D02*
X271261Y230733D01*
G01X272764Y216168D02*
X272765Y216570D01*
G01X272761Y215841D02*
X272764Y216168D01*
G01X272757Y215645D02*
X272761Y215841D01*
G01X272752Y215615D02*
X272757Y215645D01*
G01X290945Y215610D02*
X290946Y215615D01*
G01X290945Y215606D02*
Y215610D01*
G01X290944Y215605D02*
X290945Y215606D01*
G01X300317Y230768D02*
X300316Y230762D01*
G01X300317Y230771D02*
Y230768D01*
G01X300318Y230772D02*
X300317Y230771D01*
G01X298819Y215610D02*
X298820Y215615D01*
G01X298819Y215606D02*
Y215610D01*
G01X298818Y215605D02*
X298819Y215606D01*
G01X308191Y230768D02*
X308190Y230762D01*
G01X308191Y230771D02*
Y230768D01*
G01X308192Y230772D02*
X308191Y230771D01*
G01X306693Y215610D02*
X306694Y215615D01*
G01X306693Y215606D02*
Y215610D01*
G01X306692Y215605D02*
X306693Y215606D01*
G01X316065Y230768D02*
X316064Y230762D01*
G01X316065Y230771D02*
Y230768D01*
G01X316066Y230772D02*
X316065Y230771D01*
G01X314567Y214624D02*
X314568Y214627D01*
G01X314567Y214622D02*
Y214624D01*
G01X314566Y214621D02*
X314567Y214622D01*
G01X331813Y231754D02*
X331812Y231750D01*
G01X331813Y231756D02*
Y231754D01*
G01X331814Y231756D02*
X331813D01*
G01X322441Y214624D02*
X322442Y214627D01*
G01X322441Y214622D02*
Y214624D01*
G01X322440Y214621D02*
X322441Y214622D01*
G01X339687Y231754D02*
X339686Y231750D01*
G01X339687Y231756D02*
Y231754D01*
G01X339688Y231756D02*
X339687D01*
G01X330315Y214624D02*
X330316Y214627D01*
G01X330315Y214622D02*
Y214624D01*
G01X330314Y214621D02*
X330315Y214622D01*
G01X338189Y214624D02*
X338190Y214627D01*
G01X338189Y214622D02*
Y214624D01*
G01X338188Y214621D02*
X338189Y214622D01*
G01X346063Y214624D02*
X346064Y214627D01*
G01X346063Y214622D02*
Y214624D01*
G01X346062Y214621D02*
X346063Y214622D01*
G01X267323Y230771D02*
X267322Y230772D01*
G01X267323Y230768D02*
Y230771D01*
G01X267324Y230762D02*
X267323Y230768D01*
G01X268821Y215606D02*
X268822Y215605D01*
G01X268821Y215610D02*
Y215606D01*
G01X268820Y215615D02*
X268821Y215610D01*
G01X267054Y232484D02*
X267048Y232538D01*
G01X267060Y232353D02*
X267054Y232484D01*
G01X267066Y232147D02*
X267060Y232353D01*
G01X269089Y213893D02*
X269095Y213840D01*
G01X269083Y214024D02*
X269089Y213893D01*
G01X269077Y214231D02*
X269083Y214024D01*
G01X270996Y232484D02*
X270990Y232538D01*
G01X271002Y232353D02*
X270996Y232484D01*
G01X271008Y232147D02*
X271002Y232353D01*
G01X273022Y213893D02*
X273028Y213840D01*
G01X273016Y214024D02*
X273022Y213893D01*
G01X273010Y214231D02*
X273016Y214024D01*
G01X274928Y232484D02*
X274922Y232538D01*
G01X274934Y232353D02*
X274928Y232484D01*
G01X274940Y232147D02*
X274934Y232353D01*
G01X276963Y213893D02*
X276969Y213840D01*
G01X276957Y214024D02*
X276963Y213893D01*
G01X276951Y214231D02*
X276957Y214024D01*
G01X267053Y231511D02*
X267048Y231553D01*
G01X267057Y231413D02*
X267053Y231511D01*
G01X267061Y231260D02*
X267057Y231413D01*
G01X269091Y214866D02*
X269095Y214824D01*
G01X269086Y214965D02*
X269091Y214866D01*
G01X269082Y215117D02*
X269086Y214965D01*
G01X270994Y231511D02*
X270990Y231553D01*
G01X270999Y231413D02*
X270994Y231511D01*
G01X271003Y231260D02*
X270999Y231413D01*
G01X273023Y214866D02*
X273028Y214824D01*
G01X273019Y214965D02*
X273023Y214866D01*
G01X273015Y215117D02*
X273019Y214965D01*
G01X274927Y231511D02*
X274922Y231553D01*
G01X274931Y231413D02*
X274927Y231511D01*
G01X274935Y231260D02*
X274931Y231413D01*
G01X276965Y214866D02*
X276969Y214824D01*
G01X276960Y214965D02*
X276965Y214866D01*
G01X276956Y215117D02*
X276960Y214965D01*
G01X271251Y215645D02*
X271256Y215615D01*
G01X271247Y215841D02*
X271251Y215645D01*
G01X271245Y216168D02*
X271247Y215841D01*
G01X271243Y216570D02*
X271245Y216168D01*
G01X272766Y230733D02*
X272762Y230762D01*
G01X272770Y230537D02*
X272766Y230733D01*
G01X272773Y230209D02*
X272770Y230537D01*
G01X272774Y229807D02*
X272773Y230209D01*
G01X279125Y215645D02*
X279130Y215615D01*
G01X279121Y215841D02*
X279125Y215645D01*
G01X279119Y216168D02*
X279121Y215841D01*
G01X279117Y216570D02*
X279119Y216168D01*
G01X280640Y230733D02*
X280636Y230762D01*
G01X280644Y230537D02*
X280640Y230733D01*
G01X280647Y230209D02*
X280644Y230537D01*
G01X280648Y229807D02*
X280647Y230209D01*
G01X267314Y214770D02*
X267322Y214621D01*
G01X267307Y215184D02*
X267314Y214770D01*
G01X267302Y215804D02*
X267307Y215184D01*
G01X267300Y216551D02*
X267302Y215804D01*
G01X267318Y215678D02*
X267322Y215605D01*
G01X267314Y215887D02*
X267318Y215678D01*
G01X267312Y216200D02*
X267314Y215887D01*
G01X267311Y216570D02*
X267312Y216200D01*
G01X268826Y230699D02*
X268822Y230772D01*
G01X268829Y230490D02*
X268826Y230699D01*
G01X268832Y230178D02*
X268829Y230490D01*
G01X268833Y229807D02*
X268832Y230178D01*
G01X268830Y231608D02*
X268822Y231756D01*
G01X268837Y231193D02*
X268830Y231608D01*
G01X268842Y230573D02*
X268837Y231193D01*
G01X268844Y229826D02*
X268842Y230573D01*
G01X275188Y214770D02*
X275196Y214621D01*
G01X275181Y215184D02*
X275188Y214770D01*
G01X275176Y215804D02*
X275181Y215184D01*
G01X275174Y216551D02*
X275176Y215804D01*
G01X275192Y215678D02*
X275196Y215605D01*
G01X275188Y215887D02*
X275192Y215678D01*
G01X275186Y216200D02*
X275188Y215887D01*
G01X275185Y216570D02*
X275186Y216200D01*
G01X276700Y230699D02*
X276696Y230772D01*
G01X276703Y230490D02*
X276700Y230699D01*
G01X276706Y230178D02*
X276703Y230490D01*
G01X276707Y229807D02*
X276706Y230178D01*
G01X276704Y231608D02*
X276696Y231756D01*
G01X276711Y231193D02*
X276704Y231608D01*
G01X276716Y230573D02*
X276711Y231193D01*
G01X276718Y229826D02*
X276716Y230573D01*
G01X267302D02*
X267300Y229826D01*
G01X267307Y231193D02*
X267302Y230573D01*
G01X267314Y231608D02*
X267307Y231193D01*
G01X267322Y231756D02*
X267314Y231608D01*
G01X268842Y215804D02*
X268844Y216551D01*
G01X268837Y215184D02*
X268842Y215804D01*
G01X268830Y214770D02*
X268837Y215184D01*
G01X268822Y214621D02*
X268830Y214770D01*
G01X275176Y230573D02*
X275174Y229826D01*
G01X275181Y231193D02*
X275176Y230573D01*
G01X275188Y231608D02*
X275181Y231193D01*
G01X275196Y231756D02*
X275188Y231608D01*
G01X276716Y215804D02*
X276718Y216551D01*
G01X276711Y215184D02*
X276716Y215804D01*
G01X276704Y214770D02*
X276711Y215184D01*
G01X276696Y214621D02*
X276704Y214770D01*
G01X283050Y230573D02*
X283048Y229826D01*
G01X283055Y231193D02*
X283050Y230573D01*
G01X283062Y231608D02*
X283055Y231193D01*
G01X283070Y231756D02*
X283062Y231608D01*
G01X284590Y215804D02*
X284592Y216551D01*
G01X284585Y215184D02*
X284590Y215804D01*
G01X284578Y214770D02*
X284585Y215184D01*
G01X284570Y214621D02*
X284578Y214770D01*
G01X267312Y230178D02*
X267311Y229807D01*
G01X267314Y230490D02*
X267312Y230178D01*
G01X267318Y230699D02*
X267314Y230490D01*
G01X267322Y230772D02*
X267318Y230699D01*
G01X268832Y216200D02*
X268833Y216570D01*
G01X268829Y215887D02*
X268832Y216200D01*
G01X268826Y215678D02*
X268829Y215887D01*
G01X268822Y215605D02*
X268826Y215678D01*
G01X275186Y230178D02*
X275185Y229807D01*
G01X275188Y230490D02*
X275186Y230178D01*
G01X275192Y230699D02*
X275188Y230490D01*
G01X275196Y230772D02*
X275192Y230699D01*
G01X276706Y216200D02*
X276707Y216570D01*
G01X276703Y215887D02*
X276706Y216200D01*
G01X276700Y215678D02*
X276703Y215887D01*
G01X276696Y215605D02*
X276700Y215678D01*
G01X283060Y230178D02*
X283059Y229807D01*
G01X283062Y230490D02*
X283060Y230178D01*
G01X283066Y230699D02*
X283062Y230490D01*
G01X283070Y230772D02*
X283066Y230699D01*
G01X284580Y216200D02*
X284581Y216570D01*
G01X284577Y215887D02*
X284580Y216200D01*
G01X284574Y215678D02*
X284577Y215887D01*
G01X284570Y215605D02*
X284574Y215678D01*
G01X270990Y214965D02*
X270994Y215117D01*
G01X270985Y214866D02*
X270990Y214965D01*
G01X270981Y214824D02*
X270985Y214866D01*
G01X273028Y231413D02*
X273024Y231260D01*
G01X273033Y231511D02*
X273028Y231413D01*
G01X273037Y231553D02*
X273033Y231511D01*
G01X274931Y214965D02*
X274935Y215117D01*
G01X274927Y214866D02*
X274931Y214965D01*
G01X274922Y214824D02*
X274927Y214866D01*
G01X276960Y231413D02*
X276956Y231260D01*
G01X276965Y231511D02*
X276960Y231413D01*
G01X276969Y231553D02*
X276965Y231511D01*
G01X278864Y214965D02*
X278868Y215117D01*
G01X278859Y214866D02*
X278864Y214965D01*
G01X278855Y214824D02*
X278859Y214866D01*
G01X280902Y231413D02*
X280898Y231260D01*
G01X280907Y231511D02*
X280902Y231413D01*
G01X280911Y231553D02*
X280907Y231511D01*
G01X282805Y214965D02*
X282809Y215117D01*
G01X282801Y214866D02*
X282805Y214965D01*
G01X282796Y214824D02*
X282801Y214866D01*
G01X284835Y231413D02*
X284830Y231260D01*
G01X284839Y231511D02*
X284835Y231413D01*
G01X284843Y231553D02*
X284839Y231511D01*
G01X286738Y214965D02*
X286742Y215117D01*
G01X286733Y214866D02*
X286738Y214965D01*
G01X286729Y214824D02*
X286733Y214866D01*
G01X288776Y231413D02*
X288772Y231260D01*
G01X288781Y231511D02*
X288776Y231413D01*
G01X288785Y231553D02*
X288781Y231511D01*
G01X290679Y214965D02*
X290683Y215117D01*
G01X290675Y214866D02*
X290679Y214965D01*
G01X290670Y214824D02*
X290675Y214866D01*
G01X292709Y231413D02*
X292704Y231260D01*
G01X292713Y231511D02*
X292709Y231413D01*
G01X292717Y231553D02*
X292713Y231511D01*
G01X294612Y214965D02*
X294616Y215117D01*
G01X294607Y214866D02*
X294612Y214965D01*
G01X294603Y214824D02*
X294607Y214866D01*
G01X296650Y231413D02*
X296646Y231260D01*
G01X296655Y231511D02*
X296650Y231413D01*
G01X296659Y231553D02*
X296655Y231511D01*
G01X276957Y232353D02*
X276951Y232147D01*
G01X276963Y232484D02*
X276957Y232353D01*
G01X276969Y232538D02*
X276963Y232484D01*
G01X274934Y214024D02*
X274940Y214231D01*
G01X274928Y213893D02*
X274934Y214024D01*
G01X274922Y213840D02*
X274928Y213893D01*
G01X280899Y232353D02*
X280893Y232147D01*
G01X280905Y232484D02*
X280899Y232353D01*
G01X280911Y232538D02*
X280905Y232484D01*
G01X278867Y214024D02*
X278873Y214231D01*
G01X278861Y213893D02*
X278867Y214024D01*
G01X278855Y213840D02*
X278861Y213893D01*
G01X284831Y232353D02*
X284825Y232147D01*
G01X284837Y232484D02*
X284831Y232353D01*
G01X284843Y232538D02*
X284837Y232484D01*
G01X282808Y214024D02*
X282814Y214231D01*
G01X282802Y213893D02*
X282808Y214024D01*
G01X282796Y213840D02*
X282802Y213893D01*
G01X288773Y232353D02*
X288767Y232147D01*
G01X288779Y232484D02*
X288773Y232353D01*
G01X288785Y232538D02*
X288779Y232484D01*
G01X286741Y214024D02*
X286747Y214231D01*
G01X286735Y213893D02*
X286741Y214024D01*
G01X286729Y213840D02*
X286735Y213893D01*
G01X292705Y232353D02*
X292700Y232147D01*
G01X292711Y232484D02*
X292705Y232353D01*
G01X292717Y232538D02*
X292711Y232484D01*
G01X290682Y214024D02*
X290688Y214231D01*
G01X290676Y213893D02*
X290682Y214024D01*
G01X290670Y213840D02*
X290676Y213893D01*
G01X296647Y232353D02*
X296641Y232147D01*
G01X296653Y232484D02*
X296647Y232353D01*
G01X296659Y232538D02*
X296653Y232484D01*
G01X294615Y214024D02*
X294621Y214231D01*
G01X294609Y213893D02*
X294615Y214024D01*
G01X294603Y213840D02*
X294609Y213893D01*
G01X279128Y230209D02*
X279127Y229807D01*
G01X279131Y230537D02*
X279128Y230209D01*
G01X279135Y230733D02*
X279131Y230537D01*
G01X279139Y230762D02*
X279135Y230733D01*
G01X280638Y216168D02*
X280639Y216570D01*
G01X280635Y215841D02*
X280638Y216168D01*
G01X280631Y215645D02*
X280635Y215841D01*
G01X280626Y215615D02*
X280631Y215645D01*
G01X287002Y230209D02*
X287001Y229807D01*
G01X287005Y230537D02*
X287002Y230209D01*
G01X287009Y230733D02*
X287005Y230537D01*
G01X287013Y230762D02*
X287009Y230733D01*
G01X288512Y216168D02*
X288513Y216570D01*
G01X288509Y215841D02*
X288512Y216168D01*
G01X288505Y215645D02*
X288509Y215841D01*
G01X288500Y215615D02*
X288505Y215645D01*
G01X294876Y230209D02*
X294875Y229807D01*
G01X294879Y230537D02*
X294876Y230209D01*
G01X294883Y230733D02*
X294879Y230537D01*
G01X294887Y230762D02*
X294883Y230733D01*
G01X296386Y216168D02*
X296387Y216570D01*
G01X296383Y215841D02*
X296386Y216168D01*
G01X296379Y215645D02*
X296383Y215841D01*
G01X296374Y215615D02*
X296379Y215645D01*
G01X302750Y230209D02*
X302749Y229807D01*
G01X302753Y230537D02*
X302750Y230209D01*
G01X302757Y230733D02*
X302753Y230537D01*
G01X302761Y230762D02*
X302757Y230733D01*
G01X314567Y215610D02*
X314568Y215615D01*
G01X314567Y215606D02*
Y215610D01*
G01X314566Y215605D02*
X314567Y215606D01*
G01X339687Y230768D02*
X339686Y230762D01*
G01X339687Y230771D02*
Y230768D01*
G01X339688Y230772D02*
X339687Y230771D01*
G01X338189Y215610D02*
X338190Y215615D01*
G01X338189Y215606D02*
Y215610D01*
G01X338188Y215605D02*
X338189Y215606D01*
G01X275197Y230771D02*
X275196Y230772D01*
G01X275197Y230768D02*
Y230771D01*
G01X275198Y230762D02*
X275197Y230768D01*
G01X276695Y215606D02*
X276696Y215605D01*
G01X276695Y215610D02*
Y215606D01*
G01X276694Y215615D02*
X276695Y215610D01*
G01X283071Y230771D02*
X283070Y230772D01*
G01X283071Y230768D02*
Y230771D01*
G01X283072Y230762D02*
X283071Y230768D01*
G01X284569Y215606D02*
X284570Y215605D01*
G01X284569Y215610D02*
Y215606D01*
G01X284568Y215615D02*
X284569Y215610D01*
G01X290945Y230771D02*
X290944Y230772D01*
G01X290945Y230768D02*
Y230771D01*
G01X290946Y230762D02*
X290945Y230768D01*
G01X292443Y215606D02*
X292444Y215605D01*
G01X292443Y215610D02*
Y215606D01*
G01X292442Y215615D02*
X292443Y215610D01*
G01X278870Y232484D02*
X278864Y232538D01*
G01X278876Y232353D02*
X278870Y232484D01*
G01X278882Y232147D02*
X278876Y232353D01*
G01X280896Y213893D02*
X280902Y213840D01*
G01X280890Y214024D02*
X280896Y213893D01*
G01X280884Y214231D02*
X280890Y214024D01*
G01X282802Y232484D02*
X282796Y232538D01*
G01X282808Y232353D02*
X282802Y232484D01*
G01X282814Y232147D02*
X282808Y232353D01*
G01X284837Y213893D02*
X284843Y213840D01*
G01X284831Y214024D02*
X284837Y213893D01*
G01X284825Y214231D02*
X284831Y214024D01*
G01X286744Y232484D02*
X286738Y232538D01*
G01X286750Y232353D02*
X286744Y232484D01*
G01X286756Y232147D02*
X286750Y232353D01*
G01X288770Y213893D02*
X288776Y213840D01*
G01X288764Y214024D02*
X288770Y213893D01*
G01X288758Y214231D02*
X288764Y214024D01*
G01X290676Y232484D02*
X290670Y232538D01*
G01X290682Y232353D02*
X290676Y232484D01*
G01X290688Y232147D02*
X290682Y232353D01*
G01X292711Y213893D02*
X292717Y213840D01*
G01X292705Y214024D02*
X292711Y213893D01*
G01X292700Y214231D02*
X292705Y214024D01*
G01X294618Y232484D02*
X294612Y232538D01*
G01X294624Y232353D02*
X294618Y232484D01*
G01X294630Y232147D02*
X294624Y232353D01*
G01X296644Y213893D02*
X296650Y213840D01*
G01X296638Y214024D02*
X296644Y213893D01*
G01X296632Y214231D02*
X296638Y214024D01*
G01X298550Y232484D02*
X298544Y232538D01*
G01X298556Y232353D02*
X298550Y232484D01*
G01X298562Y232147D02*
X298556Y232353D01*
G01X300585Y213893D02*
X300592Y213840D01*
G01X300579Y214024D02*
X300585Y213893D01*
G01X300574Y214231D02*
X300579Y214024D01*
G01X278868Y231511D02*
X278864Y231553D01*
G01X278873Y231413D02*
X278868Y231511D01*
G01X278877Y231260D02*
X278873Y231413D01*
G01X280897Y214866D02*
X280902Y214824D01*
G01X280893Y214965D02*
X280897Y214866D01*
G01X280889Y215117D02*
X280893Y214965D01*
G01X282801Y231511D02*
X282796Y231553D01*
G01X282805Y231413D02*
X282801Y231511D01*
G01X282809Y231260D02*
X282805Y231413D01*
G01X284839Y214866D02*
X284843Y214824D01*
G01X284835Y214965D02*
X284839Y214866D01*
G01X284830Y215117D02*
X284835Y214965D01*
G01X286742Y231511D02*
X286738Y231553D01*
G01X286747Y231413D02*
X286742Y231511D01*
G01X286751Y231260D02*
X286747Y231413D01*
G01X288771Y214866D02*
X288776Y214824D01*
G01X288767Y214965D02*
X288771Y214866D01*
G01X288763Y215117D02*
X288767Y214965D01*
G01X290675Y231511D02*
X290670Y231553D01*
G01X290679Y231413D02*
X290675Y231511D01*
G01X290683Y231260D02*
X290679Y231413D01*
G01X292713Y214866D02*
X292717Y214824D01*
G01X292709Y214965D02*
X292713Y214866D01*
G01X292704Y215117D02*
X292709Y214965D01*
G01X294616Y231511D02*
X294612Y231553D01*
G01X294621Y231413D02*
X294616Y231511D01*
G01X294625Y231260D02*
X294621Y231413D01*
G01X296645Y214866D02*
X296650Y214824D01*
G01X296641Y214965D02*
X296645Y214866D01*
G01X296637Y215117D02*
X296641Y214965D01*
G01X298549Y231511D02*
X298544Y231553D01*
G01X298553Y231413D02*
X298549Y231511D01*
G01X298557Y231260D02*
X298553Y231413D01*
G01X300587Y214866D02*
X300592Y214824D01*
G01X300583Y214965D02*
X300587Y214866D01*
G01X300578Y215117D02*
X300583Y214965D01*
G01X286999Y215645D02*
X287004Y215615D01*
G01X286995Y215841D02*
X286999Y215645D01*
G01X286993Y216168D02*
X286995Y215841D01*
G01X286991Y216570D02*
X286993Y216168D01*
G01X288514Y230733D02*
X288510Y230762D01*
G01X288518Y230537D02*
X288514Y230733D01*
G01X288521Y230209D02*
X288518Y230537D01*
G01X288522Y229807D02*
X288521Y230209D01*
G01X294873Y215645D02*
X294878Y215615D01*
G01X294869Y215841D02*
X294873Y215645D01*
G01X294867Y216168D02*
X294869Y215841D01*
G01X294865Y216570D02*
X294867Y216168D01*
G01X296388Y230733D02*
X296384Y230762D01*
G01X296392Y230537D02*
X296388Y230733D01*
G01X296395Y230209D02*
X296392Y230537D01*
G01X296396Y229807D02*
X296395Y230209D01*
G01X302747Y215645D02*
X302752Y215615D01*
G01X302743Y215841D02*
X302747Y215645D01*
G01X302741Y216168D02*
X302743Y215841D01*
G01X302740Y216570D02*
X302741Y216168D01*
G01X304262Y230733D02*
X304258Y230762D01*
G01X304266Y230537D02*
X304262Y230733D01*
G01X304269Y230209D02*
X304266Y230537D01*
G01X304270Y229807D02*
X304269Y230209D01*
G01X283062Y214770D02*
X283070Y214621D01*
G01X283055Y215184D02*
X283062Y214770D01*
G01X283050Y215804D02*
X283055Y215184D01*
G01X283048Y216551D02*
X283050Y215804D01*
G01X283066Y215678D02*
X283070Y215605D01*
G01X283062Y215887D02*
X283066Y215678D01*
G01X283060Y216200D02*
X283062Y215887D01*
G01X283059Y216570D02*
X283060Y216200D01*
G01X284574Y230699D02*
X284570Y230772D01*
G01X284577Y230490D02*
X284574Y230699D01*
G01X284580Y230178D02*
X284577Y230490D01*
G01X284581Y229807D02*
X284580Y230178D01*
G01X284578Y231608D02*
X284570Y231756D01*
G01X284585Y231193D02*
X284578Y231608D01*
G01X284590Y230573D02*
X284585Y231193D01*
G01X284592Y229826D02*
X284590Y230573D01*
G01X290936Y214770D02*
X290944Y214621D01*
G01X290929Y215184D02*
X290936Y214770D01*
G01X290924Y215804D02*
X290929Y215184D01*
G01X290922Y216551D02*
X290924Y215804D01*
G01X290940Y215678D02*
X290944Y215605D01*
G01X290936Y215887D02*
X290940Y215678D01*
G01X290934Y216200D02*
X290936Y215887D01*
G01X290933Y216570D02*
X290934Y216200D01*
G01X292448Y230699D02*
X292444Y230772D01*
G01X292451Y230490D02*
X292448Y230699D01*
G01X292454Y230178D02*
X292451Y230490D01*
G01X292455Y229807D02*
X292454Y230178D01*
G01X292452Y231608D02*
X292444Y231756D01*
G01X292459Y231193D02*
X292452Y231608D01*
G01X292464Y230573D02*
X292459Y231193D01*
G01X292466Y229826D02*
X292464Y230573D01*
G01X298810Y214770D02*
X298818Y214621D01*
G01X298803Y215184D02*
X298810Y214770D01*
G01X298798Y215804D02*
X298803Y215184D01*
G01X298796Y216551D02*
X298798Y215804D01*
G01X298814Y215678D02*
X298818Y215605D01*
G01X298810Y215887D02*
X298814Y215678D01*
G01X298808Y216200D02*
X298810Y215887D01*
G01X298807Y216570D02*
X298808Y216200D01*
G01X300322Y230699D02*
X300318Y230772D01*
G01X300325Y230490D02*
X300322Y230699D01*
G01X300328Y230178D02*
X300325Y230490D01*
G01X300329Y229807D02*
X300328Y230178D01*
G01X300326Y231608D02*
X300318Y231756D01*
G01X300333Y231193D02*
X300326Y231608D01*
G01X300338Y230573D02*
X300333Y231193D01*
G01X300340Y229826D02*
X300338Y230573D01*
G01X290924D02*
X290922Y229826D01*
G01X290929Y231193D02*
X290924Y230573D01*
G01X290936Y231608D02*
X290929Y231193D01*
G01X290944Y231756D02*
X290936Y231608D01*
G01X292464Y215804D02*
X292466Y216551D01*
G01X292459Y215184D02*
X292464Y215804D01*
G01X292452Y214770D02*
X292459Y215184D01*
G01X292444Y214621D02*
X292452Y214770D01*
G01X298798Y230573D02*
X298796Y229826D01*
G01X298803Y231193D02*
X298798Y230573D01*
G01X298810Y231608D02*
X298803Y231193D01*
G01X298818Y231756D02*
X298810Y231608D01*
G01X300338Y215804D02*
X300340Y216551D01*
G01X300333Y215184D02*
X300338Y215804D01*
G01X300326Y214770D02*
X300333Y215184D01*
G01X300318Y214621D02*
X300326Y214770D01*
G01X306672Y230573D02*
X306670Y229826D01*
G01X306677Y231193D02*
X306672Y230573D01*
G01X306684Y231608D02*
X306677Y231193D01*
G01X306692Y231756D02*
X306684Y231608D01*
G01X308212Y215804D02*
X308214Y216551D01*
G01X308207Y215184D02*
X308212Y215804D01*
G01X308200Y214770D02*
X308207Y215184D01*
G01X308192Y214621D02*
X308200Y214770D01*
G01X290934Y230178D02*
X290933Y229807D01*
G01X290936Y230490D02*
X290934Y230178D01*
G01X290940Y230699D02*
X290936Y230490D01*
G01X290944Y230772D02*
X290940Y230699D01*
G01X292454Y216200D02*
X292455Y216570D01*
G01X292451Y215887D02*
X292454Y216200D01*
G01X292448Y215678D02*
X292451Y215887D01*
G01X292444Y215605D02*
X292448Y215678D01*
G01X298808Y230178D02*
X298807Y229807D01*
G01X298810Y230490D02*
X298808Y230178D01*
G01X298814Y230699D02*
X298810Y230490D01*
G01X298818Y230772D02*
X298814Y230699D01*
G01X300328Y216200D02*
X300329Y216570D01*
G01X300325Y215887D02*
X300328Y216200D01*
G01X300322Y215678D02*
X300325Y215887D01*
G01X300318Y215605D02*
X300322Y215678D01*
G01X306682Y230178D02*
X306681Y229807D01*
G01X306684Y230490D02*
X306682Y230178D01*
G01X306688Y230699D02*
X306684Y230490D01*
G01X306692Y230772D02*
X306688Y230699D01*
G01X308202Y216200D02*
X308203Y216570D01*
G01X308199Y215887D02*
X308202Y216200D01*
G01X308196Y215678D02*
X308199Y215887D01*
G01X308192Y215605D02*
X308196Y215678D01*
G01X298553Y214965D02*
X298557Y215117D01*
G01X298549Y214866D02*
X298553Y214965D01*
G01X298544Y214824D02*
X298549Y214866D01*
G01X300583Y231413D02*
X300578Y231260D01*
G01X300587Y231511D02*
X300583Y231413D01*
G01X300592Y231553D02*
X300587Y231511D01*
G01X302486Y214965D02*
X302490Y215117D01*
G01X302481Y214866D02*
X302486Y214965D01*
G01X302477Y214824D02*
X302481Y214866D01*
G01X304524Y231413D02*
X304520Y231260D01*
G01X304529Y231511D02*
X304524Y231413D01*
G01X304533Y231553D02*
X304529Y231511D01*
G01X306427Y214965D02*
X306431Y215117D01*
G01X306423Y214866D02*
X306427Y214965D01*
G01X306418Y214824D02*
X306423Y214866D01*
G01X308457Y231413D02*
X308452Y231260D01*
G01X308461Y231511D02*
X308457Y231413D01*
G01X308466Y231553D02*
X308461Y231511D01*
G01X310360Y214965D02*
X310364Y215117D01*
G01X310355Y214866D02*
X310360Y214965D01*
G01X310351Y214824D02*
X310355Y214866D01*
G01X312398Y231413D02*
X312394Y231260D01*
G01X312403Y231511D02*
X312398Y231413D01*
G01X312407Y231553D02*
X312403Y231511D01*
G01X314301Y214965D02*
X314306Y215117D01*
G01X314297Y214866D02*
X314301Y214965D01*
G01X314292Y214824D02*
X314297Y214866D01*
G01X316331Y231413D02*
X316326Y231260D01*
G01X316335Y231511D02*
X316331Y231413D01*
G01X316340Y231553D02*
X316335Y231511D01*
G01X318234Y214965D02*
X318238Y215117D01*
G01X318229Y214866D02*
X318234Y214965D01*
G01X318225Y214824D02*
X318229Y214866D01*
G01X320272Y231413D02*
X320268Y231260D01*
G01X320277Y231511D02*
X320272Y231413D01*
G01X320281Y231553D02*
X320277Y231511D01*
G01X300579Y232353D02*
X300574Y232147D01*
G01X300585Y232484D02*
X300579Y232353D01*
G01X300592Y232538D02*
X300585Y232484D01*
G01X298556Y214024D02*
X298562Y214231D01*
G01X298550Y213893D02*
X298556Y214024D01*
G01X298544Y213840D02*
X298550Y213893D01*
G01X304521Y232353D02*
X304515Y232147D01*
G01X304527Y232484D02*
X304521Y232353D01*
G01X304533Y232538D02*
X304527Y232484D01*
G01X302489Y214024D02*
X302495Y214231D01*
G01X302483Y213893D02*
X302489Y214024D01*
G01X302477Y213840D02*
X302483Y213893D01*
G01X308453Y232353D02*
X308448Y232147D01*
G01X308459Y232484D02*
X308453Y232353D01*
G01X308466Y232538D02*
X308459Y232484D01*
G01X306431Y214024D02*
X306436Y214231D01*
G01X306424Y213893D02*
X306431Y214024D01*
G01X306418Y213840D02*
X306424Y213893D01*
G01X312395Y232353D02*
X312389Y232147D01*
G01X312401Y232484D02*
X312395Y232353D01*
G01X312407Y232538D02*
X312401Y232484D01*
G01X310363Y214024D02*
X310369Y214231D01*
G01X310357Y213893D02*
X310363Y214024D01*
G01X310351Y213840D02*
X310357Y213893D01*
G01X316327Y232353D02*
X316322Y232147D01*
G01X316333Y232484D02*
X316327Y232353D01*
G01X316340Y232538D02*
X316333Y232484D01*
G01X314305Y214024D02*
X314310Y214231D01*
G01X314298Y213893D02*
X314305Y214024D01*
G01X314292Y213840D02*
X314298Y213893D01*
G01X320269Y232353D02*
X320263Y232147D01*
G01X320275Y232484D02*
X320269Y232353D01*
G01X320281Y232538D02*
X320275Y232484D01*
G01X318237Y214024D02*
X318243Y214231D01*
G01X318231Y213893D02*
X318237Y214024D01*
G01X318225Y213840D02*
X318231Y213893D01*
G01X304260Y216168D02*
X304261Y216570D01*
G01X304257Y215841D02*
X304260Y216168D01*
G01X304253Y215645D02*
X304257Y215841D01*
G01X304248Y215615D02*
X304253Y215645D01*
G01X310624Y230209D02*
X310623Y229807D01*
G01X310627Y230537D02*
X310624Y230209D01*
G01X310631Y230733D02*
X310627Y230537D01*
G01X310635Y230762D02*
X310631Y230733D01*
G01X312134Y216168D02*
X312135Y216570D01*
G01X312131Y215841D02*
X312134Y216168D01*
G01X312127Y215645D02*
X312131Y215841D01*
G01X312122Y215615D02*
X312127Y215645D01*
G01X318498Y230209D02*
X318497Y229807D01*
G01X318501Y230537D02*
X318498Y230209D01*
G01X318505Y230733D02*
X318501Y230537D01*
G01X318509Y230762D02*
X318505Y230733D01*
G01X320008Y216168D02*
X320009Y216570D01*
G01X320005Y215841D02*
X320008Y216168D01*
G01X320001Y215645D02*
X320005Y215841D01*
G01X319996Y215615D02*
X320001Y215645D01*
G01X326372Y230209D02*
X326371Y229807D01*
G01X326375Y230537D02*
X326372Y230209D01*
G01X326379Y230733D02*
X326375Y230537D01*
G01X326383Y230762D02*
X326379Y230733D01*
G01X346063Y215610D02*
X346064Y215615D01*
G01X346063Y215606D02*
Y215610D01*
G01X346062Y215605D02*
X346063Y215606D01*
G01X268821Y214622D02*
X268822Y214621D01*
G01X268820Y214624D02*
X268821Y214622D01*
G01X268820Y214627D02*
Y214624D01*
G01X267323Y231756D02*
X267322D01*
G01X267323Y231754D02*
Y231756D01*
G01X267324Y231750D02*
X267323Y231754D01*
G01X276695Y214622D02*
X276696Y214621D01*
G01X276694Y214624D02*
X276695Y214622D01*
G01X276694Y214627D02*
Y214624D01*
G01X275197Y231756D02*
X275196D01*
G01X275197Y231754D02*
Y231756D01*
G01X275198Y231750D02*
X275197Y231754D01*
G01X298819Y230771D02*
X298818Y230772D01*
G01X298819Y230768D02*
Y230771D01*
G01X298820Y230762D02*
X298819Y230768D01*
G01X300317Y215606D02*
X300318Y215605D01*
G01X300317Y215610D02*
Y215606D01*
G01X300316Y215615D02*
X300317Y215610D01*
G01X306693Y230771D02*
X306692Y230772D01*
G01X306693Y230768D02*
Y230771D01*
G01X306694Y230762D02*
X306693Y230768D01*
G01X308191Y215606D02*
X308192Y215605D01*
G01X308191Y215610D02*
Y215606D01*
G01X308190Y215615D02*
X308191Y215610D01*
G01X314567Y230771D02*
X314566Y230772D01*
G01X314567Y230768D02*
Y230771D01*
G01X314568Y230762D02*
X314567Y230768D01*
G01X316065Y215606D02*
X316066Y215605D01*
G01X316065Y215610D02*
Y215606D01*
G01X316064Y215615D02*
X316065Y215610D01*
G01X322430Y216197D02*
X322429Y216570D01*
G01X322433Y215887D02*
X322430Y216197D01*
G01X322436Y215680D02*
X322433Y215887D01*
G01X322440Y215605D02*
X322436Y215680D01*
G01X302492Y232484D02*
X302486Y232538D01*
G01X302498Y232353D02*
X302492Y232484D01*
G01X302504Y232147D02*
X302498Y232353D01*
G01X304518Y213893D02*
X304524Y213840D01*
G01X304512Y214024D02*
X304518Y213893D01*
G01X304506Y214231D02*
X304512Y214024D01*
G01X306424Y232484D02*
X306418Y232538D01*
G01X306431Y232353D02*
X306424Y232484D01*
G01X306436Y232147D02*
X306431Y232353D01*
G01X308459Y213893D02*
X308466Y213840D01*
G01X308453Y214024D02*
X308459Y213893D01*
G01X308448Y214231D02*
X308453Y214024D01*
G01X310366Y232484D02*
X310360Y232538D01*
G01X310372Y232353D02*
X310366Y232484D01*
G01X310378Y232147D02*
X310372Y232353D01*
G01X312392Y213893D02*
X312398Y213840D01*
G01X312386Y214024D02*
X312392Y213893D01*
G01X312380Y214231D02*
X312386Y214024D01*
G01X314298Y232484D02*
X314292Y232538D01*
G01X314305Y232353D02*
X314298Y232484D01*
G01X314310Y232147D02*
X314305Y232353D01*
G01X316333Y213893D02*
X316340Y213840D01*
G01X316327Y214024D02*
X316333Y213893D01*
G01X316322Y214231D02*
X316327Y214024D01*
G01X318240Y232484D02*
X318234Y232538D01*
G01X318246Y232353D02*
X318240Y232484D01*
G01X318252Y232147D02*
X318246Y232353D01*
G01X320266Y213893D02*
X320272Y213840D01*
G01X320260Y214024D02*
X320266Y213893D01*
G01X320254Y214231D02*
X320260Y214024D01*
G01X322173Y232484D02*
X322166Y232538D01*
G01X322179Y232353D02*
X322173Y232484D01*
G01X322184Y232147D02*
X322179Y232353D01*
G01X324207Y213893D02*
X324214Y213840D01*
G01X324201Y214024D02*
X324207Y213893D01*
G01X324196Y214231D02*
X324201Y214024D01*
G01X326114Y232484D02*
X326108Y232538D01*
G01X326120Y232353D02*
X326114Y232484D01*
G01X326126Y232147D02*
X326120Y232353D01*
G01X302490Y231511D02*
X302486Y231553D01*
G01X302495Y231413D02*
X302490Y231511D01*
G01X302499Y231260D02*
X302495Y231413D01*
G01X304519Y214866D02*
X304524Y214824D01*
G01X304515Y214965D02*
X304519Y214866D01*
G01X304511Y215117D02*
X304515Y214965D01*
G01X306423Y231511D02*
X306418Y231553D01*
G01X306427Y231413D02*
X306423Y231511D01*
G01X306431Y231260D02*
X306427Y231413D01*
G01X308461Y214866D02*
X308466Y214824D01*
G01X308457Y214965D02*
X308461Y214866D01*
G01X308452Y215117D02*
X308457Y214965D01*
G01X310365Y231511D02*
X310360Y231553D01*
G01X310369Y231413D02*
X310365Y231511D01*
G01X310373Y231260D02*
X310369Y231413D01*
G01X312393Y214866D02*
X312398Y214824D01*
G01X312389Y214965D02*
X312393Y214866D01*
G01X312385Y215117D02*
X312389Y214965D01*
G01X314297Y231511D02*
X314292Y231553D01*
G01X314301Y231413D02*
X314297Y231511D01*
G01X314306Y231260D02*
X314301Y231413D01*
G01X316335Y214866D02*
X316340Y214824D01*
G01X316331Y214965D02*
X316335Y214866D01*
G01X316326Y215117D02*
X316331Y214965D01*
G01X318239Y231511D02*
X318234Y231553D01*
G01X318243Y231413D02*
X318239Y231511D01*
G01X318247Y231260D02*
X318243Y231413D01*
G01X320267Y214866D02*
X320272Y214824D01*
G01X320263Y214965D02*
X320267Y214866D01*
G01X320259Y215117D02*
X320263Y214965D01*
G01X322171Y231511D02*
X322166Y231553D01*
G01X322175Y231413D02*
X322171Y231511D01*
G01X322180Y231260D02*
X322175Y231413D01*
G01X324209Y214866D02*
X324214Y214824D01*
G01X324205Y214965D02*
X324209Y214866D01*
G01X324200Y215117D02*
X324205Y214965D01*
G01X326113Y231511D02*
X326108Y231553D01*
G01X326117Y231413D02*
X326113Y231511D01*
G01X326121Y231260D02*
X326117Y231413D01*
G01X310621Y215645D02*
X310626Y215615D01*
G01X310617Y215841D02*
X310621Y215645D01*
G01X310615Y216168D02*
X310617Y215841D01*
G01X310614Y216570D02*
X310615Y216168D01*
G01X312136Y230733D02*
X312132Y230762D01*
G01X312140Y230537D02*
X312136Y230733D01*
G01X312143Y230209D02*
X312140Y230537D01*
G01X312144Y229807D02*
X312143Y230209D01*
G01X318495Y215645D02*
X318500Y215615D01*
G01X318491Y215841D02*
X318495Y215645D01*
G01X318489Y216168D02*
X318491Y215841D01*
G01X318488Y216570D02*
X318489Y216168D01*
G01X320010Y230733D02*
X320006Y230762D01*
G01X320014Y230537D02*
X320010Y230733D01*
G01X320017Y230209D02*
X320014Y230537D01*
G01X320018Y229807D02*
X320017Y230209D01*
G01X326369Y215645D02*
X326374Y215615D01*
G01X326365Y215841D02*
X326369Y215645D01*
G01X326363Y216168D02*
X326365Y215841D01*
G01X326362Y216570D02*
X326363Y216168D01*
G01X327884Y230733D02*
X327880Y230762D01*
G01X327888Y230537D02*
X327884Y230733D01*
G01X327891Y230209D02*
X327888Y230537D01*
G01X327892Y229807D02*
X327891Y230209D01*
G01X306684Y214770D02*
X306692Y214621D01*
G01X306677Y215184D02*
X306684Y214770D01*
G01X306672Y215804D02*
X306677Y215184D01*
G01X306670Y216551D02*
X306672Y215804D01*
G01X306688Y215678D02*
X306692Y215605D01*
G01X306684Y215887D02*
X306688Y215678D01*
G01X306682Y216200D02*
X306684Y215887D01*
G01X306681Y216570D02*
X306682Y216200D01*
G01X308196Y230699D02*
X308192Y230772D01*
G01X308199Y230490D02*
X308196Y230699D01*
G01X308202Y230178D02*
X308199Y230490D01*
G01X308203Y229807D02*
X308202Y230178D01*
G01X308200Y231608D02*
X308192Y231756D01*
G01X308207Y231193D02*
X308200Y231608D01*
G01X308212Y230573D02*
X308207Y231193D01*
G01X308214Y229826D02*
X308212Y230573D01*
G01X314558Y214770D02*
X314566Y214621D01*
G01X314551Y215184D02*
X314558Y214770D01*
G01X314546Y215804D02*
X314551Y215184D01*
G01X314544Y216551D02*
X314546Y215804D01*
G01X314562Y215678D02*
X314566Y215605D01*
G01X314559Y215887D02*
X314562Y215678D01*
G01X314556Y216200D02*
X314559Y215887D01*
G01X314555Y216570D02*
X314556Y216200D01*
G01X316070Y230699D02*
X316066Y230772D01*
G01X316073Y230490D02*
X316070Y230699D01*
G01X316076Y230178D02*
X316073Y230490D01*
G01X316077Y229807D02*
X316076Y230178D01*
G01X316074Y231608D02*
X316066Y231756D01*
G01X316081Y231193D02*
X316074Y231608D01*
G01X316086Y230573D02*
X316081Y231193D01*
G01X316088Y229826D02*
X316086Y230573D01*
G01X322432Y214770D02*
X322440Y214621D01*
G01X322425Y215184D02*
X322432Y214770D01*
G01X322420Y215804D02*
X322425Y215184D01*
G01X322418Y216551D02*
X322420Y215804D01*
G01X323948Y231608D02*
X323940Y231756D01*
G01X323955Y231193D02*
X323948Y231608D01*
G01X323960Y230573D02*
X323955Y231193D01*
G01X323962Y229826D02*
X323960Y230573D01*
G01X330306Y214770D02*
X330314Y214621D01*
G01X330299Y215184D02*
X330306Y214770D01*
G01X330294Y215804D02*
X330299Y215184D01*
G01X330292Y216551D02*
X330294Y215804D01*
G01X322436Y230698D02*
X322440Y230772D01*
G01X322433Y230490D02*
X322436Y230698D01*
G01X322430Y230180D02*
X322433Y230490D01*
G01X322429Y229807D02*
X322430Y230180D01*
G01X323944Y215680D02*
X323940Y215605D01*
G01X323947Y215887D02*
X323944Y215680D01*
G01X323950Y216197D02*
X323947Y215887D01*
G01X323951Y216570D02*
X323950Y216197D01*
G01X330310Y230698D02*
X330314Y230772D01*
G01X330307Y230490D02*
X330310Y230698D01*
G01X330304Y230180D02*
X330307Y230490D01*
G01X330303Y229807D02*
X330304Y230180D01*
G01X314546Y230573D02*
X314544Y229826D01*
G01X314551Y231193D02*
X314546Y230573D01*
G01X314558Y231608D02*
X314551Y231193D01*
G01X314566Y231756D02*
X314558Y231608D01*
G01X316086Y215804D02*
X316088Y216551D01*
G01X316081Y215184D02*
X316086Y215804D01*
G01X316074Y214770D02*
X316081Y215184D01*
G01X316066Y214621D02*
X316074Y214770D01*
G01X322420Y230573D02*
X322418Y229826D01*
G01X322425Y231193D02*
X322420Y230573D01*
G01X322432Y231608D02*
X322425Y231193D01*
G01X322440Y231756D02*
X322432Y231608D01*
G01X323960Y215804D02*
X323962Y216551D01*
G01X323955Y215184D02*
X323960Y215804D01*
G01X323948Y214770D02*
X323955Y215184D01*
G01X323940Y214621D02*
X323948Y214770D01*
G01X330294Y230573D02*
X330292Y229826D01*
G01X330299Y231193D02*
X330294Y230573D01*
G01X330306Y231608D02*
X330299Y231193D01*
G01X330314Y231756D02*
X330306Y231608D01*
G01X331834Y215804D02*
X331836Y216551D01*
G01X331829Y215184D02*
X331834Y215804D01*
G01X331822Y214770D02*
X331829Y215184D01*
G01X331814Y214621D02*
X331822Y214770D01*
G01X338168Y230573D02*
X338166Y229826D01*
G01X338173Y231193D02*
X338168Y230573D01*
G01X338180Y231608D02*
X338173Y231193D01*
G01X338188Y231756D02*
X338180Y231608D01*
G01X314556Y230178D02*
X314555Y229807D01*
G01X314559Y230490D02*
X314556Y230178D01*
G01X314562Y230699D02*
X314559Y230490D01*
G01X314566Y230772D02*
X314562Y230699D01*
G01X316076Y216200D02*
X316077Y216570D01*
G01X316073Y215887D02*
X316076Y216200D01*
G01X316070Y215678D02*
X316073Y215887D01*
G01X316066Y215605D02*
X316070Y215678D01*
G01X338178Y230178D02*
X338177Y229807D01*
G01X338181Y230490D02*
X338178Y230178D01*
G01X338184Y230699D02*
X338181Y230490D01*
G01X338188Y230772D02*
X338184Y230699D01*
G01X322441Y215606D02*
X322440Y215605D01*
G01X322441Y215610D02*
Y215606D01*
G01X322442Y215617D02*
X322441Y215610D01*
G01X323939Y230771D02*
X323940Y230772D01*
G01X323939Y230768D02*
Y230771D01*
G01X323938Y230760D02*
X323939Y230768D01*
G01X330315Y215606D02*
X330314Y215605D01*
G01X330315Y215610D02*
Y215606D01*
G01X330316Y215617D02*
X330315Y215610D01*
G01X331813Y230771D02*
X331814Y230772D01*
G01X331813Y230768D02*
Y230771D01*
G01X331812Y230760D02*
X331813Y230768D01*
G01X322175Y214965D02*
X322180Y215117D01*
G01X322171Y214866D02*
X322175Y214965D01*
G01X322166Y214824D02*
X322171Y214866D01*
G01X324205Y231413D02*
X324200Y231260D01*
G01X324209Y231511D02*
X324205Y231413D01*
G01X324214Y231553D02*
X324209Y231511D01*
G01X326108Y214965D02*
X326112Y215117D01*
G01X326103Y214866D02*
X326108Y214965D01*
G01X326099Y214824D02*
X326103Y214866D01*
G01X328146Y231413D02*
X328142Y231260D01*
G01X328151Y231511D02*
X328146Y231413D01*
G01X328155Y231553D02*
X328151Y231511D01*
G01X330049Y214965D02*
X330054Y215117D01*
G01X330045Y214866D02*
X330049Y214965D01*
G01X330040Y214824D02*
X330045Y214866D01*
G01X332079Y231413D02*
X332074Y231260D01*
G01X332083Y231511D02*
X332079Y231413D01*
G01X332088Y231553D02*
X332083Y231511D01*
G01X333982Y214965D02*
X333986Y215117D01*
G01X333977Y214866D02*
X333982Y214965D01*
G01X333973Y214824D02*
X333977Y214866D01*
G01X336020Y231413D02*
X336016Y231260D01*
G01X336025Y231511D02*
X336020Y231413D01*
G01X336029Y231553D02*
X336025Y231511D01*
G01X337923Y214965D02*
X337928Y215117D01*
G01X337919Y214866D02*
X337923Y214965D01*
G01X337914Y214824D02*
X337919Y214866D01*
G01X339953Y231413D02*
X339948Y231260D01*
G01X339957Y231511D02*
X339953Y231413D01*
G01X339962Y231553D02*
X339957Y231511D01*
G01X341856Y214965D02*
X341860Y215117D01*
G01X341851Y214866D02*
X341856Y214965D01*
G01X341847Y214824D02*
X341851Y214866D01*
G01X343894Y231413D02*
X343890Y231260D01*
G01X343899Y231511D02*
X343894Y231413D01*
G01X343903Y231553D02*
X343899Y231511D01*
G01X324201Y232353D02*
X324196Y232147D01*
G01X324207Y232484D02*
X324201Y232353D01*
G01X324214Y232538D02*
X324207Y232484D01*
G01X322179Y214024D02*
X322184Y214231D01*
G01X322173Y213893D02*
X322179Y214024D01*
G01X322166Y213840D02*
X322173Y213893D01*
G01X328143Y232353D02*
X328137Y232147D01*
G01X328149Y232484D02*
X328143Y232353D01*
G01X328155Y232538D02*
X328149Y232484D01*
G01X326111Y214024D02*
X326117Y214231D01*
G01X326105Y213893D02*
X326111Y214024D01*
G01X326099Y213840D02*
X326105Y213893D01*
G01X332075Y232353D02*
X332070Y232147D01*
G01X332081Y232484D02*
X332075Y232353D01*
G01X332088Y232538D02*
X332081Y232484D01*
G01X330053Y214024D02*
X330058Y214231D01*
G01X330047Y213893D02*
X330053Y214024D01*
G01X330040Y213840D02*
X330047Y213893D01*
G01X336017Y232353D02*
X336011Y232147D01*
G01X336023Y232484D02*
X336017Y232353D01*
G01X336029Y232538D02*
X336023Y232484D01*
G01X333985Y214024D02*
X333991Y214231D01*
G01X333979Y213893D02*
X333985Y214024D01*
G01X333973Y213840D02*
X333979Y213893D01*
G01X339949Y232353D02*
X339944Y232147D01*
G01X339955Y232484D02*
X339949Y232353D01*
G01X339962Y232538D02*
X339955Y232484D01*
G01X337927Y214024D02*
X337932Y214231D01*
G01X337921Y213893D02*
X337927Y214024D01*
G01X337914Y213840D02*
X337921Y213893D01*
G01X343891Y232353D02*
X343885Y232147D01*
G01X343897Y232484D02*
X343891Y232353D01*
G01X343903Y232538D02*
X343897Y232484D01*
G01X341859Y214024D02*
X341865Y214231D01*
G01X341853Y213893D02*
X341859Y214024D01*
G01X341847Y213840D02*
X341853Y213893D01*
G01X327882Y216168D02*
X327883Y216570D01*
G01X327879Y215841D02*
X327882Y216168D01*
G01X327875Y215645D02*
X327879Y215841D01*
G01X327870Y215615D02*
X327875Y215645D01*
G01X334246Y230209D02*
X334245Y229807D01*
G01X334249Y230537D02*
X334246Y230209D01*
G01X334253Y230733D02*
X334249Y230537D01*
G01X334257Y230762D02*
X334253Y230733D01*
G01X335756Y216168D02*
X335757Y216570D01*
G01X335753Y215841D02*
X335756Y216168D01*
G01X335749Y215645D02*
X335753Y215841D01*
G01X335745Y215615D02*
X335749Y215645D01*
G01X342120Y230209D02*
X342119Y229807D01*
G01X342123Y230537D02*
X342120Y230209D01*
G01X342127Y230733D02*
X342123Y230537D01*
G01X342131Y230762D02*
X342127Y230733D01*
G01X343630Y216168D02*
X343631Y216570D01*
G01X343627Y215841D02*
X343630Y216168D01*
G01X343623Y215645D02*
X343627Y215841D01*
G01X343619Y215615D02*
X343623Y215645D01*
G01X284569Y214622D02*
X284570Y214621D01*
G01X284568Y214624D02*
X284569Y214622D01*
G01X284568Y214627D02*
Y214624D01*
G01X283071Y231756D02*
X283070D01*
G01X283071Y231754D02*
Y231756D01*
G01X283072Y231750D02*
X283071Y231754D01*
G01X292443Y214622D02*
X292444Y214621D01*
G01X292442Y214624D02*
X292443Y214622D01*
G01X292442Y214627D02*
Y214624D01*
G01X290945Y231756D02*
X290944D01*
G01X290945Y231754D02*
Y231756D01*
G01X290946Y231750D02*
X290945Y231754D01*
G01X300317Y214622D02*
X300318Y214621D01*
G01X300316Y214624D02*
X300317Y214622D01*
G01X300316Y214627D02*
Y214624D01*
G01X298819Y231756D02*
X298818D01*
G01X298819Y231754D02*
Y231756D01*
G01X298820Y231750D02*
X298819Y231754D01*
G01X308191Y214622D02*
X308192Y214621D01*
G01X308191Y214624D02*
Y214622D01*
G01X308190Y214627D02*
X308191Y214624D01*
G01X338189Y230771D02*
X338188Y230772D01*
G01X338189Y230768D02*
Y230771D01*
G01X338190Y230762D02*
X338189Y230768D01*
G01X339687Y215606D02*
X339688Y215605D01*
G01X339687Y215610D02*
Y215606D01*
G01X339686Y215615D02*
X339687Y215610D01*
G01X323950Y230180D02*
X323951Y229807D01*
G01X323947Y230490D02*
X323950Y230180D01*
G01X323944Y230698D02*
X323947Y230490D01*
G01X323940Y230772D02*
X323944Y230698D01*
G01X330304Y216197D02*
X330303Y216570D01*
G01X330307Y215887D02*
X330304Y216197D01*
G01X330310Y215680D02*
X330307Y215887D01*
G01X330314Y215605D02*
X330310Y215680D01*
G01X331824Y230180D02*
X331825Y229807D01*
G01X331821Y230490D02*
X331824Y230180D01*
G01X331818Y230698D02*
X331821Y230490D01*
G01X331814Y230772D02*
X331818Y230698D01*
G01X328140Y213893D02*
X328146Y213840D01*
G01X328134Y214024D02*
X328140Y213893D01*
G01X328128Y214231D02*
X328134Y214024D01*
G01X330047Y232484D02*
X330040Y232538D01*
G01X330053Y232353D02*
X330047Y232484D01*
G01X330058Y232147D02*
X330053Y232353D01*
G01X332081Y213893D02*
X332088Y213840D01*
G01X332075Y214024D02*
X332081Y213893D01*
G01X332070Y214231D02*
X332075Y214024D01*
G01X333988Y232484D02*
X333982Y232538D01*
G01X333994Y232353D02*
X333988Y232484D01*
G01X334000Y232147D02*
X333994Y232353D01*
G01X336014Y213893D02*
X336020Y213840D01*
G01X336008Y214024D02*
X336014Y213893D01*
G01X336002Y214231D02*
X336008Y214024D01*
G01X337921Y232484D02*
X337914Y232538D01*
G01X337927Y232353D02*
X337921Y232484D01*
G01X337932Y232147D02*
X337927Y232353D01*
G01X339955Y213893D02*
X339962Y213840D01*
G01X339949Y214024D02*
X339955Y213893D01*
G01X339944Y214231D02*
X339949Y214024D01*
G01X341862Y232484D02*
X341856Y232538D01*
G01X341868Y232353D02*
X341862Y232484D01*
G01X341874Y232147D02*
X341868Y232353D01*
G01X343888Y213893D02*
X343894Y213840D01*
G01X343882Y214024D02*
X343888Y213893D01*
G01X343876Y214231D02*
X343882Y214024D01*
G01X345795Y232484D02*
X345788Y232538D01*
G01X345801Y232353D02*
X345795Y232484D01*
G01X345806Y232147D02*
X345801Y232353D01*
G01X328141Y214866D02*
X328146Y214824D01*
G01X328137Y214965D02*
X328141Y214866D01*
G01X328133Y215117D02*
X328137Y214965D01*
G01X330045Y231511D02*
X330040Y231553D01*
G01X330049Y231413D02*
X330045Y231511D01*
G01X330054Y231260D02*
X330049Y231413D01*
G01X332083Y214866D02*
X332088Y214824D01*
G01X332079Y214965D02*
X332083Y214866D01*
G01X332074Y215117D02*
X332079Y214965D01*
G01X333987Y231511D02*
X333982Y231553D01*
G01X333991Y231413D02*
X333987Y231511D01*
G01X333995Y231260D02*
X333991Y231413D01*
G01X336015Y214866D02*
X336020Y214824D01*
G01X336011Y214965D02*
X336015Y214866D01*
G01X336007Y215117D02*
X336011Y214965D01*
G01X337919Y231511D02*
X337914Y231553D01*
G01X337923Y231413D02*
X337919Y231511D01*
G01X337928Y231260D02*
X337923Y231413D01*
G01X339957Y214866D02*
X339962Y214824D01*
G01X339953Y214965D02*
X339957Y214866D01*
G01X339948Y215117D02*
X339953Y214965D01*
G01X341861Y231511D02*
X341856Y231553D01*
G01X341865Y231413D02*
X341861Y231511D01*
G01X341869Y231260D02*
X341865Y231413D01*
G01X343889Y214866D02*
X343894Y214824D01*
G01X343885Y214965D02*
X343889Y214866D01*
G01X343881Y215117D02*
X343885Y214965D01*
G01X345793Y231511D02*
X345788Y231553D01*
G01X345797Y231413D02*
X345793Y231511D01*
G01X345802Y231260D02*
X345797Y231413D01*
G01X334243Y215645D02*
X334248Y215615D01*
G01X334239Y215841D02*
X334243Y215645D01*
G01X334237Y216168D02*
X334239Y215841D01*
G01X334236Y216570D02*
X334237Y216168D01*
G01X335758Y230733D02*
X335754Y230762D01*
G01X335762Y230537D02*
X335758Y230733D01*
G01X335765Y230209D02*
X335762Y230537D01*
G01X335766Y229807D02*
X335765Y230209D01*
G01X342117Y215645D02*
X342122Y215615D01*
G01X342113Y215841D02*
X342117Y215645D01*
G01X342111Y216168D02*
X342113Y215841D01*
G01X342110Y216570D02*
X342111Y216168D01*
G01X343632Y230733D02*
X343628Y230762D01*
G01X343637Y230537D02*
X343632Y230733D01*
G01X343639Y230209D02*
X343637Y230537D01*
G01X343640Y229807D02*
X343639Y230209D01*
G01X331822Y231608D02*
X331814Y231756D01*
G01X331829Y231193D02*
X331822Y231608D01*
G01X331834Y230573D02*
X331829Y231193D01*
G01X331836Y229826D02*
X331834Y230573D01*
G01X338180Y214770D02*
X338188Y214621D01*
G01X338173Y215184D02*
X338180Y214770D01*
G01X338168Y215804D02*
X338173Y215184D01*
G01X338166Y216551D02*
X338168Y215804D01*
G01X338184Y215678D02*
X338188Y215605D01*
G01X338181Y215887D02*
X338184Y215678D01*
G01X338178Y216200D02*
X338181Y215887D01*
G01X338177Y216570D02*
X338178Y216200D01*
G01X339692Y230699D02*
X339688Y230772D01*
G01X339695Y230490D02*
X339692Y230699D01*
G01X339698Y230178D02*
X339695Y230490D01*
G01X339699Y229807D02*
X339698Y230178D01*
G01X339696Y231608D02*
X339688Y231756D01*
G01X339703Y231193D02*
X339696Y231608D01*
G01X339708Y230573D02*
X339703Y231193D01*
G01X339710Y229826D02*
X339708Y230573D01*
G01X346054Y214770D02*
X346062Y214621D01*
G01X346047Y215184D02*
X346054Y214770D01*
G01X346042Y215804D02*
X346047Y215184D01*
G01X346040Y216551D02*
X346042Y215804D01*
G01X346058Y215678D02*
X346062Y215605D01*
G01X346055Y215887D02*
X346058Y215678D01*
G01X346052Y216200D02*
X346055Y215887D01*
G01X346051Y216570D02*
X346052Y216200D01*
G01X331818Y215680D02*
X331814Y215605D01*
G01X331821Y215887D02*
X331818Y215680D01*
G01X331824Y216197D02*
X331821Y215887D01*
G01X331825Y216570D02*
X331824Y216197D01*
G01X339708Y215804D02*
X339710Y216551D01*
G01X339703Y215184D02*
X339708Y215804D01*
G01X339696Y214770D02*
X339703Y215184D01*
G01X339688Y214621D02*
X339696Y214770D01*
G01X346042Y230573D02*
X346040Y229826D01*
G01X346047Y231193D02*
X346042Y230573D01*
G01X346054Y231608D02*
X346047Y231193D01*
G01X346062Y231756D02*
X346054Y231608D01*
G01X339698Y216200D02*
X339699Y216570D01*
G01X339695Y215887D02*
X339698Y216200D01*
G01X339692Y215678D02*
X339695Y215887D01*
G01X339688Y215605D02*
X339692Y215678D01*
G01X346052Y230178D02*
X346051Y229807D01*
G01X346055Y230490D02*
X346052Y230178D01*
G01X346058Y230699D02*
X346055Y230490D01*
G01X346062Y230772D02*
X346058Y230699D01*
G01X345797Y214965D02*
X345802Y215117D01*
G01X345793Y214866D02*
X345797Y214965D01*
G01X345788Y214824D02*
X345793Y214866D01*
G01X345801Y214024D02*
X345806Y214231D01*
G01X345795Y213893D02*
X345801Y214024D01*
G01X345788Y213840D02*
X345795Y213893D01*
G01X306693Y231756D02*
X306692D01*
G01X306693Y231754D02*
Y231756D01*
G01X306694Y231750D02*
X306693Y231754D01*
G01X316065Y214622D02*
X316066Y214621D01*
G01X316065Y214624D02*
Y214622D01*
G01X316064Y214627D02*
X316065Y214624D01*
G01X314567Y231756D02*
X314566D01*
G01X314567Y231754D02*
Y231756D01*
G01X314568Y231750D02*
X314567Y231754D01*
G01X323939Y214622D02*
X323940Y214621D01*
G01X323939Y214624D02*
Y214622D01*
G01X323938Y214627D02*
X323939Y214624D01*
G01X322441Y231756D02*
X322440D01*
G01X322441Y231754D02*
Y231756D01*
G01X322442Y231750D02*
X322441Y231754D01*
G01X331813Y214622D02*
X331814Y214621D01*
G01X331813Y214624D02*
Y214622D01*
G01X331812Y214627D02*
X331813Y214624D01*
G01X330315Y231756D02*
X330314D01*
G01X330315Y231754D02*
Y231756D01*
G01X330316Y231750D02*
X330315Y231754D01*
G01X346063Y230771D02*
X346062Y230772D01*
G01X346063Y230768D02*
Y230771D01*
G01X346064Y230762D02*
X346063Y230768D01*
G01X339687Y214622D02*
X339688Y214621D01*
G01X339687Y214624D02*
Y214622D01*
G01X339686Y214627D02*
X339687Y214624D01*
G01X338189Y231756D02*
X338188D01*
G01X338189Y231754D02*
Y231756D01*
G01X338190Y231750D02*
X338189Y231754D01*
G01X346063Y231756D02*
X346062D01*
G01X346063Y231754D02*
Y231756D01*
G01X346064Y231750D02*
X346063Y231754D01*
G01X323939Y215610D02*
X323938Y215617D01*
G01X323939Y215606D02*
Y215610D01*
G01X323940Y215605D02*
X323939Y215606D01*
G01X322441Y230768D02*
X322442Y230760D01*
G01X322441Y230771D02*
Y230768D01*
G01X322440Y230772D02*
X322441Y230771D01*
G01X331813Y215610D02*
X331812Y215617D01*
G01X331813Y215606D02*
Y215610D01*
G01X331814Y215605D02*
X331813Y215606D01*
G01X330315Y230768D02*
X330316Y230760D01*
G01X330315Y230771D02*
Y230768D01*
G01X330314Y230772D02*
X330315Y230771D01*
G01X345758Y214823D02*
X345743Y214822D01*
G01X345773Y214823D02*
X345758D01*
G01X345788Y214824D02*
X345773Y214823D01*
G01X341817D02*
X341802Y214822D01*
G01X341832Y214823D02*
X341817D01*
G01X341847Y214824D02*
X341832Y214823D01*
G01X337884D02*
X337869Y214822D01*
G01X337899Y214823D02*
X337884D01*
G01X337914Y214824D02*
X337899Y214823D01*
G01X333943D02*
X333928Y214822D01*
G01X333958Y214823D02*
X333943D01*
G01X333973Y214824D02*
X333958Y214823D01*
G01X330010D02*
X329995Y214822D01*
G01X330025Y214823D02*
X330010D01*
G01X330040Y214824D02*
X330025Y214823D01*
G01X322136D02*
X322121Y214822D01*
G01X322151Y214823D02*
X322136D01*
G01X322166Y214824D02*
X322151Y214823D01*
G01X314262D02*
X314247Y214822D01*
G01X314277Y214823D02*
X314262D01*
G01X314292Y214824D02*
X314277Y214823D01*
G01X310321D02*
X310306Y214822D01*
G01X310336Y214823D02*
X310321D01*
G01X310351Y214824D02*
X310336Y214823D01*
G01X306388D02*
X306373Y214822D01*
G01X306403Y214823D02*
X306388D01*
G01X306418Y214824D02*
X306403Y214823D01*
G01X302447D02*
X302432Y214822D01*
G01X302462Y214823D02*
X302447D01*
G01X302477Y214824D02*
X302462Y214823D01*
G01X298514D02*
X298499Y214822D01*
G01X298529Y214823D02*
X298514D01*
G01X298544Y214824D02*
X298529Y214823D01*
G01X294573D02*
X294558Y214822D01*
G01X294588Y214823D02*
X294573D01*
G01X294603Y214824D02*
X294588Y214823D01*
G01X290640D02*
X290625Y214822D01*
G01X290655Y214823D02*
X290640D01*
G01X290670Y214824D02*
X290655Y214823D01*
G01X286699D02*
X286684Y214822D01*
G01X286714Y214823D02*
X286699D01*
G01X286729Y214824D02*
X286714Y214823D01*
G01X282766D02*
X282751Y214822D01*
G01X282781Y214823D02*
X282766D01*
G01X282796Y214824D02*
X282781Y214823D01*
G01X278825D02*
X278810Y214822D01*
G01X278840Y214823D02*
X278825D01*
G01X278855Y214824D02*
X278840Y214823D01*
G01X274892D02*
X274877Y214822D01*
G01X274907Y214823D02*
X274892D01*
G01X274922Y214824D02*
X274907Y214823D01*
G01X270951D02*
X270936Y214822D01*
G01X270966Y214823D02*
X270951D01*
G01X270981Y214824D02*
X270966Y214823D01*
G01X267018D02*
X267003Y214822D01*
G01X267033Y214823D02*
X267018D01*
G01X267048Y214824D02*
X267033Y214823D01*
G01X339992Y231555D02*
X340007D01*
G01X339977Y231554D02*
X339992Y231555D01*
G01X339962Y231553D02*
X339977Y231554D01*
G01X332118Y231555D02*
X332133D01*
G01X332103Y231554D02*
X332118Y231555D01*
G01X332088Y231553D02*
X332103Y231554D01*
G01X328185Y231555D02*
X328200D01*
G01X328170Y231554D02*
X328185Y231555D01*
G01X328155Y231553D02*
X328170Y231554D01*
G01X324244Y231555D02*
X324259D01*
G01X324229Y231554D02*
X324244Y231555D01*
G01X324214Y231553D02*
X324229Y231554D01*
G01X320311Y231555D02*
X320326D01*
G01X320296Y231554D02*
X320311Y231555D01*
G01X320281Y231553D02*
X320296Y231554D01*
G01X316370Y231555D02*
X316385D01*
G01X316355Y231554D02*
X316370Y231555D01*
G01X316340Y231553D02*
X316355Y231554D01*
G01X312437Y231555D02*
X312452D01*
G01X312422Y231554D02*
X312437Y231555D01*
G01X312407Y231553D02*
X312422Y231554D01*
G01X308496Y231555D02*
X308511D01*
G01X308481Y231554D02*
X308496Y231555D01*
G01X308466Y231553D02*
X308481Y231554D01*
G01X300622Y231555D02*
X300637D01*
G01X300607Y231554D02*
X300622Y231555D01*
G01X300592Y231553D02*
X300607Y231554D01*
G01X292748Y231555D02*
X292763D01*
G01X292733Y231554D02*
X292748Y231555D01*
G01X292717Y231553D02*
X292733Y231554D01*
G01X288815Y231555D02*
X288830D01*
G01X288800Y231554D02*
X288815Y231555D01*
G01X288785Y231553D02*
X288800Y231554D01*
G01X284873Y231555D02*
X284889D01*
G01X284858Y231554D02*
X284873Y231555D01*
G01X284843Y231553D02*
X284858Y231554D01*
G01X280941Y231555D02*
X280956D01*
G01X280926Y231554D02*
X280941Y231555D01*
G01X280911Y231553D02*
X280926Y231554D01*
G01X276999Y231555D02*
X277014D01*
G01X276984Y231554D02*
X276999Y231555D01*
G01X276969Y231553D02*
X276984Y231554D01*
G01X269125Y231555D02*
X269140D01*
G01X269110Y231554D02*
X269125Y231555D01*
G01X269095Y231553D02*
X269110Y231554D01*
G01X345758Y213838D02*
X345743D01*
G01X345773Y213839D02*
X345758Y213838D01*
G01X345788Y213840D02*
X345773Y213839D01*
G01X341817Y213838D02*
X341802D01*
G01X341832Y213839D02*
X341817Y213838D01*
G01X341847Y213840D02*
X341832Y213839D01*
G01X337884Y213838D02*
X337869D01*
G01X337899Y213839D02*
X337884Y213838D01*
G01X337914Y213840D02*
X337899Y213839D01*
G01X333943Y213838D02*
X333928D01*
G01X333958Y213839D02*
X333943Y213838D01*
G01X333973Y213840D02*
X333958Y213839D01*
G01X326069Y213838D02*
X326054D01*
G01X326084Y213839D02*
X326069Y213838D01*
G01X326099Y213840D02*
X326084Y213839D01*
G01X318195Y213838D02*
X318180D01*
G01X318210Y213839D02*
X318195Y213838D01*
G01X318225Y213840D02*
X318210Y213839D01*
G01X314262Y213838D02*
X314247D01*
G01X314277Y213839D02*
X314262Y213838D01*
G01X314292Y213840D02*
X314277Y213839D01*
G01X310321Y213838D02*
X310306D01*
G01X310336Y213839D02*
X310321Y213838D01*
G01X310351Y213840D02*
X310336Y213839D01*
G01X306388Y213838D02*
X306373D01*
G01X306403Y213839D02*
X306388Y213838D01*
G01X306418Y213840D02*
X306403Y213839D01*
G01X302447Y213838D02*
X302432D01*
G01X302462Y213839D02*
X302447Y213838D01*
G01X302477Y213840D02*
X302462Y213839D01*
G01X298514Y213838D02*
X298499D01*
G01X298529Y213839D02*
X298514Y213838D01*
G01X298544Y213840D02*
X298529Y213839D01*
G01X294573Y213838D02*
X294558D01*
G01X294588Y213839D02*
X294573Y213838D01*
G01X294603Y213840D02*
X294588Y213839D01*
G01X290640Y213838D02*
X290625D01*
G01X290655Y213839D02*
X290640Y213838D01*
G01X290670Y213840D02*
X290655Y213839D01*
G01X286699Y213838D02*
X286684D01*
G01X286714Y213839D02*
X286699Y213838D01*
G01X286729Y213840D02*
X286714Y213839D01*
G01X282766Y213838D02*
X282751D01*
G01X282781Y213839D02*
X282766Y213838D01*
G01X282796Y213840D02*
X282781Y213839D01*
G01X278825Y213838D02*
X278810D01*
G01X278840Y213839D02*
X278825Y213838D01*
G01X278855Y213840D02*
X278840Y213839D01*
G01X274892Y213838D02*
X274877D01*
G01X274907Y213839D02*
X274892Y213838D01*
G01X274922Y213840D02*
X274907Y213839D01*
G01X270951Y213838D02*
X270936D01*
G01X270966Y213839D02*
X270951Y213838D01*
G01X270981Y213840D02*
X270966Y213839D01*
G01X267018Y213838D02*
X267003D01*
G01X267033Y213839D02*
X267018Y213838D01*
G01X267048Y213840D02*
X267033Y213839D01*
G01X343933Y232539D02*
X343948D01*
G01X343918Y232538D02*
X343933Y232539D01*
G01X343903Y232538D02*
X343918D01*
G01X339992Y232539D02*
X340007D01*
G01X339977Y232538D02*
X339992Y232539D01*
G01X339962Y232538D02*
X339977D01*
G01X336059Y232539D02*
X336074D01*
G01X336044Y232538D02*
X336059Y232539D01*
G01X336029Y232538D02*
X336044D01*
G01X320311Y232539D02*
X320326D01*
G01X320296Y232538D02*
X320311Y232539D01*
G01X320281Y232538D02*
X320296D01*
G01X316370Y232539D02*
X316385D01*
G01X316355Y232538D02*
X316370Y232539D01*
G01X316340Y232538D02*
X316355D01*
G01X312437Y232539D02*
X312452D01*
G01X312422Y232538D02*
X312437Y232539D01*
G01X312407Y232538D02*
X312422D01*
G01X308496Y232539D02*
X308511D01*
G01X308481Y232538D02*
X308496Y232539D01*
G01X308466Y232538D02*
X308481D01*
G01X304563Y232539D02*
X304578D01*
G01X304548Y232538D02*
X304563Y232539D01*
G01X304533Y232538D02*
X304548D01*
G01X300622Y232539D02*
X300637D01*
G01X300607Y232538D02*
X300622Y232539D01*
G01X300592Y232538D02*
X300607D01*
G01X296689Y232539D02*
X296704D01*
G01X296674Y232538D02*
X296689Y232539D01*
G01X296659Y232538D02*
X296674D01*
G01X292748Y232539D02*
X292763D01*
G01X292733Y232538D02*
X292748Y232539D01*
G01X292717Y232538D02*
X292733D01*
G01X288815Y232539D02*
X288830D01*
G01X288800Y232538D02*
X288815Y232539D01*
G01X288785Y232538D02*
X288800D01*
G01X284873Y232539D02*
X284889D01*
G01X284858Y232538D02*
X284873Y232539D01*
G01X284843Y232538D02*
X284858D01*
G01X280941Y232539D02*
X280956D01*
G01X280926Y232538D02*
X280941Y232539D01*
G01X280911Y232538D02*
X280926D01*
G01X276999Y232539D02*
X277014D01*
G01X276984Y232538D02*
X276999Y232539D01*
G01X276969Y232538D02*
X276984D01*
G01X273067Y232539D02*
X273082D01*
G01X273052Y232538D02*
X273067Y232539D01*
G01X273037Y232538D02*
X273052D01*
G01X269110Y213839D02*
X269095Y213840D01*
G01X269125Y213838D02*
X269110Y213839D01*
G01X269140Y213838D02*
X269125D01*
G01X273043Y213839D02*
X273028Y213840D01*
G01X273058Y213838D02*
X273043Y213839D01*
G01X273073Y213838D02*
X273058D01*
G01X276984Y213839D02*
X276969Y213840D01*
G01X276999Y213838D02*
X276984Y213839D01*
G01X277014Y213838D02*
X276999D01*
G01X280917Y213839D02*
X280902Y213840D01*
G01X280932Y213838D02*
X280917Y213839D01*
G01X280947Y213838D02*
X280932D01*
G01X284858Y213839D02*
X284843Y213840D01*
G01X284873Y213838D02*
X284858Y213839D01*
G01X284889Y213838D02*
X284873D01*
G01X288791Y213839D02*
X288776Y213840D01*
G01X288806Y213838D02*
X288791Y213839D01*
G01X288821Y213838D02*
X288806D01*
G01X292733Y213839D02*
X292717Y213840D01*
G01X292748Y213838D02*
X292733Y213839D01*
G01X292763Y213838D02*
X292748D01*
G01X296665Y213839D02*
X296650Y213840D01*
G01X296680Y213838D02*
X296665Y213839D01*
G01X296695Y213838D02*
X296680D01*
G01X300607Y213839D02*
X300592Y213840D01*
G01X300622Y213838D02*
X300607Y213839D01*
G01X300637Y213838D02*
X300622D01*
G01X304539Y213839D02*
X304524Y213840D01*
G01X304554Y213838D02*
X304539Y213839D01*
G01X304569Y213838D02*
X304554D01*
G01X308481Y213839D02*
X308466Y213840D01*
G01X308496Y213838D02*
X308481Y213839D01*
G01X308511Y213838D02*
X308496D01*
G01X312413Y213839D02*
X312398Y213840D01*
G01X312428Y213838D02*
X312413Y213839D01*
G01X312443Y213838D02*
X312428D01*
G01X316355Y213839D02*
X316340Y213840D01*
G01X316370Y213838D02*
X316355Y213839D01*
G01X316385Y213838D02*
X316370D01*
G01X320287Y213839D02*
X320272Y213840D01*
G01X320302Y213838D02*
X320287Y213839D01*
G01X320317Y213838D02*
X320302D01*
G01X324229Y213839D02*
X324214Y213840D01*
G01X324244Y213838D02*
X324229Y213839D01*
G01X324259Y213838D02*
X324244D01*
G01X328161Y213839D02*
X328146Y213840D01*
G01X328176Y213838D02*
X328161Y213839D01*
G01X328191Y213838D02*
X328176D01*
G01X332103Y213839D02*
X332088Y213840D01*
G01X332118Y213838D02*
X332103Y213839D01*
G01X332133Y213838D02*
X332118D01*
G01X336035Y213839D02*
X336020Y213840D01*
G01X336050Y213838D02*
X336035Y213839D01*
G01X336065Y213838D02*
X336050D01*
G01X339977Y213839D02*
X339962Y213840D01*
G01X339992Y213838D02*
X339977Y213839D01*
G01X340007Y213838D02*
X339992D01*
G01X343909Y213839D02*
X343894Y213840D01*
G01X343924Y213838D02*
X343909Y213839D01*
G01X343939Y213838D02*
X343924D01*
G01X267033Y232538D02*
X267048D01*
G01X267018Y232539D02*
X267033Y232538D01*
G01X267003Y232539D02*
X267018D01*
G01X270975Y232538D02*
X270990D01*
G01X270960Y232539D02*
X270975Y232538D01*
G01X270945Y232539D02*
X270960D01*
G01X274907Y232538D02*
X274922D01*
G01X274892Y232539D02*
X274907Y232538D01*
G01X274877Y232539D02*
X274892D01*
G01X278849Y232538D02*
X278864D01*
G01X278834Y232539D02*
X278849Y232538D01*
G01X278819Y232539D02*
X278834D01*
G01X282781Y232538D02*
X282796D01*
G01X282766Y232539D02*
X282781Y232538D01*
G01X282751Y232539D02*
X282766D01*
G01X286723Y232538D02*
X286738D01*
G01X286708Y232539D02*
X286723Y232538D01*
G01X286693Y232539D02*
X286708D01*
G01X290655Y232538D02*
X290670D01*
G01X290640Y232539D02*
X290655Y232538D01*
G01X290625Y232539D02*
X290640D01*
G01X294597Y232538D02*
X294612D01*
G01X294582Y232539D02*
X294597Y232538D01*
G01X294567Y232539D02*
X294582D01*
G01X298529Y232538D02*
X298544D01*
G01X298514Y232539D02*
X298529Y232538D01*
G01X298499Y232539D02*
X298514D01*
G01X302471Y232538D02*
X302486D01*
G01X302456Y232539D02*
X302471Y232538D01*
G01X302441Y232539D02*
X302456D01*
G01X306403Y232538D02*
X306418D01*
G01X306388Y232539D02*
X306403Y232538D01*
G01X306373Y232539D02*
X306388D01*
G01X310345Y232538D02*
X310360D01*
G01X310330Y232539D02*
X310345Y232538D01*
G01X310315Y232539D02*
X310330D01*
G01X314277Y232538D02*
X314292D01*
G01X314262Y232539D02*
X314277Y232538D01*
G01X314247Y232539D02*
X314262D01*
G01X318219Y232538D02*
X318234D01*
G01X318204Y232539D02*
X318219Y232538D01*
G01X318189Y232539D02*
X318204D01*
G01X322151Y232538D02*
X322166D01*
G01X322136Y232539D02*
X322151Y232538D01*
G01X322121Y232539D02*
X322136D01*
G01X326093Y232538D02*
X326108D01*
G01X326078Y232539D02*
X326093Y232538D01*
G01X326063Y232539D02*
X326078D01*
G01X330025Y232538D02*
X330040D01*
G01X330010Y232539D02*
X330025Y232538D01*
G01X329995Y232539D02*
X330010D01*
G01X333967Y232538D02*
X333982D01*
G01X333952Y232539D02*
X333967Y232538D01*
G01X333937Y232539D02*
X333952D01*
G01X337899Y232538D02*
X337914D01*
G01X337884Y232539D02*
X337899Y232538D01*
G01X337869Y232539D02*
X337884D01*
G01X341841Y232538D02*
X341856D01*
G01X341826Y232539D02*
X341841Y232538D01*
G01X341811Y232539D02*
X341826D01*
G01X345773Y232538D02*
X345788D01*
G01X345758Y232539D02*
X345773Y232538D01*
G01X345743Y232539D02*
X345758D01*
G01X269110Y214823D02*
X269095Y214824D01*
G01X269125Y214823D02*
X269110D01*
G01X269140Y214822D02*
X269125Y214823D01*
G01X273043D02*
X273028Y214824D01*
G01X273058Y214823D02*
X273043D01*
G01X273073Y214822D02*
X273058Y214823D01*
G01X276984D02*
X276969Y214824D01*
G01X276999Y214823D02*
X276984D01*
G01X277014Y214822D02*
X276999Y214823D01*
G01X280917D02*
X280902Y214824D01*
G01X280932Y214823D02*
X280917D01*
G01X280947Y214822D02*
X280932Y214823D01*
G01X284858D02*
X284843Y214824D01*
G01X284873Y214823D02*
X284858D01*
G01X284889Y214822D02*
X284873Y214823D01*
G01X288791D02*
X288776Y214824D01*
G01X288806Y214823D02*
X288791D01*
G01X288821Y214822D02*
X288806Y214823D01*
G01X292733D02*
X292717Y214824D01*
G01X292748Y214823D02*
X292733D01*
G01X292763Y214822D02*
X292748Y214823D01*
G01X296665D02*
X296650Y214824D01*
G01X296680Y214823D02*
X296665D01*
G01X296695Y214822D02*
X296680Y214823D01*
G01X300607D02*
X300592Y214824D01*
G01X300622Y214823D02*
X300607D01*
G01X300637Y214822D02*
X300622Y214823D01*
G01X304539D02*
X304524Y214824D01*
G01X304554Y214823D02*
X304539D01*
G01X304569Y214822D02*
X304554Y214823D01*
G01X308481D02*
X308466Y214824D01*
G01X308496Y214823D02*
X308481D01*
G01X308511Y214822D02*
X308496Y214823D01*
G01X312413D02*
X312398Y214824D01*
G01X312428Y214823D02*
X312413D01*
G01X312443Y214822D02*
X312428Y214823D01*
G01X316355D02*
X316340Y214824D01*
G01X316370Y214823D02*
X316355D01*
G01X316385Y214822D02*
X316370Y214823D01*
G01X324229D02*
X324214Y214824D01*
G01X324244Y214823D02*
X324229D01*
G01X324259Y214822D02*
X324244Y214823D01*
G01X332103D02*
X332088Y214824D01*
G01X332118Y214823D02*
X332103D01*
G01X332133Y214822D02*
X332118Y214823D01*
G01X336035D02*
X336020Y214824D01*
G01X336050Y214823D02*
X336035D01*
G01X336065Y214822D02*
X336050Y214823D01*
G01X339977D02*
X339962Y214824D01*
G01X339992Y214823D02*
X339977D01*
G01X340007Y214822D02*
X339992Y214823D01*
G01X343909D02*
X343894Y214824D01*
G01X343924Y214823D02*
X343909D01*
G01X343939Y214822D02*
X343924Y214823D01*
G01X267033Y231554D02*
X267048Y231553D01*
G01X267018Y231555D02*
X267033Y231554D01*
G01X267003Y231555D02*
X267018D01*
G01X270975Y231554D02*
X270990Y231553D01*
G01X270960Y231555D02*
X270975Y231554D01*
G01X270945Y231555D02*
X270960D01*
G01X274907Y231554D02*
X274922Y231553D01*
G01X274892Y231555D02*
X274907Y231554D01*
G01X274877Y231555D02*
X274892D01*
G01X282781Y231554D02*
X282796Y231553D01*
G01X282766Y231555D02*
X282781Y231554D01*
G01X282751Y231555D02*
X282766D01*
G01X290655Y231554D02*
X290670Y231553D01*
G01X290640Y231555D02*
X290655Y231554D01*
G01X290625Y231555D02*
X290640D01*
G01X294597Y231554D02*
X294612Y231553D01*
G01X294582Y231555D02*
X294597Y231554D01*
G01X294567Y231555D02*
X294582D01*
G01X298529Y231554D02*
X298544Y231553D01*
G01X298514Y231555D02*
X298529Y231554D01*
G01X298499Y231555D02*
X298514D01*
G01X302471Y231554D02*
X302486Y231553D01*
G01X302456Y231555D02*
X302471Y231554D01*
G01X302441Y231555D02*
X302456D01*
G01X306403Y231554D02*
X306418Y231553D01*
G01X306388Y231555D02*
X306403Y231554D01*
G01X306373Y231555D02*
X306388D01*
G01X314277Y231554D02*
X314292Y231553D01*
G01X314262Y231555D02*
X314277Y231554D01*
G01X314247Y231555D02*
X314262D01*
G01X318219Y231554D02*
X318234Y231553D01*
G01X318204Y231555D02*
X318219Y231554D01*
G01X318189Y231555D02*
X318204D01*
G01X322151Y231554D02*
X322166Y231553D01*
G01X322136Y231555D02*
X322151Y231554D01*
G01X322121Y231555D02*
X322136D01*
G01X326093Y231554D02*
X326108Y231553D01*
G01X326078Y231555D02*
X326093Y231554D01*
G01X326063Y231555D02*
X326078D01*
G01X330025Y231554D02*
X330040Y231553D01*
G01X330010Y231555D02*
X330025Y231554D01*
G01X329995Y231555D02*
X330010D01*
G01X333967Y231554D02*
X333982Y231553D01*
G01X333952Y231555D02*
X333967Y231554D01*
G01X333937Y231555D02*
X333952D01*
G01X337899Y231554D02*
X337914Y231553D01*
G01X337884Y231555D02*
X337899Y231554D01*
G01X337869Y231555D02*
X337884D01*
G01X341841Y231554D02*
X341856Y231553D01*
G01X341826Y231555D02*
X341841Y231554D01*
G01X341811Y231555D02*
X341826D01*
G01X345773Y231554D02*
X345788Y231553D01*
G01X345758Y231555D02*
X345773Y231554D01*
G01X345743Y231555D02*
X345758D01*
G01X320302Y214823D02*
X320317Y214822D01*
G01X320287Y214823D02*
X320302D01*
G01X320272Y214824D02*
X320287Y214823D01*
G01X328176D02*
X328191Y214822D01*
G01X328161Y214823D02*
X328176D01*
G01X328146Y214824D02*
X328161Y214823D01*
G01X278834Y231555D02*
X278819D01*
G01X278849Y231554D02*
X278834Y231555D01*
G01X278864Y231553D02*
X278849Y231554D01*
G01X286708Y231555D02*
X286693D01*
G01X286723Y231554D02*
X286708Y231555D01*
G01X286738Y231553D02*
X286723Y231554D01*
G01X310330Y231555D02*
X310315D01*
G01X310345Y231554D02*
X310330Y231555D01*
G01X310360Y231553D02*
X310345Y231554D01*
G01X269125Y232539D02*
X269140D01*
G01X269110Y232538D02*
X269125Y232539D01*
G01X269095Y232538D02*
X269110D01*
G01X267245Y209981D02*
X267403Y209943D01*
G01X268741D02*
X268899Y209981D01*
G01X267245Y211039D02*
X267403Y210965D01*
G01X268741D02*
X268899Y211039D01*
G01X267324Y214627D02*
X267335Y214640D01*
G01X268808D02*
X268820Y214627D01*
G01X268899Y236396D02*
X268741Y236434D01*
G01X267403D02*
X267245Y236396D01*
G01X268899Y235338D02*
X268741Y235412D01*
G01X267403D02*
X267245Y235338D01*
G01X267335Y231737D02*
X267324Y231750D01*
G01X268820D02*
X268808Y231737D01*
G01X272741Y214640D02*
X272752Y214627D01*
G01X271256D02*
X271268Y214640D01*
G01X272836Y218680D02*
X272678Y218717D01*
G01X271340D02*
X271182Y218680D01*
G01X272836Y217621D02*
X272678Y217696D01*
G01X271340D02*
X271182Y217621D01*
G01Y227698D02*
X271340Y227660D01*
G01X271182Y228756D02*
X271340Y228681D01*
G01X272678D02*
X272836Y228756D01*
G01X272678Y227660D02*
X272836Y227698D01*
G01X273082Y231555D02*
X273037Y231553D01*
G01X271277Y231737D02*
X271265Y231750D01*
G01X272762D02*
X272750Y231737D01*
G01X275119Y209981D02*
X275277Y209943D01*
G01X276615D02*
X276773Y209981D01*
G01X275119Y211039D02*
X275277Y210965D01*
G01X276615D02*
X276773Y211039D01*
G01X275198Y214627D02*
X275209Y214640D01*
G01X276682D02*
X276694Y214627D01*
G01X276773Y236396D02*
X276615Y236434D01*
G01X275277D02*
X275119Y236396D01*
G01X276773Y235338D02*
X276615Y235412D01*
G01X275277D02*
X275119Y235338D01*
G01X275209Y231737D02*
X275198Y231750D01*
G01X276694D02*
X276682Y231737D01*
G01X280615Y214640D02*
X280626Y214627D01*
G01X279130D02*
X279142Y214640D01*
G01X280710Y218680D02*
X280552Y218717D01*
G01X279214D02*
X279056Y218680D01*
G01X280710Y217621D02*
X280552Y217696D01*
G01X279214D02*
X279056Y217621D01*
G01Y227698D02*
X279214Y227660D01*
G01X280552D02*
X280710Y227698D01*
G01X279056Y228756D02*
X279214Y228681D01*
G01X280552D02*
X280710Y228756D01*
G01X279151Y231737D02*
X279139Y231750D01*
G01X280636D02*
X280624Y231737D01*
G01X282993Y209981D02*
X283151Y209943D01*
G01X284489D02*
X284647Y209981D01*
G01X282993Y211039D02*
X283151Y210965D01*
G01X284489D02*
X284647Y211039D01*
G01X283072Y214627D02*
X283083Y214640D01*
G01X284556D02*
X284568Y214627D01*
G01X284647Y236396D02*
X284489Y236434D01*
G01X283151D02*
X282993Y236396D01*
G01X284647Y235338D02*
X284489Y235412D01*
G01X283151D02*
X282993Y235338D01*
G01X283083Y231737D02*
X283072Y231750D01*
G01X284568D02*
X284556Y231737D01*
G01X288489Y214640D02*
X288500Y214627D01*
G01X287004D02*
X287016Y214640D01*
G01X288584Y218680D02*
X288426Y218717D01*
G01X287088D02*
X286930Y218680D01*
G01X288584Y217621D02*
X288426Y217696D01*
G01X287088D02*
X286930Y217621D01*
G01Y227698D02*
X287088Y227660D01*
G01X288426D02*
X288584Y227698D01*
G01X286930Y228756D02*
X287088Y228681D01*
G01X288426D02*
X288584Y228756D01*
G01X287025Y231737D02*
X287014Y231750D01*
G01X288510D02*
X288498Y231737D01*
G01X290867Y209981D02*
X291025Y209943D01*
G01X292363D02*
X292521Y209981D01*
G01X290867Y211039D02*
X291025Y210965D01*
G01X292363D02*
X292521Y211039D01*
G01X290946Y214627D02*
X290957Y214640D01*
G01X292430D02*
X292442Y214627D01*
G01X292521Y236396D02*
X292363Y236434D01*
G01X291025D02*
X290867Y236396D01*
G01X292521Y235338D02*
X292363Y235412D01*
G01X291025D02*
X290867Y235338D01*
G01X290957Y231737D02*
X290946Y231750D01*
G01X292442D02*
X292430Y231737D01*
G01X296363Y214640D02*
X296374Y214627D01*
G01X294878D02*
X294890Y214640D01*
G01X296458Y218680D02*
X296300Y218717D01*
G01X294962D02*
X294804Y218680D01*
G01X296458Y217621D02*
X296300Y217696D01*
G01X294962D02*
X294804Y217621D01*
G01Y227698D02*
X294962Y227660D01*
G01X294804Y228756D02*
X294962Y228681D01*
G01X296300D02*
X296458Y228756D01*
G01X296300Y227660D02*
X296458Y227698D01*
G01X296704Y231555D02*
X296659Y231553D01*
G01X294899Y231737D02*
X294888Y231750D01*
G01X296384D02*
X296372Y231737D01*
G01X298741Y209981D02*
X298899Y209943D01*
G01X300237D02*
X300395Y209981D01*
G01X298741Y211039D02*
X298899Y210965D01*
G01X300237D02*
X300395Y211039D01*
G01X298820Y214627D02*
X298831Y214640D01*
G01X300304D02*
X300316Y214627D01*
G01X300395Y236396D02*
X300237Y236434D01*
G01X298899D02*
X298741Y236396D01*
G01X300395Y235338D02*
X300237Y235412D01*
G01X298899D02*
X298741Y235338D01*
G01X298831Y231737D02*
X298820Y231750D01*
G01X300316D02*
X300304Y231737D01*
G01X304237Y214640D02*
X304248Y214627D01*
G01X302752D02*
X302764Y214640D01*
G01X304332Y218680D02*
X304174Y218717D01*
G01X302836D02*
X302678Y218680D01*
G01X304332Y217621D02*
X304174Y217696D01*
G01X302836D02*
X302678Y217621D01*
G01Y227698D02*
X302836Y227660D01*
G01X302678Y228756D02*
X302836Y228681D01*
G01X304174D02*
X304332Y228756D01*
G01X304174Y227660D02*
X304332Y227698D01*
G01X304578Y231555D02*
X304533Y231553D01*
G01X302773Y231737D02*
X302762Y231750D01*
G01X304258D02*
X304246Y231737D01*
G01X306615Y209981D02*
X306773Y209943D01*
G01X308111D02*
X308269Y209981D01*
G01X306615Y211039D02*
X306773Y210965D01*
G01X308111D02*
X308269Y211039D01*
G01X306694Y214627D02*
X306705Y214640D01*
G01X308178D02*
X308190Y214627D01*
G01X308269Y236396D02*
X308111Y236434D01*
G01X306773D02*
X306615Y236396D01*
G01X308269Y235338D02*
X308111Y235412D01*
G01X306773D02*
X306615Y235338D01*
G01X306705Y231737D02*
X306694Y231750D01*
G01X308190D02*
X308178Y231737D01*
G01X312111Y214640D02*
X312122Y214627D01*
G01X310626D02*
X310638Y214640D01*
G01X312206Y218680D02*
X312048Y218717D01*
G01X310710D02*
X310552Y218680D01*
G01X312206Y217621D02*
X312048Y217696D01*
G01X310710D02*
X310552Y217621D01*
G01Y227698D02*
X310710Y227660D01*
G01X312048D02*
X312206Y227698D01*
G01X310552Y228756D02*
X310710Y228681D01*
G01X312048D02*
X312206Y228756D01*
G01X310647Y231737D02*
X310636Y231750D01*
G01X312132D02*
X312120Y231737D01*
G01X314489Y209981D02*
X314647Y209943D01*
G01X315985D02*
X316143Y209981D01*
G01X314489Y211039D02*
X314647Y210965D01*
G01X315985D02*
X316143Y211039D01*
G01X314568Y214627D02*
X314579Y214640D01*
G01X316052D02*
X316064Y214627D01*
G01X316143Y236396D02*
X315985Y236434D01*
G01X314647D02*
X314489Y236396D01*
G01X316143Y235338D02*
X315985Y235412D01*
G01X314647D02*
X314489Y235338D01*
G01X314579Y231737D02*
X314568Y231750D01*
G01X316064D02*
X316052Y231737D01*
G01X319985Y214640D02*
X319996Y214627D01*
G01X318500D02*
X318512Y214640D01*
G01X318180Y214822D02*
X318225Y214824D01*
G01X318584Y218717D02*
X318426Y218680D01*
G01X320080D02*
X319922Y218717D01*
G01X318584Y217696D02*
X318426Y217621D01*
G01X320080D02*
X319922Y217696D01*
G01X318521Y231737D02*
X318510Y231750D01*
G01X320006D02*
X319994Y231737D01*
G01X319922Y227660D02*
X320080Y227698D01*
G01X318426D02*
X318584Y227660D01*
G01X319922Y228681D02*
X320080Y228756D01*
G01X318426D02*
X318584Y228681D01*
G01X323859Y209943D02*
X324017Y209981D01*
G01X322363D02*
X322521Y209943D01*
G01X323859Y210965D02*
X324017Y211039D01*
G01X322363D02*
X322521Y210965D01*
G01X322121Y213838D02*
X322166Y213840D01*
G01X322442Y214627D02*
X322453Y214640D01*
G01X323926D02*
X323938Y214627D01*
G01X322521Y236434D02*
X322363Y236396D01*
G01X324017D02*
X323859Y236434D01*
G01X322521Y235412D02*
X322363Y235338D01*
G01X324017D02*
X323859Y235412D01*
G01X322453Y231737D02*
X322442Y231750D01*
G01X323938D02*
X323926Y231737D01*
G01X324259Y232539D02*
X324214Y232538D01*
G01X327954Y218680D02*
X327796Y218717D01*
G01X326458D02*
X326300Y218680D01*
G01X326458Y217696D02*
X326300Y217621D01*
G01X327954D02*
X327796Y217696D01*
G01X327859Y214640D02*
X327870Y214627D01*
G01X326374D02*
X326386Y214640D01*
G01X326054Y214822D02*
X326099Y214824D01*
G01X326300Y227698D02*
X326458Y227660D01*
G01X327796Y228681D02*
X327954Y228756D01*
G01X326300D02*
X326458Y228681D01*
G01X327796Y227660D02*
X327954Y227698D01*
G01X326395Y231737D02*
X326384Y231750D01*
G01X327880D02*
X327868Y231737D01*
G01X328200Y232539D02*
X328155Y232538D01*
G01X331733Y209943D02*
X331891Y209981D01*
G01X330237D02*
X330395Y209943D01*
G01X331733Y210965D02*
X331891Y211039D01*
G01X330237D02*
X330395Y210965D01*
G01X329995Y213838D02*
X330040Y213840D01*
G01X330316Y214627D02*
X330327Y214640D01*
G01X331800D02*
X331812Y214627D01*
G01X330395Y236434D02*
X330237Y236396D01*
G01X331891D02*
X331733Y236434D01*
G01X330395Y235412D02*
X330237Y235338D01*
G01X331891D02*
X331733Y235412D01*
G01X330327Y231737D02*
X330316Y231750D01*
G01X331812D02*
X331800Y231737D01*
G01X332133Y232539D02*
X332088Y232538D01*
G01X335733Y214640D02*
X335744Y214627D01*
G01X334248D02*
X334260Y214640D01*
G01X335828Y218680D02*
X335670Y218717D01*
G01X334332D02*
X334174Y218680D01*
G01X335828Y217621D02*
X335670Y217696D01*
G01X334332D02*
X334174Y217621D01*
G01Y227698D02*
X334332Y227660D01*
G01X334174Y228756D02*
X334332Y228681D01*
G01X335670D02*
X335828Y228756D01*
G01X335670Y227660D02*
X335828Y227698D01*
G01X336074Y231555D02*
X336029Y231553D01*
G01X334269Y231737D02*
X334258Y231750D01*
G01X335754D02*
X335742Y231737D01*
G01X338111Y209981D02*
X338269Y209943D01*
G01X339607D02*
X339765Y209981D01*
G01X338111Y211039D02*
X338269Y210965D01*
G01X339607D02*
X339765Y211039D01*
G01X338190Y214627D02*
X338201Y214640D01*
G01X339674D02*
X339686Y214627D01*
G01X339765Y236396D02*
X339607Y236434D01*
G01X338269D02*
X338111Y236396D01*
G01X339765Y235338D02*
X339607Y235412D01*
G01X338269D02*
X338111Y235338D01*
G01X338201Y231737D02*
X338190Y231750D01*
G01X339686D02*
X339674Y231737D01*
G01X343607Y214640D02*
X343618Y214627D01*
G01X342122D02*
X342134Y214640D01*
G01X343702Y218680D02*
X343544Y218717D01*
G01X342206D02*
X342048Y218680D01*
G01X343702Y217621D02*
X343544Y217696D01*
G01X342206D02*
X342048Y217621D01*
G01Y227698D02*
X342206Y227660D01*
G01X342048Y228756D02*
X342206Y228681D01*
G01X343544D02*
X343702Y228756D01*
G01X343544Y227660D02*
X343702Y227698D01*
G01X343948Y231555D02*
X343903Y231553D01*
G01X342143Y231737D02*
X342132Y231750D01*
G01X343628D02*
X343616Y231737D01*
G01X345985Y209981D02*
X346143Y209943D01*
G01X345985Y211039D02*
X346143Y210965D01*
G01X346064Y214627D02*
X346075Y214640D01*
G01X346143Y236434D02*
X345985Y236396D01*
G01X346143Y235412D02*
X345985Y235338D01*
G01X346075Y231737D02*
X346064Y231750D01*
G01X269253Y236476D02*
X266891D01*
G01X273190D02*
X270828D01*
G01X277127D02*
X274765D01*
G01X281064D02*
X278702D01*
G01X285001D02*
X282639D01*
G01X288938D02*
X286576D01*
G01X292875D02*
X290513D01*
G01X296812D02*
X294450D01*
G01X300749D02*
X298387D01*
G01X304686D02*
X302324D01*
G01X308623D02*
X306261D01*
G01X312560D02*
X310198D01*
G01X316497D02*
X314135D01*
G01X320434D02*
X318072D01*
G01X324371D02*
X322009D01*
G01X328308D02*
X325946D01*
G01X332245D02*
X329883D01*
G01X336182D02*
X333820D01*
G01X340119D02*
X337757D01*
G01X344056D02*
X341694D01*
G01X347993D02*
X345631D01*
G01X268741Y235492D02*
X267403D01*
G01X276615D02*
X275277D01*
G01X284489D02*
X283151D01*
G01X292363D02*
X291025D01*
G01X300237D02*
X298899D01*
G01X308111D02*
X306773D01*
G01X315985D02*
X314647D01*
G01X323859D02*
X322521D01*
G01X331733D02*
X330395D01*
G01X339607D02*
X338269D01*
G01X347481D02*
X346143D01*
G01X345985Y235393D02*
X347639D01*
G01X338111D02*
X339765D01*
G01X330237D02*
X331891D01*
G01X322363D02*
X324017D01*
G01X314489D02*
X316143D01*
G01X306615D02*
X308269D01*
G01X298741D02*
X300395D01*
G01X290867D02*
X292521D01*
G01X282993D02*
X284647D01*
G01X275119D02*
X276773D01*
G01X267245D02*
X268899D01*
G01X269253Y235295D02*
X266891D01*
G01X273190D02*
X270828D01*
G01X277127D02*
X274765D01*
G01X281064D02*
X278702D01*
G01X285001D02*
X282639D01*
G01X288938D02*
X286576D01*
G01X292875D02*
X290513D01*
G01X296812D02*
X294450D01*
G01X300749D02*
X298387D01*
G01X304686D02*
X302324D01*
G01X308623D02*
X306261D01*
G01X312560D02*
X310198D01*
G01X316497D02*
X314135D01*
G01X320434D02*
X318072D01*
G01X324371D02*
X322009D01*
G01X328308D02*
X325946D01*
G01X332245D02*
X329883D01*
G01X336182D02*
X333820D01*
G01X340119D02*
X337757D01*
G01X344056D02*
X341694D01*
G01X347993D02*
X345631D01*
G01X268899Y234901D02*
X267245D01*
G01X276773D02*
X275119D01*
G01X284647D02*
X282993D01*
G01X292521D02*
X290867D01*
G01X300395D02*
X298741D01*
G01X308269D02*
X306615D01*
G01X316143D02*
X314489D01*
G01X324017D02*
X322363D01*
G01X331891D02*
X330237D01*
G01X339765D02*
X338111D01*
G01X347639D02*
X345985D01*
G01X273426Y234035D02*
X270592D01*
G01X277363D02*
X274529D01*
G01X281300D02*
X278466D01*
G01X285237D02*
X282403D01*
G01X289174D02*
X286340D01*
G01X293111D02*
X290277D01*
G01X297048D02*
X294214D01*
G01X300985D02*
X298151D01*
G01X304922D02*
X302088D01*
G01X308859D02*
X306025D01*
G01X312796D02*
X309962D01*
G01X316733D02*
X313899D01*
G01X320670D02*
X317836D01*
G01X324607D02*
X321773D01*
G01X328544D02*
X325710D01*
G01X332481D02*
X329647D01*
G01X336418D02*
X333584D01*
G01X340355D02*
X337521D01*
G01X344292D02*
X341458D01*
G01X348229D02*
X345395D01*
G01X268899Y233130D02*
X267245D01*
G01X276773D02*
X275119D01*
G01X284647D02*
X282993D01*
G01X292521D02*
X290867D01*
G01X300395D02*
X298741D01*
G01X308269D02*
X306615D01*
G01X316143D02*
X314489D01*
G01X324017D02*
X322363D01*
G01X331891D02*
X330237D01*
G01X339765D02*
X338111D01*
G01X347639D02*
X345985D01*
G01Y232637D02*
X347639D01*
G01X338111D02*
X339765D01*
G01X330237D02*
X331891D01*
G01X322363D02*
X324017D01*
G01X314489D02*
X316143D01*
G01X306615D02*
X308269D01*
G01X298741D02*
X300395D01*
G01X290867D02*
X292521D01*
G01X282993D02*
X284647D01*
G01X275119D02*
X276773D01*
G01X267245D02*
X268899D01*
G01X273426Y232539D02*
X270592D01*
G01X277363D02*
X274529D01*
G01X281300D02*
X278466D01*
G01X285237D02*
X282403D01*
G01X289174D02*
X286340D01*
G01X293111D02*
X290277D01*
G01X297048D02*
X294214D01*
G01X300985D02*
X298151D01*
G01X304922D02*
X302088D01*
G01X308859D02*
X306025D01*
G01X312796D02*
X309962D01*
G01X316733D02*
X313899D01*
G01X320670D02*
X317836D01*
G01X324607D02*
X321773D01*
G01X328544D02*
X325710D01*
G01X332481D02*
X329647D01*
G01X336418D02*
X333584D01*
G01X340355D02*
X337521D01*
G01X344292D02*
X341458D01*
G01X348229D02*
X345395D01*
G01Y232382D02*
X345985D01*
G01X343702D02*
X344292D01*
G01X341458D02*
X342048D01*
G01X339765D02*
X340355D01*
G01X337521D02*
X338111D01*
G01X335828D02*
X336418D01*
G01X333584D02*
X334174D01*
G01X331891D02*
X332481D01*
G01X329647D02*
X330237D01*
G01X327954D02*
X328544D01*
G01X325710D02*
X326300D01*
G01X324017D02*
X324607D01*
G01X321773D02*
X322363D01*
G01X320080D02*
X320670D01*
G01X317836D02*
X318426D01*
G01X316143D02*
X316733D01*
G01X313899D02*
X314489D01*
G01X312206D02*
X312796D01*
G01X309962D02*
X310552D01*
G01X308269D02*
X308859D01*
G01X306025D02*
X306615D01*
G01X304332D02*
X304922D01*
G01X302088D02*
X302678D01*
G01X300395D02*
X300985D01*
G01X298151D02*
X298741D01*
G01X296458D02*
X297048D01*
G01X294214D02*
X294804D01*
G01X292521D02*
X293111D01*
G01X290277D02*
X290867D01*
G01X288584D02*
X289174D01*
G01X286340D02*
X286930D01*
G01X284647D02*
X285237D01*
G01X282403D02*
X282993D01*
G01X280710D02*
X281300D01*
G01X278466D02*
X279056D01*
G01X276773D02*
X277363D01*
G01X274529D02*
X275119D01*
G01X272836D02*
X273426D01*
G01X270592D02*
X271182D01*
G01X268899D02*
X269489D01*
G01X345806Y232147D02*
X347818D01*
G01X341874D02*
X343885D01*
G01X337932D02*
X339944D01*
G01X334000D02*
X336011D01*
G01X330058D02*
X332070D01*
G01X326126D02*
X328137D01*
G01X322184D02*
X324196D01*
G01X318252D02*
X320263D01*
G01X314310D02*
X316322D01*
G01X310378D02*
X312389D01*
G01X306436D02*
X308448D01*
G01X302504D02*
X304515D01*
G01X298562D02*
X300574D01*
G01X294630D02*
X296641D01*
G01X290688D02*
X292700D01*
G01X286756D02*
X288767D01*
G01X282814D02*
X284825D01*
G01X278882D02*
X280893D01*
G01X274940D02*
X276951D01*
G01X271008D02*
X273019D01*
G01X267066D02*
X269077D01*
G01X268822Y231756D02*
X267322D01*
G01X272763D02*
X271264D01*
G01X276696D02*
X275196D01*
G01X280637D02*
X279138D01*
G01X284570D02*
X283070D01*
G01X288511D02*
X287012D01*
G01X292444D02*
X290944D01*
G01X296385D02*
X294886D01*
G01X300318D02*
X298818D01*
G01X304259D02*
X302760D01*
G01X308192D02*
X306692D01*
G01X312133D02*
X310634D01*
G01X316066D02*
X314566D01*
G01X320007D02*
X318508D01*
G01X323940D02*
X322440D01*
G01X327881D02*
X326382D01*
G01X331814D02*
X330314D01*
G01X335755D02*
X334256D01*
G01X339688D02*
X338188D01*
G01X343629D02*
X342130D01*
G01X347562D02*
X346062D01*
G01X346075Y231737D02*
X347548D01*
G01X342143D02*
X343616D01*
G01X338201D02*
X339674D01*
G01X334269D02*
X335742D01*
G01X330327D02*
X331800D01*
G01X326395D02*
X327868D01*
G01X322453D02*
X323926D01*
G01X318521D02*
X319994D01*
G01X314579D02*
X316052D01*
G01X310647D02*
X312120D01*
G01X306705D02*
X308178D01*
G01X302773D02*
X304246D01*
G01X298831D02*
X300304D01*
G01X294899D02*
X296372D01*
G01X290957D02*
X292430D01*
G01X287025D02*
X288498D01*
G01X283083D02*
X284556D01*
G01X279151D02*
X280624D01*
G01X275209D02*
X276682D01*
G01X271277D02*
X272750D01*
G01X267335D02*
X268808D01*
G01X269489Y231712D02*
X268899D01*
G01X271182D02*
X270592D01*
G01X273426D02*
X272836D01*
G01X275119D02*
X274529D01*
G01X277363D02*
X276773D01*
G01X279056D02*
X278466D01*
G01X281300D02*
X280710D01*
G01X282993D02*
X282403D01*
G01X285237D02*
X284647D01*
G01X286930D02*
X286340D01*
G01X289174D02*
X288584D01*
G01X290867D02*
X290277D01*
G01X293111D02*
X292521D01*
G01X294804D02*
X294214D01*
G01X297048D02*
X296458D01*
G01X298741D02*
X298151D01*
G01X300985D02*
X300395D01*
G01X302678D02*
X302088D01*
G01X304922D02*
X304332D01*
G01X306615D02*
X306025D01*
G01X308859D02*
X308269D01*
G01X310552D02*
X309962D01*
G01X312796D02*
X312206D01*
G01X314489D02*
X313899D01*
G01X316733D02*
X316143D01*
G01X318426D02*
X317836D01*
G01X320670D02*
X320080D01*
G01X322363D02*
X321773D01*
G01X324607D02*
X324017D01*
G01X326300D02*
X325710D01*
G01X328544D02*
X327954D01*
G01X330237D02*
X329647D01*
G01X332481D02*
X331891D01*
G01X334174D02*
X333584D01*
G01X336418D02*
X335828D01*
G01X338111D02*
X337521D01*
G01X340355D02*
X339765D01*
G01X342048D02*
X341458D01*
G01X344292D02*
X343702D01*
G01X345985D02*
X345395D01*
G01Y231555D02*
X348229D01*
G01X341458D02*
X344292D01*
G01X337521D02*
X340355D01*
G01X333584D02*
X336418D01*
G01X329647D02*
X332481D01*
G01X325710D02*
X328544D01*
G01X321773D02*
X324607D01*
G01X313899D02*
X316733D01*
G01X309962D02*
X312796D01*
G01X306025D02*
X308859D01*
G01X302088D02*
X304922D01*
G01X298151D02*
X300985D01*
G01X294214D02*
X297048D01*
G01X290277D02*
X293111D01*
G01X282403D02*
X285237D01*
G01X274529D02*
X277363D01*
G01X270592D02*
X273426D01*
G01X281300D02*
X278466D01*
G01X289174D02*
X286340D01*
G01X320670D02*
X317836D01*
G01X272836Y231456D02*
X271182D01*
G01X280710D02*
X279056D01*
G01X288584D02*
X286930D01*
G01X296458D02*
X294804D01*
G01X304332D02*
X302678D01*
G01X312206D02*
X310552D01*
G01X320080D02*
X318426D01*
G01X327954D02*
X326300D01*
G01X335828D02*
X334174D01*
G01X343702D02*
X342048D01*
G01X268555Y231368D02*
X267589D01*
G01X272496D02*
X271531D01*
G01X276429D02*
X275463D01*
G01X280370D02*
X279405D01*
G01X284303D02*
X283337D01*
G01X288244D02*
X287279D01*
G01X292177D02*
X291211D01*
G01X296118D02*
X295153D01*
G01X300051D02*
X299085D01*
G01X303992D02*
X303027D01*
G01X307925D02*
X306959D01*
G01X311866D02*
X310901D01*
G01X315799D02*
X314833D01*
G01X319740D02*
X318775D01*
G01X323673D02*
X322707D01*
G01X327614D02*
X326649D01*
G01X331547D02*
X330581D01*
G01X335488D02*
X334523D01*
G01X339421D02*
X338455D01*
G01X343362D02*
X342397D01*
G01X347295D02*
X346329D01*
G01X345395Y231358D02*
X345710D01*
G01X341458D02*
X341773D01*
G01X337521D02*
X337836D01*
G01X333584D02*
X333899D01*
G01X325710D02*
X326025D01*
G01X317836D02*
X318151D01*
G01X313899D02*
X314214D01*
G01X309962D02*
X310277D01*
G01X306025D02*
X306340D01*
G01X302088D02*
X302403D01*
G01X298151D02*
X298466D01*
G01X294214D02*
X294529D01*
G01X290277D02*
X290592D01*
G01X286340D02*
X286655D01*
G01X282403D02*
X282717D01*
G01X278466D02*
X278780D01*
G01X274529D02*
X274843D01*
G01X270592D02*
X270906D01*
G01X269489D02*
X269174D01*
G01X273426D02*
X273111D01*
G01X277363D02*
X277048D01*
G01X281300D02*
X280985D01*
G01X285237D02*
X284922D01*
G01X289174D02*
X288859D01*
G01X293111D02*
X292796D01*
G01X297048D02*
X296733D01*
G01X300985D02*
X300670D01*
G01X304922D02*
X304607D01*
G01X308859D02*
X308544D01*
G01X312796D02*
X312481D01*
G01X316733D02*
X316418D01*
G01X320670D02*
X320355D01*
G01X322088D02*
X321773D01*
G01X324607D02*
X324292D01*
G01X328544D02*
X328229D01*
G01X329962D02*
X329647D01*
G01X332481D02*
X332166D01*
G01X336418D02*
X336103D01*
G01X340355D02*
X340040D01*
G01X344292D02*
X343977D01*
G01X269082Y231260D02*
X267061D01*
G01X273024D02*
X271003D01*
G01X276956D02*
X274935D01*
G01X280898D02*
X278877D01*
G01X284830D02*
X282809D01*
G01X288772D02*
X286751D01*
G01X292704D02*
X290683D01*
G01X296646D02*
X294625D01*
G01X300578D02*
X298557D01*
G01X304520D02*
X302499D01*
G01X308452D02*
X306431D01*
G01X312394D02*
X310373D01*
G01X316326D02*
X314306D01*
G01X320268D02*
X318247D01*
G01X324200D02*
X322180D01*
G01X328142D02*
X326121D01*
G01X332074D02*
X330054D01*
G01X336016D02*
X333995D01*
G01X339948D02*
X337928D01*
G01X343890D02*
X341869D01*
G01X347822D02*
X345802D01*
G01X342048Y230964D02*
X343702D01*
G01X334174D02*
X335828D01*
G01X326300D02*
X327954D01*
G01X318426D02*
X320080D01*
G01X310552D02*
X312206D01*
G01X302678D02*
X304332D01*
G01X294804D02*
X296458D01*
G01X286930D02*
X288584D01*
G01X279056D02*
X280710D01*
G01X271182D02*
X272836D01*
G01X268822Y230772D02*
X267322D01*
G01X272763D02*
X271264D01*
G01X276696D02*
X275196D01*
G01X280637D02*
X279138D01*
G01X284570D02*
X283070D01*
G01X288511D02*
X287012D01*
G01X292444D02*
X290944D01*
G01X296385D02*
X294886D01*
G01X300318D02*
X298818D01*
G01X304259D02*
X302760D01*
G01X308192D02*
X306692D01*
G01X312133D02*
X310634D01*
G01X316066D02*
X314566D01*
G01X320007D02*
X318508D01*
G01X323940D02*
X322440D01*
G01X327881D02*
X326382D01*
G01X331814D02*
X330314D01*
G01X335755D02*
X334256D01*
G01X339688D02*
X338188D01*
G01X343629D02*
X342130D01*
G01X347562D02*
X346062D01*
G01X268820Y230762D02*
X267324D01*
G01X272762D02*
X271265D01*
G01X276694D02*
X275198D01*
G01X280636D02*
X279139D01*
G01X284568D02*
X283072D01*
G01X288510D02*
X287013D01*
G01X292442D02*
X290946D01*
G01X296384D02*
X294887D01*
G01X300316D02*
X298820D01*
G01X304258D02*
X302761D01*
G01X308190D02*
X306694D01*
G01X312132D02*
X310635D01*
G01X316064D02*
X314568D01*
G01X320006D02*
X318509D01*
G01X323938D02*
X322442D01*
G01X327880D02*
X326383D01*
G01X331812D02*
X330316D01*
G01X335754D02*
X334257D01*
G01X339686D02*
X338190D01*
G01X343628D02*
X342131D01*
G01X347560D02*
X346064D01*
G01X346284Y230441D02*
X347340D01*
G01X342351D02*
X343408D01*
G01X338410D02*
X339466D01*
G01X334477D02*
X335534D01*
G01X330536D02*
X331592D01*
G01X326603D02*
X327660D01*
G01X322662D02*
X323718D01*
G01X318729D02*
X319786D01*
G01X314788D02*
X315844D01*
G01X310855D02*
X311912D01*
G01X306914D02*
X307970D01*
G01X302981D02*
X304038D01*
G01X299040D02*
X300096D01*
G01X295107D02*
X296164D01*
G01X291166D02*
X292222D01*
G01X287233D02*
X288290D01*
G01X283292D02*
X284348D01*
G01X279359D02*
X280416D01*
G01X275418D02*
X276474D01*
G01X271485D02*
X272542D01*
G01X267544D02*
X268600D01*
G01X329883Y230393D02*
X332245D01*
G01X325946D02*
X328308D01*
G01X322009D02*
X324371D01*
G01X269253D02*
X266891D01*
G01X273190D02*
X270828D01*
G01X277127D02*
X274765D01*
G01X281064D02*
X278702D01*
G01X285001D02*
X282639D01*
G01X288938D02*
X286576D01*
G01X292875D02*
X290513D01*
G01X296812D02*
X294450D01*
G01X300749D02*
X298387D01*
G01X304686D02*
X302324D01*
G01X308623D02*
X306261D01*
G01X312560D02*
X310198D01*
G01X316497D02*
X314135D01*
G01X320434D02*
X318072D01*
G01X336182D02*
X333820D01*
G01X340119D02*
X337757D01*
G01X344056D02*
X341694D01*
G01X347993D02*
X345631D01*
G01X345395Y229862D02*
X345710D01*
G01X343977D02*
X344292D01*
G01X341458D02*
X341773D01*
G01X340040D02*
X340355D01*
G01X337521D02*
X337836D01*
G01X336103D02*
X336418D01*
G01X333584D02*
X333899D01*
G01X332166D02*
X332481D01*
G01X329647D02*
X329962D01*
G01X328229D02*
X328544D01*
G01X325710D02*
X326025D01*
G01X324292D02*
X324607D01*
G01X320355D02*
X320670D01*
G01X321773D02*
X322088D01*
G01X317836D02*
X318151D01*
G01X316418D02*
X316733D01*
G01X313899D02*
X314214D01*
G01X312481D02*
X312796D01*
G01X309962D02*
X310277D01*
G01X308544D02*
X308859D01*
G01X306025D02*
X306340D01*
G01X304607D02*
X304922D01*
G01X302088D02*
X302403D01*
G01X300670D02*
X300985D01*
G01X298151D02*
X298466D01*
G01X296733D02*
X297048D01*
G01X294214D02*
X294529D01*
G01X292796D02*
X293111D01*
G01X290277D02*
X290592D01*
G01X288859D02*
X289174D01*
G01X286340D02*
X286655D01*
G01X284922D02*
X285237D01*
G01X282403D02*
X282717D01*
G01X280985D02*
X281300D01*
G01X278466D02*
X278780D01*
G01X277048D02*
X277363D01*
G01X274529D02*
X274843D01*
G01X273111D02*
X273426D01*
G01X270592D02*
X270906D01*
G01X269174D02*
X269489D01*
G01X346040Y229826D02*
X347584D01*
G01X342108D02*
X343651D01*
G01X338166D02*
X339710D01*
G01X334234D02*
X335777D01*
G01X330292D02*
X331836D01*
G01X326360D02*
X327903D01*
G01X322418D02*
X323962D01*
G01X318486D02*
X320029D01*
G01X314544D02*
X316088D01*
G01X310612D02*
X312155D01*
G01X306670D02*
X308214D01*
G01X302738D02*
X304281D01*
G01X298796D02*
X300340D01*
G01X294864D02*
X296407D01*
G01X290922D02*
X292466D01*
G01X286990D02*
X288533D01*
G01X283048D02*
X284592D01*
G01X279116D02*
X280659D01*
G01X275174D02*
X276718D01*
G01X271242D02*
X272785D01*
G01X267300D02*
X268844D01*
G01X346051Y229807D02*
X347573D01*
G01X342119D02*
X343640D01*
G01X338177D02*
X339699D01*
G01X334245D02*
X335766D01*
G01X330303D02*
X331825D01*
G01X326371D02*
X327892D01*
G01X322429D02*
X323951D01*
G01X318497D02*
X320018D01*
G01X314555D02*
X316077D01*
G01X310623D02*
X312144D01*
G01X306681D02*
X308203D01*
G01X302749D02*
X304270D01*
G01X298807D02*
X300329D01*
G01X294875D02*
X296396D01*
G01X290933D02*
X292455D01*
G01X287001D02*
X288522D01*
G01X283059D02*
X284581D01*
G01X279127D02*
X280648D01*
G01X275185D02*
X276707D01*
G01X271253D02*
X272774D01*
G01X267311D02*
X268833D01*
G01X342048Y229193D02*
X343702D01*
G01X334174D02*
X335828D01*
G01X326300D02*
X327954D01*
G01X318426D02*
X320080D01*
G01X310552D02*
X312206D01*
G01X302678D02*
X304332D01*
G01X294804D02*
X296458D01*
G01X286930D02*
X288584D01*
G01X279056D02*
X280710D01*
G01X271182D02*
X272836D01*
G01Y228700D02*
X271182D01*
G01X280710D02*
X279056D01*
G01X288584D02*
X286930D01*
G01X296458D02*
X294804D01*
G01X304332D02*
X302678D01*
G01X312206D02*
X310552D01*
G01X320080D02*
X318426D01*
G01X327954D02*
X326300D01*
G01X335828D02*
X334174D01*
G01X343702D02*
X342048D01*
G01X272678Y228602D02*
X271340D01*
G01X280552D02*
X279214D01*
G01X288426D02*
X287088D01*
G01X296300D02*
X294962D01*
G01X304174D02*
X302836D01*
G01X312048D02*
X310710D01*
G01X319922D02*
X318584D01*
G01X327796D02*
X326458D01*
G01X335670D02*
X334332D01*
G01X343544D02*
X342206D01*
G01Y227618D02*
X343544D01*
G01X334332D02*
X335670D01*
G01X326458D02*
X327796D01*
G01X318584D02*
X319922D01*
G01X310710D02*
X312048D01*
G01X302836D02*
X304174D01*
G01X294962D02*
X296300D01*
G01X287088D02*
X288426D01*
G01X279214D02*
X280552D01*
G01X271340D02*
X272678D01*
G01X268869Y226999D02*
X267274D01*
G01X272811D02*
X271216D01*
G01X276743D02*
X275148D01*
G01X280685D02*
X279090D01*
G01X284617D02*
X283022D01*
G01X288559D02*
X286964D01*
G01X292491D02*
X290896D01*
G01X296433D02*
X294838D01*
G01X300365D02*
X298770D01*
G01X304307D02*
X302712D01*
G01X308239D02*
X306644D01*
G01X312181D02*
X310586D01*
G01X316114D02*
X314518D01*
G01X320055D02*
X318460D01*
G01X323988D02*
X322392D01*
G01X327929D02*
X326334D01*
G01X331862D02*
X330266D01*
G01X335803D02*
X334208D01*
G01X339736D02*
X338140D01*
G01X343677D02*
X342082D01*
G01X347610D02*
X346014D01*
G01X269174Y226889D02*
X266969D01*
G01X273111D02*
X270906D01*
G01X277048D02*
X274843D01*
G01X280985D02*
X278780D01*
G01X284922D02*
X282717D01*
G01X288859D02*
X286655D01*
G01X292796D02*
X290592D01*
G01X296733D02*
X294529D01*
G01X300670D02*
X298466D01*
G01X304607D02*
X302403D01*
G01X308544D02*
X306340D01*
G01X312481D02*
X310277D01*
G01X316418D02*
X314214D01*
G01X320355D02*
X318151D01*
G01X324292D02*
X322088D01*
G01X328229D02*
X326025D01*
G01X332166D02*
X329962D01*
G01X336103D02*
X333899D01*
G01X340040D02*
X337836D01*
G01X343977D02*
X341773D01*
G01X347914D02*
X345710D01*
G01X268941Y226239D02*
X267202D01*
G01X272883D02*
X271144D01*
G01X276815D02*
X275076D01*
G01X280757D02*
X279018D01*
G01X284689D02*
X282950D01*
G01X288631D02*
X286892D01*
G01X292563D02*
X290824D01*
G01X296505D02*
X294766D01*
G01X300437D02*
X298698D01*
G01X304379D02*
X302640D01*
G01X308311D02*
X306573D01*
G01X312253D02*
X310514D01*
G01X316185D02*
X314447D01*
G01X320127D02*
X318388D01*
G01X324059D02*
X322321D01*
G01X328001D02*
X326262D01*
G01X331933D02*
X330195D01*
G01X335875D02*
X334136D01*
G01X339807D02*
X338069D01*
G01X343749D02*
X342010D01*
G01X347681D02*
X345943D01*
G01X346017Y226037D02*
X347607D01*
G01X342084D02*
X343675D01*
G01X338143D02*
X339733D01*
G01X334210D02*
X335801D01*
G01X330269D02*
X331859D01*
G01X326336D02*
X327927D01*
G01X322395D02*
X323985D01*
G01X318462D02*
X320053D01*
G01X314521D02*
X316111D01*
G01X310588D02*
X312179D01*
G01X306647D02*
X308237D01*
G01X302714D02*
X304305D01*
G01X298773D02*
X300363D01*
G01X294840D02*
X296431D01*
G01X290899D02*
X292489D01*
G01X286966D02*
X288557D01*
G01X283025D02*
X284615D01*
G01X279092D02*
X280683D01*
G01X275151D02*
X276741D01*
G01X271218D02*
X272809D01*
G01X267277D02*
X268867D01*
G01X345964Y226012D02*
X347660D01*
G01X342032D02*
X343728D01*
G01X338090D02*
X339786D01*
G01X334158D02*
X335854D01*
G01X330216D02*
X331912D01*
G01X326284D02*
X327980D01*
G01X322342D02*
X324038D01*
G01X318410D02*
X320106D01*
G01X314468D02*
X316164D01*
G01X310536D02*
X312232D01*
G01X306594D02*
X308290D01*
G01X302661D02*
X304358D01*
G01X298720D02*
X300416D01*
G01X294787D02*
X296484D01*
G01X290846D02*
X292542D01*
G01X286913D02*
X288610D01*
G01X282972D02*
X284668D01*
G01X279039D02*
X280736D01*
G01X275098D02*
X276794D01*
G01X271165D02*
X272862D01*
G01X267224D02*
X268920D01*
G01X268927Y225945D02*
X267217D01*
G01X272869D02*
X271158D01*
G01X276801D02*
X275091D01*
G01X280743D02*
X279032D01*
G01X284675D02*
X282965D01*
G01X288617D02*
X286906D01*
G01X292549D02*
X290839D01*
G01X296491D02*
X294780D01*
G01X300423D02*
X298713D01*
G01X304365D02*
X302654D01*
G01X308297D02*
X306587D01*
G01X312239D02*
X310529D01*
G01X316171D02*
X314461D01*
G01X320113D02*
X318403D01*
G01X324045D02*
X322335D01*
G01X327987D02*
X326277D01*
G01X331919D02*
X330209D01*
G01X335861D02*
X334151D01*
G01X339793D02*
X338083D01*
G01X343735D02*
X342025D01*
G01X347667D02*
X345957D01*
G01X345938Y225353D02*
X347686D01*
G01X342005D02*
X343754D01*
G01X338064D02*
X339812D01*
G01X334131D02*
X335880D01*
G01X330190D02*
X331938D01*
G01X326257D02*
X328006D01*
G01X322316D02*
X324064D01*
G01X318383D02*
X320132D01*
G01X314442D02*
X316190D01*
G01X310509D02*
X312258D01*
G01X306568D02*
X308316D01*
G01X302635D02*
X304384D01*
G01X298694D02*
X300442D01*
G01X294761D02*
X296510D01*
G01X290820D02*
X292568D01*
G01X286887D02*
X288636D01*
G01X282946D02*
X284694D01*
G01X279013D02*
X280762D01*
G01X275072D02*
X276820D01*
G01X271139D02*
X272888D01*
G01X267198D02*
X268946D01*
G01X268918Y225050D02*
X267226D01*
G01X272859D02*
X271168D01*
G01X276792D02*
X275100D01*
G01X280733D02*
X279042D01*
G01X284666D02*
X282974D01*
G01X288607D02*
X286916D01*
G01X292540D02*
X290848D01*
G01X296481D02*
X294790D01*
G01X300414D02*
X298722D01*
G01X304355D02*
X302664D01*
G01X308288D02*
X306596D01*
G01X312229D02*
X310538D01*
G01X316162D02*
X314470D01*
G01X320103D02*
X318412D01*
G01X324036D02*
X322344D01*
G01X327977D02*
X326286D01*
G01X331910D02*
X330218D01*
G01X335851D02*
X334160D01*
G01X339784D02*
X338092D01*
G01X343725D02*
X342034D01*
G01X347658D02*
X345966D01*
G01X268927Y224960D02*
X267217D01*
G01X272869D02*
X271158D01*
G01X276801D02*
X275091D01*
G01X280743D02*
X279032D01*
G01X284675D02*
X282965D01*
G01X288617D02*
X286906D01*
G01X292549D02*
X290839D01*
G01X296491D02*
X294780D01*
G01X300423D02*
X298713D01*
G01X304365D02*
X302654D01*
G01X308297D02*
X306587D01*
G01X312239D02*
X310529D01*
G01X316171D02*
X314461D01*
G01X320113D02*
X318403D01*
G01X324045D02*
X322335D01*
G01X327987D02*
X326277D01*
G01X331919D02*
X330209D01*
G01X335861D02*
X334151D01*
G01X339793D02*
X338083D01*
G01X343735D02*
X342025D01*
G01X347667D02*
X345957D01*
G01X345710Y224634D02*
X347914D01*
G01X341773D02*
X343977D01*
G01X337836D02*
X340040D01*
G01X333899D02*
X336103D01*
G01X329962D02*
X332166D01*
G01X326025D02*
X328229D01*
G01X322088D02*
X324292D01*
G01X318151D02*
X320355D01*
G01X314214D02*
X316418D01*
G01X310277D02*
X312481D01*
G01X306340D02*
X308544D01*
G01X302403D02*
X304607D01*
G01X298466D02*
X300670D01*
G01X294529D02*
X296733D01*
G01X290592D02*
X292796D01*
G01X286655D02*
X288859D01*
G01X282717D02*
X284922D01*
G01X278780D02*
X280985D01*
G01X274843D02*
X277048D01*
G01X270906D02*
X273111D01*
G01X266969D02*
X269174D01*
G01X345710Y224467D02*
X347914D01*
G01X341773D02*
X343977D01*
G01X337836D02*
X340040D01*
G01X333899D02*
X336103D01*
G01X329962D02*
X332166D01*
G01X326025D02*
X328229D01*
G01X322088D02*
X324292D01*
G01X318151D02*
X320355D01*
G01X314214D02*
X316418D01*
G01X310277D02*
X312481D01*
G01X306340D02*
X308544D01*
G01X302403D02*
X304607D01*
G01X298466D02*
X300670D01*
G01X294529D02*
X296733D01*
G01X290592D02*
X292796D01*
G01X286655D02*
X288859D01*
G01X282717D02*
X284922D01*
G01X278780D02*
X280985D01*
G01X274843D02*
X277048D01*
G01X270906D02*
X273111D01*
G01X266969D02*
X269174D01*
G01Y221910D02*
X266969D01*
G01X273111D02*
X270906D01*
G01X277048D02*
X274843D01*
G01X280985D02*
X278780D01*
G01X284922D02*
X282717D01*
G01X288859D02*
X286655D01*
G01X292796D02*
X290592D01*
G01X296733D02*
X294529D01*
G01X300670D02*
X298466D01*
G01X304607D02*
X302403D01*
G01X308544D02*
X306340D01*
G01X312481D02*
X310277D01*
G01X316418D02*
X314214D01*
G01X320355D02*
X318151D01*
G01X324292D02*
X322088D01*
G01X328229D02*
X326025D01*
G01X332166D02*
X329962D01*
G01X336103D02*
X333899D01*
G01X340040D02*
X337836D01*
G01X343977D02*
X341773D01*
G01X347914D02*
X345710D01*
G01X269174Y221743D02*
X266969D01*
G01X273111D02*
X270906D01*
G01X277048D02*
X274843D01*
G01X280985D02*
X278780D01*
G01X284922D02*
X282717D01*
G01X288859D02*
X286655D01*
G01X292796D02*
X290592D01*
G01X296733D02*
X294529D01*
G01X300670D02*
X298466D01*
G01X304607D02*
X302403D01*
G01X308544D02*
X306340D01*
G01X312481D02*
X310277D01*
G01X316418D02*
X314214D01*
G01X320355D02*
X318151D01*
G01X324292D02*
X322088D01*
G01X328229D02*
X326025D01*
G01X332166D02*
X329962D01*
G01X336103D02*
X333899D01*
G01X340040D02*
X337836D01*
G01X343977D02*
X341773D01*
G01X347914D02*
X345710D01*
G01X345957Y221417D02*
X347667D01*
G01X342015D02*
X343725D01*
G01X338083D02*
X339793D01*
G01X334141D02*
X335851D01*
G01X330209D02*
X331919D01*
G01X326267D02*
X327977D01*
G01X322335D02*
X324045D01*
G01X318393D02*
X320103D01*
G01X314461D02*
X316171D01*
G01X310519D02*
X312229D01*
G01X306587D02*
X308297D01*
G01X302645D02*
X304355D01*
G01X298713D02*
X300423D01*
G01X294771D02*
X296481D01*
G01X290839D02*
X292549D01*
G01X286897D02*
X288607D01*
G01X282965D02*
X284675D01*
G01X279023D02*
X280733D01*
G01X275091D02*
X276801D01*
G01X271149D02*
X272859D01*
G01X267217D02*
X268927D01*
G01X345966Y221327D02*
X347658D01*
G01X342025D02*
X343716D01*
G01X338092D02*
X339784D01*
G01X334151D02*
X335842D01*
G01X330218D02*
X331910D01*
G01X326277D02*
X327968D01*
G01X322344D02*
X324036D01*
G01X318403D02*
X320094D01*
G01X314470D02*
X316162D01*
G01X310529D02*
X312220D01*
G01X306596D02*
X308288D01*
G01X302654D02*
X304346D01*
G01X298722D02*
X300414D01*
G01X294780D02*
X296472D01*
G01X290848D02*
X292540D01*
G01X286906D02*
X288598D01*
G01X282974D02*
X284666D01*
G01X279032D02*
X280724D01*
G01X275100D02*
X276792D01*
G01X271158D02*
X272850D01*
G01X267226D02*
X268918D01*
G01X268946Y221024D02*
X267198D01*
G01X272878D02*
X271130D01*
G01X276820D02*
X275072D01*
G01X280752D02*
X279004D01*
G01X284694D02*
X282946D01*
G01X288626D02*
X286878D01*
G01X292568D02*
X290820D01*
G01X296500D02*
X294752D01*
G01X300442D02*
X298694D01*
G01X304374D02*
X302626D01*
G01X308316D02*
X306568D01*
G01X312248D02*
X310500D01*
G01X316190D02*
X314442D01*
G01X320122D02*
X318374D01*
G01X324064D02*
X322316D01*
G01X327996D02*
X326248D01*
G01X331938D02*
X330190D01*
G01X335870D02*
X334122D01*
G01X339812D02*
X338064D01*
G01X343744D02*
X341996D01*
G01X347686D02*
X345938D01*
G01X345957Y220433D02*
X347667D01*
G01X342015D02*
X343725D01*
G01X338083D02*
X339793D01*
G01X334141D02*
X335851D01*
G01X330209D02*
X331919D01*
G01X326267D02*
X327977D01*
G01X322335D02*
X324045D01*
G01X318393D02*
X320103D01*
G01X314461D02*
X316171D01*
G01X310519D02*
X312229D01*
G01X306587D02*
X308297D01*
G01X302645D02*
X304355D01*
G01X298713D02*
X300423D01*
G01X294771D02*
X296481D01*
G01X290839D02*
X292549D01*
G01X286897D02*
X288607D01*
G01X282965D02*
X284675D01*
G01X279023D02*
X280733D01*
G01X275091D02*
X276801D01*
G01X271149D02*
X272859D01*
G01X267217D02*
X268927D01*
G01X268920Y220365D02*
X267224D01*
G01X272852D02*
X271156D01*
G01X276794D02*
X275098D01*
G01X280726D02*
X279030D01*
G01X284668D02*
X282972D01*
G01X288600D02*
X286904D01*
G01X292542D02*
X290846D01*
G01X296474D02*
X294778D01*
G01X300416D02*
X298720D01*
G01X304348D02*
X302652D01*
G01X308290D02*
X306594D01*
G01X312222D02*
X310526D01*
G01X316164D02*
X314468D01*
G01X320096D02*
X318400D01*
G01X324038D02*
X322342D01*
G01X327970D02*
X326274D01*
G01X331912D02*
X330216D01*
G01X335844D02*
X334148D01*
G01X339786D02*
X338090D01*
G01X343718D02*
X342022D01*
G01X347660D02*
X345964D01*
G01X268867Y220340D02*
X267277D01*
G01X272799D02*
X271209D01*
G01X276741D02*
X275151D01*
G01X280673D02*
X279083D01*
G01X284615D02*
X283025D01*
G01X288547D02*
X286957D01*
G01X292489D02*
X290899D01*
G01X296421D02*
X294831D01*
G01X300363D02*
X298773D01*
G01X304295D02*
X302705D01*
G01X308237D02*
X306647D01*
G01X312169D02*
X310579D01*
G01X316111D02*
X314521D01*
G01X320044D02*
X318453D01*
G01X323985D02*
X322395D01*
G01X327918D02*
X326327D01*
G01X331859D02*
X330269D01*
G01X335792D02*
X334201D01*
G01X339733D02*
X338143D01*
G01X343666D02*
X342075D01*
G01X347607D02*
X346017D01*
G01X345943Y220138D02*
X347681D01*
G01X342001D02*
X343740D01*
G01X338069D02*
X339807D01*
G01X334127D02*
X335866D01*
G01X330195D02*
X331933D01*
G01X326253D02*
X327992D01*
G01X322321D02*
X324059D01*
G01X318379D02*
X320118D01*
G01X314447D02*
X316185D01*
G01X310505D02*
X312244D01*
G01X306573D02*
X308311D01*
G01X302631D02*
X304370D01*
G01X298698D02*
X300437D01*
G01X294757D02*
X296496D01*
G01X290824D02*
X292563D01*
G01X286883D02*
X288622D01*
G01X282950D02*
X284689D01*
G01X279009D02*
X280748D01*
G01X275076D02*
X276815D01*
G01X271135D02*
X272874D01*
G01X267202D02*
X268941D01*
G01X345710Y219488D02*
X347914D01*
G01X341773D02*
X343977D01*
G01X337836D02*
X340040D01*
G01X333899D02*
X336103D01*
G01X329962D02*
X332166D01*
G01X326025D02*
X328229D01*
G01X322088D02*
X324292D01*
G01X318151D02*
X320355D01*
G01X314214D02*
X316418D01*
G01X310277D02*
X312481D01*
G01X306340D02*
X308544D01*
G01X302403D02*
X304607D01*
G01X298466D02*
X300670D01*
G01X294529D02*
X296733D01*
G01X290592D02*
X292796D01*
G01X286655D02*
X288859D01*
G01X282717D02*
X284922D01*
G01X278780D02*
X280985D01*
G01X274843D02*
X277048D01*
G01X270906D02*
X273111D01*
G01X266969D02*
X269174D01*
G01X346014Y219379D02*
X347610D01*
G01X342073D02*
X343668D01*
G01X338140D02*
X339736D01*
G01X334199D02*
X335794D01*
G01X330266D02*
X331862D01*
G01X326325D02*
X327920D01*
G01X322392D02*
X323988D01*
G01X318451D02*
X320046D01*
G01X314518D02*
X316114D01*
G01X310577D02*
X312172D01*
G01X306644D02*
X308239D01*
G01X302703D02*
X304298D01*
G01X298770D02*
X300365D01*
G01X294829D02*
X296424D01*
G01X290896D02*
X292491D01*
G01X286955D02*
X288550D01*
G01X283022D02*
X284617D01*
G01X279081D02*
X280676D01*
G01X275148D02*
X276743D01*
G01X271207D02*
X272802D01*
G01X267274D02*
X268869D01*
G01X272678Y218760D02*
X271340D01*
G01X280552D02*
X279214D01*
G01X288426D02*
X287088D01*
G01X296300D02*
X294962D01*
G01X304174D02*
X302836D01*
G01X312048D02*
X310710D01*
G01X319922D02*
X318584D01*
G01X327796D02*
X326458D01*
G01X335670D02*
X334332D01*
G01X343544D02*
X342206D01*
G01X272678Y217775D02*
X271340D01*
G01X280552D02*
X279214D01*
G01X288426D02*
X287088D01*
G01X296300D02*
X294962D01*
G01X304174D02*
X302836D01*
G01X312048D02*
X310710D01*
G01X319922D02*
X318584D01*
G01X327796D02*
X326458D01*
G01X335670D02*
X334332D01*
G01X343544D02*
X342206D01*
G01X342048Y217677D02*
X343702D01*
G01X334174D02*
X335828D01*
G01X326300D02*
X327954D01*
G01X318426D02*
X320080D01*
G01X310552D02*
X312206D01*
G01X302678D02*
X304332D01*
G01X294804D02*
X296458D01*
G01X286930D02*
X288584D01*
G01X279056D02*
X280710D01*
G01X271182D02*
X272836D01*
G01Y217185D02*
X271182D01*
G01X280710D02*
X279056D01*
G01X288584D02*
X286930D01*
G01X296458D02*
X294804D01*
G01X304332D02*
X302678D01*
G01X312206D02*
X310552D01*
G01X320080D02*
X318426D01*
G01X327954D02*
X326300D01*
G01X335828D02*
X334174D01*
G01X343702D02*
X342048D01*
G01X268833Y216570D02*
X267311D01*
G01X272765D02*
X271243D01*
G01X276707D02*
X275185D01*
G01X280639D02*
X279117D01*
G01X284581D02*
X283059D01*
G01X288513D02*
X286991D01*
G01X292455D02*
X290933D01*
G01X296387D02*
X294865D01*
G01X300329D02*
X298807D01*
G01X304261D02*
X302740D01*
G01X308203D02*
X306681D01*
G01X312135D02*
X310614D01*
G01X316077D02*
X314555D01*
G01X320009D02*
X318488D01*
G01X323951D02*
X322429D01*
G01X327883D02*
X326362D01*
G01X331825D02*
X330303D01*
G01X335757D02*
X334236D01*
G01X339699D02*
X338177D01*
G01X343631D02*
X342110D01*
G01X347573D02*
X346051D01*
G01X268844Y216551D02*
X267300D01*
G01X272776D02*
X271232D01*
G01X276718D02*
X275174D01*
G01X280650D02*
X279107D01*
G01X284592D02*
X283048D01*
G01X288524D02*
X286981D01*
G01X292466D02*
X290922D01*
G01X296398D02*
X294855D01*
G01X300340D02*
X298796D01*
G01X304272D02*
X302729D01*
G01X308214D02*
X306670D01*
G01X312146D02*
X310603D01*
G01X316088D02*
X314544D01*
G01X320020D02*
X318477D01*
G01X323962D02*
X322418D01*
G01X327894D02*
X326351D01*
G01X331836D02*
X330292D01*
G01X335768D02*
X334225D01*
G01X339710D02*
X338166D01*
G01X343642D02*
X342099D01*
G01X347584D02*
X346040D01*
G01X270906Y216515D02*
X270592D01*
G01X269489D02*
X269174D01*
G01X273426D02*
X273111D01*
G01X274843D02*
X274529D01*
G01X277363D02*
X277048D01*
G01X278780D02*
X278466D01*
G01X281300D02*
X280985D01*
G01X282717D02*
X282403D01*
G01X285237D02*
X284922D01*
G01X286655D02*
X286340D01*
G01X289174D02*
X288859D01*
G01X290592D02*
X290277D01*
G01X293111D02*
X292796D01*
G01X294529D02*
X294214D01*
G01X297048D02*
X296733D01*
G01X298466D02*
X298151D01*
G01X302403D02*
X302088D01*
G01X300985D02*
X300670D01*
G01X304922D02*
X304607D01*
G01X306340D02*
X306025D01*
G01X308859D02*
X308544D01*
G01X310277D02*
X309962D01*
G01X312796D02*
X312481D01*
G01X314214D02*
X313899D01*
G01X316733D02*
X316418D01*
G01X318151D02*
X317836D01*
G01X320670D02*
X320355D01*
G01X322088D02*
X321773D01*
G01X324607D02*
X324292D01*
G01X326025D02*
X325710D01*
G01X328544D02*
X328229D01*
G01X329962D02*
X329647D01*
G01X332481D02*
X332166D01*
G01X333899D02*
X333584D01*
G01X336418D02*
X336103D01*
G01X337836D02*
X337521D01*
G01X340355D02*
X340040D01*
G01X341773D02*
X341458D01*
G01X344292D02*
X343977D01*
G01X345710D02*
X345395D01*
G01X269253Y215984D02*
X266891D01*
G01X273190D02*
X270828D01*
G01X277127D02*
X274765D01*
G01X281064D02*
X278702D01*
G01X285001D02*
X282639D01*
G01X288938D02*
X286576D01*
G01X292875D02*
X290513D01*
G01X296812D02*
X294450D01*
G01X300749D02*
X298387D01*
G01X304686D02*
X302324D01*
G01X308623D02*
X306261D01*
G01X312560D02*
X310198D01*
G01X316497D02*
X314135D01*
G01X320434D02*
X318072D01*
G01X324371D02*
X322009D01*
G01X328308D02*
X325946D01*
G01X332245D02*
X329883D01*
G01X336182D02*
X333820D01*
G01X340119D02*
X337757D01*
G01X344056D02*
X341694D01*
G01X347993D02*
X345631D01*
G01X268600Y215937D02*
X267544D01*
G01X272532D02*
X271476D01*
G01X276474D02*
X275418D01*
G01X280406D02*
X279350D01*
G01X284348D02*
X283292D01*
G01X288280D02*
X287224D01*
G01X292222D02*
X291166D01*
G01X296155D02*
X295098D01*
G01X300096D02*
X299040D01*
G01X304029D02*
X302972D01*
G01X307970D02*
X306914D01*
G01X311903D02*
X310846D01*
G01X315844D02*
X314788D01*
G01X319777D02*
X318720D01*
G01X323718D02*
X322662D01*
G01X327651D02*
X326594D01*
G01X331592D02*
X330536D01*
G01X335525D02*
X334468D01*
G01X339466D02*
X338410D01*
G01X343399D02*
X342342D01*
G01X347340D02*
X346284D01*
G01X346064Y215615D02*
X347560D01*
G01X342122D02*
X343619D01*
G01X338190D02*
X339686D01*
G01X334248D02*
X335745D01*
G01X330316D02*
X331812D01*
G01X326374D02*
X327870D01*
G01X322442D02*
X323938D01*
G01X318500D02*
X319996D01*
G01X314568D02*
X316064D01*
G01X310626D02*
X312122D01*
G01X306694D02*
X308190D01*
G01X302752D02*
X304248D01*
G01X298820D02*
X300316D01*
G01X294878D02*
X296374D01*
G01X290946D02*
X292442D01*
G01X287004D02*
X288500D01*
G01X283072D02*
X284568D01*
G01X279130D02*
X280626D01*
G01X275198D02*
X276694D01*
G01X271256D02*
X272752D01*
G01X267324D02*
X268820D01*
G01X346062Y215605D02*
X347562D01*
G01X342121D02*
X343620D01*
G01X338188D02*
X339688D01*
G01X334247D02*
X335746D01*
G01X330314D02*
X331814D01*
G01X326373D02*
X327872D01*
G01X322440D02*
X323940D01*
G01X318499D02*
X319998D01*
G01X314566D02*
X316066D01*
G01X310625D02*
X312124D01*
G01X306692D02*
X308192D01*
G01X302751D02*
X304250D01*
G01X298818D02*
X300318D01*
G01X294876D02*
X296376D01*
G01X290944D02*
X292444D01*
G01X287002D02*
X288502D01*
G01X283070D02*
X284570D01*
G01X279128D02*
X280628D01*
G01X275196D02*
X276696D01*
G01X271254D02*
X272754D01*
G01X267322D02*
X268822D01*
G01X272836Y215413D02*
X271182D01*
G01X280710D02*
X279056D01*
G01X288584D02*
X286930D01*
G01X296458D02*
X294804D01*
G01X304332D02*
X302678D01*
G01X312206D02*
X310552D01*
G01X320080D02*
X318426D01*
G01X327954D02*
X326300D01*
G01X335828D02*
X334174D01*
G01X343702D02*
X342048D01*
G01X345802Y215117D02*
X347822D01*
G01X341860D02*
X343881D01*
G01X337928D02*
X339948D01*
G01X333986D02*
X336007D01*
G01X330054D02*
X332074D01*
G01X326112D02*
X328133D01*
G01X322180D02*
X324200D01*
G01X318238D02*
X320259D01*
G01X314306D02*
X316326D01*
G01X310364D02*
X312385D01*
G01X306431D02*
X308452D01*
G01X302490D02*
X304511D01*
G01X298557D02*
X300578D01*
G01X294616D02*
X296637D01*
G01X290683D02*
X292704D01*
G01X286742D02*
X288763D01*
G01X282809D02*
X284830D01*
G01X278868D02*
X280889D01*
G01X274935D02*
X276956D01*
G01X270994D02*
X273015D01*
G01X267061D02*
X269082D01*
G01X343977Y215019D02*
X344292D01*
G01X340040D02*
X340355D01*
G01X336103D02*
X336418D01*
G01X328229D02*
X328544D01*
G01X320355D02*
X320670D01*
G01X316418D02*
X316733D01*
G01X312481D02*
X312796D01*
G01X308544D02*
X308859D01*
G01X304607D02*
X304922D01*
G01X300670D02*
X300985D01*
G01X296733D02*
X297048D01*
G01X292796D02*
X293111D01*
G01X288859D02*
X289174D01*
G01X284922D02*
X285237D01*
G01X280985D02*
X281300D01*
G01X277048D02*
X277363D01*
G01X273111D02*
X273426D01*
G01X269174D02*
X269489D01*
G01X270906D02*
X270592D01*
G01X274843D02*
X274529D01*
G01X278780D02*
X278466D01*
G01X282717D02*
X282403D01*
G01X286655D02*
X286340D01*
G01X290592D02*
X290277D01*
G01X294529D02*
X294214D01*
G01X298466D02*
X298151D01*
G01X302403D02*
X302088D01*
G01X306340D02*
X306025D01*
G01X310277D02*
X309962D01*
G01X314214D02*
X313899D01*
G01X318151D02*
X317836D01*
G01X322088D02*
X321773D01*
G01X324607D02*
X324292D01*
G01X326025D02*
X325710D01*
G01X329962D02*
X329647D01*
G01X332481D02*
X332166D01*
G01X333899D02*
X333584D01*
G01X337836D02*
X337521D01*
G01X341773D02*
X341458D01*
G01X345710D02*
X345395D01*
G01X346329Y215009D02*
X347295D01*
G01X342388D02*
X343353D01*
G01X338455D02*
X339421D01*
G01X334514D02*
X335479D01*
G01X330581D02*
X331547D01*
G01X326640D02*
X327605D01*
G01X322707D02*
X323673D01*
G01X318766D02*
X319731D01*
G01X314833D02*
X315799D01*
G01X310892D02*
X311857D01*
G01X306959D02*
X307925D01*
G01X303018D02*
X303983D01*
G01X299085D02*
X300051D01*
G01X295144D02*
X296109D01*
G01X291211D02*
X292177D01*
G01X287270D02*
X288235D01*
G01X283337D02*
X284303D01*
G01X279396D02*
X280361D01*
G01X275463D02*
X276429D01*
G01X271521D02*
X272487D01*
G01X267589D02*
X268555D01*
G01X342048Y214921D02*
X343702D01*
G01X334174D02*
X335828D01*
G01X326300D02*
X327954D01*
G01X318426D02*
X320080D01*
G01X310552D02*
X312206D01*
G01X302678D02*
X304332D01*
G01X294804D02*
X296458D01*
G01X286930D02*
X288584D01*
G01X279056D02*
X280710D01*
G01X271182D02*
X272836D01*
G01X345395Y214822D02*
X348229D01*
G01X341458D02*
X344292D01*
G01X337521D02*
X340355D01*
G01X333584D02*
X336418D01*
G01X329647D02*
X332481D01*
G01X325710D02*
X328544D01*
G01X321773D02*
X324607D01*
G01X317836D02*
X320670D01*
G01X313899D02*
X316733D01*
G01X309962D02*
X312796D01*
G01X306025D02*
X308859D01*
G01X302088D02*
X304922D01*
G01X298151D02*
X300985D01*
G01X294214D02*
X297048D01*
G01X290277D02*
X293111D01*
G01X286340D02*
X289174D01*
G01X282403D02*
X285237D01*
G01X278466D02*
X281300D01*
G01X274529D02*
X277363D01*
G01X270592D02*
X273426D01*
G01X345395Y214665D02*
X345985D01*
G01X343702D02*
X344292D01*
G01X341458D02*
X342048D01*
G01X339765D02*
X340355D01*
G01X337521D02*
X338111D01*
G01X335828D02*
X336418D01*
G01X333584D02*
X334174D01*
G01X331891D02*
X332481D01*
G01X329647D02*
X330237D01*
G01X327954D02*
X328544D01*
G01X325710D02*
X326300D01*
G01X324017D02*
X324607D01*
G01X321773D02*
X322363D01*
G01X320080D02*
X320670D01*
G01X317836D02*
X318426D01*
G01X316143D02*
X316733D01*
G01X313899D02*
X314489D01*
G01X312206D02*
X312796D01*
G01X309962D02*
X310552D01*
G01X308269D02*
X308859D01*
G01X306025D02*
X306615D01*
G01X304332D02*
X304922D01*
G01X302088D02*
X302678D01*
G01X300395D02*
X300985D01*
G01X298151D02*
X298741D01*
G01X296458D02*
X297048D01*
G01X294214D02*
X294804D01*
G01X292521D02*
X293111D01*
G01X290277D02*
X290867D01*
G01X288584D02*
X289174D01*
G01X286340D02*
X286930D01*
G01X284647D02*
X285237D01*
G01X282403D02*
X282993D01*
G01X280710D02*
X281300D01*
G01X278466D02*
X279056D01*
G01X276773D02*
X277363D01*
G01X274529D02*
X275119D01*
G01X272836D02*
X273426D01*
G01X270592D02*
X271182D01*
G01X268899D02*
X269489D01*
G01X268808Y214640D02*
X267335D01*
G01X272741D02*
X271268D01*
G01X276682D02*
X275209D01*
G01X280615D02*
X279142D01*
G01X284556D02*
X283083D01*
G01X288489D02*
X287016D01*
G01X292430D02*
X290957D01*
G01X296363D02*
X294890D01*
G01X300304D02*
X298831D01*
G01X304237D02*
X302764D01*
G01X308178D02*
X306705D01*
G01X312111D02*
X310638D01*
G01X316052D02*
X314579D01*
G01X319985D02*
X318512D01*
G01X323926D02*
X322453D01*
G01X327859D02*
X326386D01*
G01X331800D02*
X330327D01*
G01X335733D02*
X334260D01*
G01X339674D02*
X338201D01*
G01X343607D02*
X342134D01*
G01X347548D02*
X346075D01*
G01X346062Y214621D02*
X347562D01*
G01X342121D02*
X343620D01*
G01X338188D02*
X339688D01*
G01X334247D02*
X335746D01*
G01X330314D02*
X331814D01*
G01X326373D02*
X327872D01*
G01X322440D02*
X323940D01*
G01X318499D02*
X319998D01*
G01X314566D02*
X316066D01*
G01X310625D02*
X312124D01*
G01X306692D02*
X308192D01*
G01X302751D02*
X304250D01*
G01X298818D02*
X300318D01*
G01X294876D02*
X296376D01*
G01X290944D02*
X292444D01*
G01X287002D02*
X288502D01*
G01X283070D02*
X284570D01*
G01X279128D02*
X280628D01*
G01X275196D02*
X276696D01*
G01X271254D02*
X272754D01*
G01X267322D02*
X268822D01*
G01X269077Y214231D02*
X267066D01*
G01X273010D02*
X270999D01*
G01X276951D02*
X274940D01*
G01X280884D02*
X278873D01*
G01X284825D02*
X282814D01*
G01X288758D02*
X286747D01*
G01X292700D02*
X290688D01*
G01X296632D02*
X294621D01*
G01X300574D02*
X298562D01*
G01X304506D02*
X302495D01*
G01X308448D02*
X306436D01*
G01X312380D02*
X310369D01*
G01X316322D02*
X314310D01*
G01X320254D02*
X318243D01*
G01X324196D02*
X322184D01*
G01X328128D02*
X326117D01*
G01X332070D02*
X330058D01*
G01X336002D02*
X333991D01*
G01X339944D02*
X337932D01*
G01X343876D02*
X341865D01*
G01X347818D02*
X345806D01*
G01X269489Y213996D02*
X268899D01*
G01X271182D02*
X270592D01*
G01X273426D02*
X272836D01*
G01X275119D02*
X274529D01*
G01X277363D02*
X276773D01*
G01X279056D02*
X278466D01*
G01X281300D02*
X280710D01*
G01X282993D02*
X282403D01*
G01X285237D02*
X284647D01*
G01X286930D02*
X286340D01*
G01X289174D02*
X288584D01*
G01X290867D02*
X290277D01*
G01X293111D02*
X292521D01*
G01X294804D02*
X294214D01*
G01X297048D02*
X296458D01*
G01X298741D02*
X298151D01*
G01X300985D02*
X300395D01*
G01X302678D02*
X302088D01*
G01X304922D02*
X304332D01*
G01X306615D02*
X306025D01*
G01X308859D02*
X308269D01*
G01X310552D02*
X309962D01*
G01X312796D02*
X312206D01*
G01X314489D02*
X313899D01*
G01X316733D02*
X316143D01*
G01X318426D02*
X317836D01*
G01X320670D02*
X320080D01*
G01X322363D02*
X321773D01*
G01X324607D02*
X324017D01*
G01X326300D02*
X325710D01*
G01X328544D02*
X327954D01*
G01X330237D02*
X329647D01*
G01X332481D02*
X331891D01*
G01X334174D02*
X333584D01*
G01X336418D02*
X335828D01*
G01X338111D02*
X337521D01*
G01X340355D02*
X339765D01*
G01X342048D02*
X341458D01*
G01X344292D02*
X343702D01*
G01X345985D02*
X345395D01*
G01X273426Y213838D02*
X270592D01*
G01X277363D02*
X274529D01*
G01X281300D02*
X278466D01*
G01X285237D02*
X282403D01*
G01X289174D02*
X286340D01*
G01X293111D02*
X290277D01*
G01X297048D02*
X294214D01*
G01X300985D02*
X298151D01*
G01X304922D02*
X302088D01*
G01X308859D02*
X306025D01*
G01X312796D02*
X309962D01*
G01X316733D02*
X313899D01*
G01X320670D02*
X317836D01*
G01X324607D02*
X321773D01*
G01X328544D02*
X325710D01*
G01X332481D02*
X329647D01*
G01X336418D02*
X333584D01*
G01X340355D02*
X337521D01*
G01X344292D02*
X341458D01*
G01X348229D02*
X345395D01*
G01X268899Y213740D02*
X267245D01*
G01X276773D02*
X275119D01*
G01X284647D02*
X282993D01*
G01X292521D02*
X290867D01*
G01X300395D02*
X298741D01*
G01X308269D02*
X306615D01*
G01X316143D02*
X314489D01*
G01X324017D02*
X322363D01*
G01X331891D02*
X330237D01*
G01X339765D02*
X338111D01*
G01X347639D02*
X345985D01*
G01Y213248D02*
X347639D01*
G01X338111D02*
X339765D01*
G01X330237D02*
X331891D01*
G01X322363D02*
X324017D01*
G01X314489D02*
X316143D01*
G01X306615D02*
X308269D01*
G01X298741D02*
X300395D01*
G01X290867D02*
X292521D01*
G01X282993D02*
X284647D01*
G01X275119D02*
X276773D01*
G01X267245D02*
X268899D01*
G01X345395Y212342D02*
X348229D01*
G01X341458D02*
X344292D01*
G01X337521D02*
X340355D01*
G01X333584D02*
X336418D01*
G01X329647D02*
X332481D01*
G01X325710D02*
X328544D01*
G01X321773D02*
X324607D01*
G01X317836D02*
X320670D01*
G01X313899D02*
X316733D01*
G01X309962D02*
X312796D01*
G01X306025D02*
X308859D01*
G01X302088D02*
X304922D01*
G01X298151D02*
X300985D01*
G01X294214D02*
X297048D01*
G01X290277D02*
X293111D01*
G01X286340D02*
X289174D01*
G01X282403D02*
X285237D01*
G01X278466D02*
X281300D01*
G01X274529D02*
X277363D01*
G01X270592D02*
X273426D01*
G01X345985Y211476D02*
X347639D01*
G01X338111D02*
X339765D01*
G01X330237D02*
X331891D01*
G01X322363D02*
X324017D01*
G01X314489D02*
X316143D01*
G01X306615D02*
X308269D01*
G01X298741D02*
X300395D01*
G01X290867D02*
X292521D01*
G01X282993D02*
X284647D01*
G01X275119D02*
X276773D01*
G01X267245D02*
X268899D01*
G01X329883Y211082D02*
X332245D01*
G01X325946D02*
X328308D01*
G01X322009D02*
X324371D01*
G01X318072D02*
X320434D01*
G01X269253D02*
X266891D01*
G01X273190D02*
X270828D01*
G01X277127D02*
X274765D01*
G01X281064D02*
X278702D01*
G01X285001D02*
X282639D01*
G01X288938D02*
X286576D01*
G01X292875D02*
X290513D01*
G01X296812D02*
X294450D01*
G01X300749D02*
X298387D01*
G01X304686D02*
X302324D01*
G01X308623D02*
X306261D01*
G01X312560D02*
X310198D01*
G01X316497D02*
X314135D01*
G01X336182D02*
X333820D01*
G01X340119D02*
X337757D01*
G01X344056D02*
X341694D01*
G01X347993D02*
X345631D01*
G01X268899Y210984D02*
X267245D01*
G01X276773D02*
X275119D01*
G01X284647D02*
X282993D01*
G01X292521D02*
X290867D01*
G01X300395D02*
X298741D01*
G01X308269D02*
X306615D01*
G01X316143D02*
X314489D01*
G01X324017D02*
X322363D01*
G01X331891D02*
X330237D01*
G01X339765D02*
X338111D01*
G01X347639D02*
X345985D01*
G01X268741Y210885D02*
X267403D01*
G01X276615D02*
X275277D01*
G01X284489D02*
X283151D01*
G01X292363D02*
X291025D01*
G01X300237D02*
X298899D01*
G01X308111D02*
X306773D01*
G01X315985D02*
X314647D01*
G01X323859D02*
X322521D01*
G01X331733D02*
X330395D01*
G01X339607D02*
X338269D01*
G01X347481D02*
X346143D01*
G01X345631Y209901D02*
X347993D01*
G01X341694D02*
X344056D01*
G01X337757D02*
X340119D01*
G01X333820D02*
X336182D01*
G01X329883D02*
X332245D01*
G01X325946D02*
X328308D01*
G01X322009D02*
X324371D01*
G01X318072D02*
X320434D01*
G01X314135D02*
X316497D01*
G01X310198D02*
X312560D01*
G01X306261D02*
X308623D01*
G01X302324D02*
X304686D01*
G01X298387D02*
X300749D01*
G01X294450D02*
X296812D01*
G01X290513D02*
X292875D01*
G01X286576D02*
X288938D01*
G01X282639D02*
X285001D01*
G01X278702D02*
X281064D01*
G01X274765D02*
X277127D01*
G01X270828D02*
X273190D01*
G01X266891D02*
X269253D01*
G01X346812Y203011D02*
X366497D01*
G01X323190D02*
X342875D01*
G01X299568D02*
X319253D01*
G01X275946D02*
X295631D01*
G01X346075Y231737D02*
X346329Y231368D01*
G01X346284Y230441D02*
X346062Y230762D01*
G01X342143Y231737D02*
X342397Y231368D01*
G01X342351Y230441D02*
X342130Y230762D01*
G01X338201Y231737D02*
X338455Y231368D01*
G01X338410Y230441D02*
X338188Y230762D01*
G01X334269Y231737D02*
X334523Y231368D01*
G01X334477Y230441D02*
X334256Y230762D01*
G01X343399Y215937D02*
X343620Y215615D01*
G01X343607Y214640D02*
X343353Y215009D01*
G01X330581Y231368D02*
X330327Y231737D01*
G01X330316Y230760D02*
X330536Y230441D01*
G01X339466Y215937D02*
X339688Y215615D01*
G01X339674Y214640D02*
X339421Y215009D01*
G01X326649Y231368D02*
X326395Y231737D01*
G01X326603Y230441D02*
X326382Y230762D01*
G01X335525Y215937D02*
X335746Y215615D01*
G01X335733Y214640D02*
X335479Y215009D01*
G01X322707Y231368D02*
X322453Y231737D01*
G01X322442Y230760D02*
X322662Y230441D01*
G01X331812Y215617D02*
X331592Y215937D01*
G01X331547Y215009D02*
X331800Y214640D01*
G01X318775Y231368D02*
X318521Y231737D01*
G01X318729Y230441D02*
X318508Y230762D01*
G01X327651Y215937D02*
X327872Y215615D01*
G01X327605Y215009D02*
X327859Y214640D01*
G01X314579Y231737D02*
X314833Y231368D01*
G01X314788Y230441D02*
X314566Y230762D01*
G01X323938Y215617D02*
X323718Y215937D01*
G01X323673Y215009D02*
X323926Y214640D01*
G01X310647Y231737D02*
X310901Y231368D01*
G01X310855Y230441D02*
X310634Y230762D01*
G01X319777Y215937D02*
X319998Y215615D01*
G01X319731Y215009D02*
X319985Y214640D01*
G01X306705Y231737D02*
X306959Y231368D01*
G01X306914Y230441D02*
X306692Y230762D01*
G01X315844Y215937D02*
X316066Y215615D01*
G01X316052Y214640D02*
X315799Y215009D01*
G01X302773Y231737D02*
X303027Y231368D01*
G01X302981Y230441D02*
X302760Y230762D01*
G01X311903Y215937D02*
X312124Y215615D01*
G01X312111Y214640D02*
X311857Y215009D01*
G01X298831Y231737D02*
X299085Y231368D01*
G01X299040Y230441D02*
X298818Y230762D01*
G01X307970Y215937D02*
X308192Y215615D01*
G01X308178Y214640D02*
X307925Y215009D01*
G01X294899Y231737D02*
X295153Y231368D01*
G01X295107Y230441D02*
X294886Y230762D01*
G01X304029Y215937D02*
X304250Y215615D01*
G01X304237Y214640D02*
X303983Y215009D01*
G01X290957Y231737D02*
X291211Y231368D01*
G01X291166Y230441D02*
X290944Y230762D01*
G01X346284Y230441D02*
X346293Y230393D01*
G01X342351Y230441D02*
X342361Y230393D01*
G01X343399Y215937D02*
X343389Y215984D01*
G01X338410Y230441D02*
X338419Y230393D01*
G01X339466Y215937D02*
X339457Y215984D01*
G01X334477Y230441D02*
X334487Y230393D01*
G01X335525Y215937D02*
X335515Y215984D01*
G01X330545Y230393D02*
X330536Y230441D01*
G01X331583Y215984D02*
X331592Y215937D01*
G01X326603Y230441D02*
X326613Y230393D01*
G01X300096Y215937D02*
X300318Y215615D01*
G01X300304Y214640D02*
X300051Y215009D01*
G01X287025Y231737D02*
X287279Y231368D01*
G01X287233Y230441D02*
X287012Y230762D01*
G01X296155Y215937D02*
X296376Y215615D01*
G01X296363Y214640D02*
X296109Y215009D01*
G01X283083Y231737D02*
X283337Y231368D01*
G01X283292Y230441D02*
X283070Y230762D01*
G01X292222Y215937D02*
X292444Y215615D01*
G01X292430Y214640D02*
X292177Y215009D01*
G01X279151Y231737D02*
X279405Y231368D01*
G01X279359Y230441D02*
X279138Y230762D01*
G01X288280Y215937D02*
X288502Y215615D01*
G01X288489Y214640D02*
X288235Y215009D01*
G01X275209Y231737D02*
X275463Y231368D01*
G01X275418Y230441D02*
X275196Y230762D01*
G01X284348Y215937D02*
X284569Y215615D01*
G01X284556Y214640D02*
X284303Y215009D01*
G01X271277Y231737D02*
X271531Y231368D01*
G01X271485Y230441D02*
X271264Y230762D01*
G01X280406Y215937D02*
X280628Y215615D01*
G01X280615Y214640D02*
X280361Y215009D01*
G01X267335Y231737D02*
X267589Y231368D01*
G01X267544Y230441D02*
X267322Y230762D01*
G01X276474Y215937D02*
X276695Y215615D01*
G01X276682Y214640D02*
X276429Y215009D01*
G01X272532Y215937D02*
X272754Y215615D01*
G01X272741Y214640D02*
X272487Y215009D01*
G01X327651Y215937D02*
X327641Y215984D01*
G01X322671Y230393D02*
X322662Y230441D01*
G01X323709Y215984D02*
X323718Y215937D01*
G01X318729Y230441D02*
X318739Y230393D01*
G01X319777Y215937D02*
X319767Y215984D01*
G01X314788Y230441D02*
X314797Y230393D01*
G01X315844Y215937D02*
X315835Y215984D01*
G01X310855Y230441D02*
X310865Y230393D01*
G01X311903Y215937D02*
X311893Y215984D01*
G01X306914Y230441D02*
X306923Y230393D01*
G01X307970Y215937D02*
X307961Y215984D01*
G01X302981Y230441D02*
X302991Y230393D01*
G01X268600Y215937D02*
X268821Y215615D01*
G01X268808Y214640D02*
X268555Y215009D01*
G01X345966Y225050D02*
X346017Y226037D01*
G01X346014Y226999D02*
X345964Y226012D01*
G01X343668Y219379D02*
X343718Y220365D01*
G01X343716Y221327D02*
X343666Y220340D01*
G01X342034Y225050D02*
X342084Y226037D01*
G01X342082Y226999D02*
X342032Y226012D01*
G01X339736Y219379D02*
X339786Y220365D01*
G01X339784Y221327D02*
X339733Y220340D01*
G01X338092Y225050D02*
X338143Y226037D01*
G01X338140Y226999D02*
X338090Y226012D01*
G01X345806Y214231D02*
X345943Y220138D01*
G01X345938Y221024D02*
X345802Y215117D01*
G01X343754Y225353D02*
X343890Y231260D01*
G01X343885Y232147D02*
X343749Y226239D01*
G01X341865Y214231D02*
X342001Y220138D01*
G01X341996Y221024D02*
X341860Y215117D01*
G01X339812Y225353D02*
X339948Y231260D01*
G01X339944Y232147D02*
X339807Y226239D01*
G01X337932Y214231D02*
X338069Y220138D01*
G01X338064Y221024D02*
X337928Y215117D01*
G01X335880Y225353D02*
X336016Y231260D01*
G01X336011Y232147D02*
X335875Y226239D01*
G01X333991Y214231D02*
X334127Y220138D01*
G01X334122Y221024D02*
X333986Y215117D01*
G01X346316Y230393D02*
X346329Y231368D01*
G01X343366Y215984D02*
X343353Y215009D01*
G01X342384Y230393D02*
X342397Y231368D01*
G01X339434Y215984D02*
X339421Y215009D01*
G01X338442Y230393D02*
X338455Y231368D01*
G01X335492Y215984D02*
X335479Y215009D01*
G01X334510Y230393D02*
X334523Y231368D01*
G01X346812Y208523D02*
Y203011D01*
G01X346418Y235492D02*
Y236476D01*
G01Y210885D02*
Y209901D01*
G01X346143Y210965D02*
Y209901D01*
G01Y236476D02*
Y235412D01*
G01X346064Y215617D02*
Y214627D01*
G01Y231750D02*
Y230760D01*
G01X345985Y231555D02*
Y236396D01*
G01Y209981D02*
Y214822D01*
G01X345788Y213840D02*
Y214824D01*
G01Y231553D02*
Y232538D01*
G01X345710Y232539D02*
Y213838D01*
G01X345631Y215984D02*
Y209901D01*
G01Y236476D02*
Y230393D01*
G01X345434Y214822D02*
Y213838D01*
G01Y232539D02*
Y231555D01*
G01X345429Y232539D02*
Y231555D01*
G01X345395Y216515D02*
Y212342D01*
G01Y234035D02*
Y229862D01*
G01X344292D02*
Y234035D01*
G01Y212342D02*
Y216515D01*
G01X344258Y232539D02*
Y231555D01*
G01X344253Y214822D02*
Y213838D01*
G01X344248Y214822D02*
Y213838D01*
G01X344056Y215984D02*
Y209901D01*
G01Y236476D02*
Y230393D01*
G01X343977Y213838D02*
Y232539D01*
G01X343903Y232538D02*
Y231553D01*
G01X343894Y214824D02*
Y213840D01*
G01X343702Y227698D02*
Y232539D01*
G01Y213838D02*
Y218680D01*
G01X343628Y230760D02*
Y231750D01*
G01X343618Y214627D02*
Y215617D01*
G01X343544Y218760D02*
Y217696D01*
G01Y228681D02*
Y227618D01*
G01X343269D02*
Y228602D01*
G01Y218760D02*
Y217775D01*
G01X342875Y208523D02*
Y203011D01*
G01X342481Y227618D02*
Y228602D01*
G01Y217775D02*
Y218760D01*
G01X342206D02*
Y217696D01*
G01Y228681D02*
Y227618D01*
G01X342132Y231750D02*
Y230760D01*
G01X342122Y215617D02*
Y214627D01*
G01X342048Y227698D02*
Y232539D01*
G01Y213838D02*
Y218680D01*
G01X341856Y231553D02*
Y232538D01*
G01X341847Y213840D02*
Y214824D01*
G01X341773Y232539D02*
Y213838D01*
G01X341694Y215984D02*
Y209901D01*
G01Y236476D02*
Y230393D01*
G01X341502Y232539D02*
Y231555D01*
G01X341497Y232539D02*
Y231555D01*
G01X341492Y214822D02*
Y213838D01*
G01X341458Y216515D02*
Y212342D01*
G01Y234035D02*
Y229862D01*
G01X340355D02*
Y234035D01*
G01Y212342D02*
Y216515D01*
G01X340321Y214822D02*
Y213838D01*
G01X340316Y214822D02*
Y213838D01*
G01Y232539D02*
Y231555D01*
G01X340119Y215984D02*
Y209901D01*
G01Y236476D02*
Y230393D01*
G01X340040Y213838D02*
Y232539D01*
G01X339962Y214824D02*
Y213840D01*
G01Y232538D02*
Y231553D01*
G01X339765Y231555D02*
Y236396D01*
G01Y209981D02*
Y214822D01*
G01X339725Y208523D02*
Y203011D01*
G01X339686Y230760D02*
Y231750D01*
G01Y214627D02*
Y215617D01*
G01X339607Y210965D02*
Y209901D01*
G01Y236476D02*
Y235412D01*
G01X339332Y210885D02*
Y209901D01*
G01Y236476D02*
Y235492D01*
G01X338544D02*
Y236476D01*
G01Y210885D02*
Y209901D01*
G01X338269Y210965D02*
Y209901D01*
G01Y236476D02*
Y235412D01*
G01X338190Y215617D02*
Y214627D01*
G01Y231750D02*
Y230760D01*
G01X338111Y231555D02*
Y236396D01*
G01Y209981D02*
Y214822D01*
G01X337914Y213840D02*
Y214824D01*
G01Y231553D02*
Y232538D01*
G01X337836Y232539D02*
Y213838D01*
G01X337757Y215984D02*
Y209901D01*
G01Y236476D02*
Y230393D01*
G01X337560Y214822D02*
Y213838D01*
G01Y232539D02*
Y231555D01*
G01X337555Y232539D02*
Y231555D01*
G01X337521Y216515D02*
Y212342D01*
G01Y234035D02*
Y229862D01*
G01X336418D02*
Y234035D01*
G01Y212342D02*
Y216515D01*
G01X336384Y232539D02*
Y231555D01*
G01X336379Y214822D02*
Y213838D01*
G01X336374Y214822D02*
Y213838D01*
G01X336182Y215984D02*
Y209901D01*
G01Y236476D02*
Y230393D01*
G01X336103Y213838D02*
Y232539D01*
G01X336029Y232538D02*
Y231553D01*
G01X336020Y214824D02*
Y213840D01*
G01X335828Y227698D02*
Y232539D01*
G01Y213838D02*
Y218680D01*
G01X335754Y230760D02*
Y231750D01*
G01X335744Y214627D02*
Y215617D01*
G01X335670Y218760D02*
Y217696D01*
G01Y228681D02*
Y227618D01*
G01X335395D02*
Y228602D01*
G01Y218760D02*
Y217775D01*
G01X334607Y227618D02*
Y228602D01*
G01Y217775D02*
Y218760D01*
G01X334332D02*
Y217696D01*
G01Y228681D02*
Y227618D01*
G01X334258Y231750D02*
Y230760D01*
G01X334248Y215617D02*
Y214627D01*
G01X334174Y227698D02*
Y232539D01*
G01Y213838D02*
Y218680D01*
G01X333982Y231553D02*
Y232538D01*
G01X333973Y213840D02*
Y214824D01*
G01X333899Y232539D02*
Y213838D01*
G01X333820Y215984D02*
Y209901D01*
G01Y236476D02*
Y230393D01*
G01X333628Y232539D02*
Y231555D01*
G01X333623Y232539D02*
Y231555D01*
G01X333618Y214822D02*
Y213838D01*
G01X333584Y216515D02*
Y212342D01*
G01Y234035D02*
Y229862D01*
G01X332481D02*
Y234035D01*
G01Y212342D02*
Y216515D01*
G01X332447Y214822D02*
Y213838D01*
G01X332442Y214822D02*
Y213838D01*
G01Y232539D02*
Y231555D01*
G01X332245Y215984D02*
Y209901D01*
G01Y236476D02*
Y230393D01*
G01X332166Y213838D02*
Y232539D01*
G01X332088Y214824D02*
Y213840D01*
G01Y232538D02*
Y231553D01*
G01X331891Y231555D02*
Y236396D01*
G01Y209981D02*
Y214822D01*
G01X331812Y230760D02*
Y231750D01*
G01Y214627D02*
Y215617D01*
G01X331733Y210965D02*
Y209901D01*
G01Y236476D02*
Y235412D01*
G01X331458Y209901D02*
Y210885D01*
G01Y236476D02*
Y235492D01*
G01X330670Y210885D02*
Y209901D01*
G01Y236476D02*
Y235492D01*
G01X346329Y215009D02*
X346316Y215984D01*
G01X343362Y231368D02*
X343375Y230393D01*
G01X342388Y215009D02*
X342375Y215984D01*
G01X339421Y231368D02*
X339434Y230393D01*
G01X338455Y215009D02*
X338442Y215984D01*
G01X335488Y231368D02*
X335501Y230393D01*
G01X334514Y215009D02*
X334500Y215984D01*
G01X331547Y231368D02*
X331560Y230393D01*
G01X330581Y215009D02*
X330568Y215984D01*
G01X345943Y226239D02*
X345806Y232147D01*
G01X345802Y231260D02*
X345938Y225353D01*
G01X343881Y215117D02*
X343744Y221024D01*
G01X343740Y220138D02*
X343876Y214231D01*
G01X342010Y226239D02*
X341874Y232147D01*
G01X341869Y231260D02*
X342005Y225353D01*
G01X339948Y215117D02*
X339812Y221024D01*
G01X339807Y220138D02*
X339944Y214231D01*
G01X338069Y226239D02*
X337932Y232147D01*
G01X337928Y231260D02*
X338064Y225353D01*
G01X336007Y215117D02*
X335870Y221024D01*
G01X335866Y220138D02*
X336002Y214231D01*
G01X334136Y226239D02*
X334000Y232147D01*
G01X333995Y231260D02*
X334131Y225353D01*
G01X332074Y215117D02*
X331938Y221024D01*
G01X331933Y220138D02*
X332070Y214231D01*
G01X330195Y226239D02*
X330058Y232147D01*
G01X330054Y231260D02*
X330190Y225353D01*
G01X328133Y215117D02*
X327996Y221024D01*
G01X327992Y220138D02*
X328128Y214231D01*
G01X346017Y220340D02*
X345966Y221327D01*
G01X345964Y220365D02*
X346014Y219379D01*
G01X343728Y226012D02*
X343677Y226999D01*
G01X343675Y226037D02*
X343725Y225050D01*
G01X342075Y220340D02*
X342025Y221327D01*
G01X342022Y220365D02*
X342073Y219379D01*
G01X339786Y226012D02*
X339736Y226999D01*
G01X339733Y226037D02*
X339784Y225050D01*
G01X338143Y220340D02*
X338092Y221327D01*
G01X338090Y220365D02*
X338140Y219379D01*
G01X335854Y226012D02*
X335803Y226999D01*
G01X335801Y226037D02*
X335851Y225050D01*
G01X334201Y220340D02*
X334151Y221327D01*
G01X334148Y220365D02*
X334199Y219379D01*
G01X331912Y226012D02*
X331862Y226999D01*
G01X331859Y226037D02*
X331910Y225050D01*
G01X330269Y220340D02*
X330218Y221327D01*
G01X330216Y220365D02*
X330266Y219379D01*
G01X327980Y226012D02*
X327929Y226999D01*
G01X327927Y226037D02*
X327977Y225050D01*
G01X326327Y220340D02*
X326277Y221327D01*
G01X326274Y220365D02*
X326325Y219379D01*
G01X324038Y226012D02*
X323988Y226999D01*
G01X323985Y226037D02*
X324036Y225050D01*
G01X304029Y215937D02*
X304019Y215984D01*
G01X299040Y230441D02*
X299049Y230393D01*
G01X300096Y215937D02*
X300087Y215984D01*
G01X295107Y230441D02*
X295117Y230393D01*
G01X296155Y215937D02*
X296145Y215984D01*
G01X291166Y230441D02*
X291175Y230393D01*
G01X292222Y215937D02*
X292213Y215984D01*
G01X287233Y230441D02*
X287243Y230393D01*
G01X288280Y215937D02*
X288271Y215984D01*
G01X283292Y230441D02*
X283301Y230393D01*
G01X284348Y215937D02*
X284339Y215984D01*
G01X279359Y230441D02*
X279369Y230393D01*
G01X280406Y215937D02*
X280397Y215984D01*
G01X346293D02*
X346284Y215937D01*
G01X342352Y215984D02*
X342342Y215937D01*
G01X343398Y230393D02*
X343408Y230441D01*
G01X338419Y215984D02*
X338410Y215937D01*
G01X339457Y230393D02*
X339466Y230441D01*
G01X334478Y215984D02*
X334468Y215937D01*
G01X335524Y230393D02*
X335534Y230441D01*
G01X335794Y219379D02*
X335844Y220365D01*
G01X335842Y221327D02*
X335792Y220340D01*
G01X334160Y225050D02*
X334210Y226037D01*
G01X334208Y226999D02*
X334158Y226012D01*
G01X331862Y219379D02*
X331912Y220365D01*
G01X331910Y221327D02*
X331859Y220340D01*
G01X330218Y225050D02*
X330269Y226037D01*
G01X330266Y226999D02*
X330216Y226012D01*
G01X327920Y219379D02*
X327970Y220365D01*
G01X327968Y221327D02*
X327918Y220340D01*
G01X326286Y225050D02*
X326336Y226037D01*
G01X326334Y226999D02*
X326284Y226012D01*
G01X323988Y219379D02*
X324038Y220365D01*
G01X324036Y221327D02*
X323985Y220340D01*
G01X322344Y225050D02*
X322395Y226037D01*
G01X322392Y226999D02*
X322342Y226012D01*
G01X320046Y219379D02*
X320096Y220365D01*
G01X320094Y221327D02*
X320044Y220340D01*
G01X318412Y225050D02*
X318462Y226037D01*
G01X318460Y226999D02*
X318410Y226012D01*
G01X316114Y219379D02*
X316164Y220365D01*
G01X316162Y221327D02*
X316111Y220340D01*
G01X314470Y225050D02*
X314521Y226037D01*
G01X314518Y226999D02*
X314468Y226012D01*
G01X331938Y225353D02*
X332074Y231260D01*
G01X332070Y232147D02*
X331933Y226239D01*
G01X330058Y214231D02*
X330195Y220138D01*
G01X330190Y221024D02*
X330054Y215117D01*
G01X328006Y225353D02*
X328142Y231260D01*
G01X328137Y232147D02*
X328001Y226239D01*
G01X326117Y214231D02*
X326253Y220138D01*
G01X326248Y221024D02*
X326112Y215117D01*
G01X324064Y225353D02*
X324200Y231260D01*
G01X324196Y232147D02*
X324059Y226239D01*
G01X322184Y214231D02*
X322321Y220138D01*
G01X322316Y221024D02*
X322180Y215117D01*
G01X320132Y225353D02*
X320268Y231260D01*
G01X320263Y232147D02*
X320127Y226239D01*
G01X318243Y214231D02*
X318379Y220138D01*
G01X318374Y221024D02*
X318238Y215117D01*
G01X316190Y225353D02*
X316326Y231260D01*
G01X316322Y232147D02*
X316185Y226239D01*
G01X314310Y214231D02*
X314447Y220138D01*
G01X314442Y221024D02*
X314306Y215117D01*
G01X312258Y225353D02*
X312394Y231260D01*
G01X312389Y232147D02*
X312253Y226239D01*
G01X310369Y214231D02*
X310505Y220138D01*
G01X310500Y221024D02*
X310364Y215117D01*
G01X331560Y215984D02*
X331547Y215009D01*
G01X330568Y230393D02*
X330581Y231368D01*
G01X327618Y215984D02*
X327605Y215009D01*
G01X326636Y230393D02*
X326649Y231368D01*
G01X323686Y215984D02*
X323673Y215009D01*
G01X322694Y230393D02*
X322707Y231368D01*
G01X319744Y215984D02*
X319731Y215009D01*
G01X318762Y230393D02*
X318775Y231368D01*
G01X315812Y215984D02*
X315799Y215009D01*
G01X314820Y230393D02*
X314833Y231368D01*
G01X311870Y215984D02*
X311857Y215009D01*
G01X310888Y230393D02*
X310901Y231368D01*
G01X307938Y215984D02*
X307925Y215009D01*
G01X330395Y210965D02*
Y209901D01*
G01Y236476D02*
Y235412D01*
G01X330316Y215617D02*
Y214627D01*
G01Y231750D02*
Y230760D01*
G01X330237Y231555D02*
Y236396D01*
G01Y209981D02*
Y214822D01*
G01X330040Y213840D02*
Y214824D01*
G01Y231553D02*
Y232538D01*
G01X329962Y232539D02*
Y213838D01*
G01X329883Y215984D02*
Y209901D01*
G01Y236476D02*
Y230393D01*
G01X329686Y214822D02*
Y213838D01*
G01Y232539D02*
Y231555D01*
G01X329681Y232539D02*
Y231555D01*
G01X329647Y216515D02*
Y212342D01*
G01Y234035D02*
Y229862D01*
G01X328544D02*
Y234035D01*
G01Y212342D02*
Y216515D01*
G01X328510Y232539D02*
Y231555D01*
G01X328505Y214822D02*
Y213838D01*
G01X328500Y214822D02*
Y213838D01*
G01X328308Y215984D02*
Y209901D01*
G01Y236476D02*
Y230393D01*
G01X328229Y213838D02*
Y232539D01*
G01X328155Y232538D02*
Y231553D01*
G01X328146Y214824D02*
Y213840D01*
G01X327954Y227698D02*
Y232539D01*
G01Y213838D02*
Y218680D01*
G01X327880Y230760D02*
Y231750D01*
G01X327870Y214627D02*
Y215617D01*
G01X327796Y218760D02*
Y217696D01*
G01Y228681D02*
Y227618D01*
G01X327521D02*
Y228602D01*
G01Y218760D02*
Y217775D01*
G01X326733Y227618D02*
Y228602D01*
G01Y218760D02*
Y217775D01*
G01X326458Y218760D02*
Y217696D01*
G01Y228681D02*
Y227618D01*
G01X326384Y231750D02*
Y230760D01*
G01X326374Y215617D02*
Y214627D01*
G01X326340Y208523D02*
Y203011D01*
G01X326300Y227698D02*
Y232539D01*
G01Y213838D02*
Y218680D01*
G01X326108Y231553D02*
Y232538D01*
G01X326099Y213840D02*
Y214824D01*
G01X326025Y232539D02*
Y213838D01*
G01X325946Y215984D02*
Y209901D01*
G01Y236476D02*
Y230393D01*
G01X325754Y232539D02*
Y231555D01*
G01X325749Y232539D02*
Y231555D01*
G01X325744Y214822D02*
Y213838D01*
G01X325710Y216515D02*
Y212342D01*
G01Y234035D02*
Y229862D01*
G01X324607D02*
Y234035D01*
G01Y212342D02*
Y216515D01*
G01X324573Y214822D02*
Y213838D01*
G01X324568Y214822D02*
Y213838D01*
G01Y232539D02*
Y231555D01*
G01X324371Y215984D02*
Y209901D01*
G01Y236476D02*
Y230393D01*
G01X324292Y213838D02*
Y232539D01*
G01X324214Y214824D02*
Y213840D01*
G01Y232538D02*
Y231553D01*
G01X324017Y231555D02*
Y236396D01*
G01Y209981D02*
Y214822D01*
G01X323938Y230760D02*
Y231750D01*
G01Y214627D02*
Y215617D01*
G01X323859Y210965D02*
Y209901D01*
G01Y236476D02*
Y235412D01*
G01X323584Y209901D02*
Y210885D01*
G01Y236476D02*
Y235492D01*
G01X323190Y208523D02*
Y203011D01*
G01X322796Y210885D02*
Y209901D01*
G01Y236476D02*
Y235492D01*
G01X322521Y210965D02*
Y209901D01*
G01Y236476D02*
Y235412D01*
G01X322442Y215617D02*
Y214627D01*
G01Y231750D02*
Y230760D01*
G01X322363Y231555D02*
Y236396D01*
G01Y209981D02*
Y214822D01*
G01X322166Y213840D02*
Y214824D01*
G01Y231553D02*
Y232538D01*
G01X322088Y232539D02*
Y213838D01*
G01X322009Y215984D02*
Y209901D01*
G01Y236476D02*
Y230393D01*
G01X321812Y214822D02*
Y213838D01*
G01Y232539D02*
Y231555D01*
G01X321807Y232539D02*
Y231555D01*
G01X321773Y216515D02*
Y212342D01*
G01Y234035D02*
Y229862D01*
G01X320670D02*
Y234035D01*
G01Y212342D02*
Y216515D01*
G01X320636Y232539D02*
Y231555D01*
G01X320631Y214822D02*
Y213838D01*
G01X320626Y214822D02*
Y213838D01*
G01X320434Y215984D02*
Y209901D01*
G01Y236476D02*
Y230393D01*
G01X320355Y213838D02*
Y232539D01*
G01X320281Y232538D02*
Y231553D01*
G01X320272Y214824D02*
Y213840D01*
G01X320080Y227698D02*
Y232539D01*
G01Y213838D02*
Y218680D01*
G01X320006Y230760D02*
Y231750D01*
G01X319996Y214627D02*
Y215617D01*
G01X319922Y218760D02*
Y217696D01*
G01Y228681D02*
Y227618D01*
G01X319647D02*
Y228602D01*
G01Y218760D02*
Y217775D01*
G01X319253Y208523D02*
Y203011D01*
G01X318859Y227618D02*
Y228602D01*
G01Y218760D02*
Y217775D01*
G01X318584Y218760D02*
Y217696D01*
G01Y228681D02*
Y227618D01*
G01X318510Y231750D02*
Y230760D01*
G01X318500Y215617D02*
Y214627D01*
G01X318426Y227698D02*
Y232539D01*
G01Y213838D02*
Y218680D01*
G01X318234Y231553D02*
Y232538D01*
G01X318225Y213840D02*
Y214824D01*
G01X318151Y232539D02*
Y213838D01*
G01X318072Y215984D02*
Y209901D01*
G01Y236476D02*
Y230393D01*
G01X317880Y232539D02*
Y231555D01*
G01X317875Y232539D02*
Y231555D01*
G01X317870Y214822D02*
Y213838D01*
G01X317836Y216515D02*
Y212342D01*
G01Y234035D02*
Y229862D01*
G01X316733D02*
Y234035D01*
G01Y212342D02*
Y216515D01*
G01X316699Y214822D02*
Y213838D01*
G01X316694Y214822D02*
Y213838D01*
G01Y232539D02*
Y231555D01*
G01X316497Y215984D02*
Y209901D01*
G01Y236476D02*
Y230393D01*
G01X316418Y213838D02*
Y232539D01*
G01X316340Y214824D02*
Y213840D01*
G01Y232538D02*
Y231553D01*
G01X316143Y231555D02*
Y236396D01*
G01Y209981D02*
Y214822D01*
G01X316103Y208523D02*
Y203011D01*
G01X316064Y230760D02*
Y231750D01*
G01Y214627D02*
Y215617D01*
G01X315985Y210965D02*
Y209901D01*
G01Y236476D02*
Y235412D01*
G01X315710Y210885D02*
Y209901D01*
G01Y236476D02*
Y235492D01*
G01X314922D02*
Y236476D01*
G01Y210885D02*
Y209901D01*
G01X314647Y210965D02*
Y209901D01*
G01Y236476D02*
Y235412D01*
G01X314568Y215617D02*
Y214627D01*
G01Y231750D02*
Y230760D01*
G01X314489Y231555D02*
Y236396D01*
G01Y209981D02*
Y214822D01*
G01X314292Y213840D02*
Y214824D01*
G01Y231553D02*
Y232538D01*
G01X314214Y232539D02*
Y213838D01*
G01X314135Y215984D02*
Y209901D01*
G01Y236476D02*
Y230393D01*
G01X313938Y214822D02*
Y213838D01*
G01Y232539D02*
Y231555D01*
G01X313933Y232539D02*
Y231555D01*
G01X313899Y216515D02*
Y212342D01*
G01Y234035D02*
Y229862D01*
G01X312796D02*
Y234035D01*
G01Y212342D02*
Y216515D01*
G01X312762Y232539D02*
Y231555D01*
G01X312757Y214822D02*
Y213838D01*
G01X312752Y214822D02*
Y213838D01*
G01X312560Y215984D02*
Y209901D01*
G01Y236476D02*
Y230393D01*
G01X312481Y213838D02*
Y232539D01*
G01X312407Y232538D02*
Y231553D01*
G01X312398Y214824D02*
Y213840D01*
G01X312206Y227698D02*
Y232539D01*
G01Y213838D02*
Y218680D01*
G01X312132Y230760D02*
Y231750D01*
G01X312122Y214627D02*
Y215617D01*
G01X312048Y218760D02*
Y217696D01*
G01Y228681D02*
Y227618D01*
G01X311773Y218760D02*
Y217775D01*
G01Y228602D02*
Y227618D01*
G01X310985Y218760D02*
Y217775D01*
G01Y228602D02*
Y227618D01*
G01X310710Y218760D02*
Y217696D01*
G01Y228681D02*
Y227618D01*
G01X310636Y231750D02*
Y230760D01*
G01X310626Y215617D02*
Y214627D01*
G01X310552Y227698D02*
Y232539D01*
G01Y213838D02*
Y218680D01*
G01X310360Y231553D02*
Y232538D01*
G01X310351Y213840D02*
Y214824D01*
G01X310277Y232539D02*
Y213838D01*
G01X310198Y215984D02*
Y209901D01*
G01Y236476D02*
Y230393D01*
G01X310006Y232539D02*
Y231555D01*
G01X310001Y232539D02*
Y231555D01*
G01X309996Y214822D02*
Y213838D01*
G01X309962Y216515D02*
Y212342D01*
G01Y234035D02*
Y229862D01*
G01X308859D02*
Y234035D01*
G01Y212342D02*
Y216515D01*
G01X308825Y214822D02*
Y213838D01*
G01X308820Y214822D02*
Y213838D01*
G01Y232539D02*
Y231555D01*
G01X308623Y215984D02*
Y209901D01*
G01Y236476D02*
Y230393D01*
G01X308544Y213838D02*
Y232539D01*
G01X308466Y214824D02*
Y213840D01*
G01Y232538D02*
Y231553D01*
G01X308269Y231555D02*
Y236396D01*
G01Y209981D02*
Y214822D01*
G01X308190Y230760D02*
Y231750D01*
G01Y214627D02*
Y215617D01*
G01X308111Y210965D02*
Y209901D01*
G01Y236476D02*
Y235412D01*
G01X307836Y210885D02*
Y209901D01*
G01Y236476D02*
Y235492D01*
G01X307048D02*
Y236476D01*
G01Y210885D02*
Y209901D01*
G01X306773Y210965D02*
Y209901D01*
G01Y236476D02*
Y235412D01*
G01X306694Y215617D02*
Y214627D01*
G01Y231750D02*
Y230760D01*
G01X306615Y231555D02*
Y236396D01*
G01Y209981D02*
Y214822D01*
G01X306418Y231553D02*
Y232538D01*
G01Y213840D02*
Y214824D01*
G01X306340Y232539D02*
Y213838D01*
G01X306261Y215984D02*
Y209901D01*
G01Y236476D02*
Y230393D01*
G01X327614Y231368D02*
X327627Y230393D01*
G01X326640Y215009D02*
X326626Y215984D01*
G01X323673Y231368D02*
X323686Y230393D01*
G01X322707Y215009D02*
X322694Y215984D01*
G01X319740Y231368D02*
X319753Y230393D01*
G01X318766Y215009D02*
X318752Y215984D01*
G01X315799Y231368D02*
X315812Y230393D01*
G01X314833Y215009D02*
X314820Y215984D01*
G01X311866Y231368D02*
X311879Y230393D01*
G01X310892Y215009D02*
X310878Y215984D01*
G01X307925Y231368D02*
X307938Y230393D01*
G01X306959Y215009D02*
X306946Y215984D01*
G01X326262Y226239D02*
X326126Y232147D01*
G01X326121Y231260D02*
X326257Y225353D01*
G01X324200Y215117D02*
X324064Y221024D01*
G01X324059Y220138D02*
X324196Y214231D01*
G01X322321Y226239D02*
X322184Y232147D01*
G01X322180Y231260D02*
X322316Y225353D01*
G01X320259Y215117D02*
X320122Y221024D01*
G01X320118Y220138D02*
X320254Y214231D01*
G01X318388Y226239D02*
X318252Y232147D01*
G01X318247Y231260D02*
X318383Y225353D01*
G01X316326Y215117D02*
X316190Y221024D01*
G01X316185Y220138D02*
X316322Y214231D01*
G01X314447Y226239D02*
X314310Y232147D01*
G01X314306Y231260D02*
X314442Y225353D01*
G01X312385Y215117D02*
X312248Y221024D01*
G01X312244Y220138D02*
X312380Y214231D01*
G01X310514Y226239D02*
X310378Y232147D01*
G01X310373Y231260D02*
X310509Y225353D01*
G01X308452Y215117D02*
X308316Y221024D01*
G01X308311Y220138D02*
X308448Y214231D01*
G01X306573Y226239D02*
X306436Y232147D01*
G01X306431Y231260D02*
X306568Y225353D01*
G01X304511Y215117D02*
X304374Y221024D01*
G01X304370Y220138D02*
X304506Y214231D01*
G01X322395Y220340D02*
X322344Y221327D01*
G01X322342Y220365D02*
X322392Y219379D01*
G01X320106Y226012D02*
X320055Y226999D01*
G01X320053Y226037D02*
X320103Y225050D01*
G01X318453Y220340D02*
X318403Y221327D01*
G01X318400Y220365D02*
X318451Y219379D01*
G01X316164Y226012D02*
X316114Y226999D01*
G01X316111Y226037D02*
X316162Y225050D01*
G01X314521Y220340D02*
X314470Y221327D01*
G01X314468Y220365D02*
X314518Y219379D01*
G01X312232Y226012D02*
X312181Y226999D01*
G01X312179Y226037D02*
X312229Y225050D01*
G01X310579Y220340D02*
X310529Y221327D01*
G01X310526Y220365D02*
X310577Y219379D01*
G01X308290Y226012D02*
X308239Y226999D01*
G01X308237Y226037D02*
X308288Y225050D01*
G01X306647Y220340D02*
X306596Y221327D01*
G01X306594Y220365D02*
X306644Y219379D01*
G01X304358Y226012D02*
X304307Y226999D01*
G01X304305Y226037D02*
X304355Y225050D01*
G01X302705Y220340D02*
X302654Y221327D01*
G01X302652Y220365D02*
X302703Y219379D01*
G01X300416Y226012D02*
X300365Y226999D01*
G01X300363Y226037D02*
X300414Y225050D01*
G01X275418Y230441D02*
X275427Y230393D01*
G01X276474Y215937D02*
X276465Y215984D01*
G01X271485Y230441D02*
X271495Y230393D01*
G01X272532Y215937D02*
X272523Y215984D01*
G01X267544Y230441D02*
X267553Y230393D01*
G01X268600Y215937D02*
X268591Y215984D01*
G01X330536Y215937D02*
X330545Y215984D01*
G01X331592Y230441D02*
X331583Y230393D01*
G01X326604Y215984D02*
X326594Y215937D01*
G01X327650Y230393D02*
X327660Y230441D01*
G01X322662Y215937D02*
X322671Y215984D01*
G01X323718Y230441D02*
X323709Y230393D01*
G01X318730Y215984D02*
X318720Y215937D01*
G01X319776Y230393D02*
X319786Y230441D01*
G01X314797Y215984D02*
X314788Y215937D01*
G01X315835Y230393D02*
X315844Y230441D01*
G01X310856Y215984D02*
X310846Y215937D01*
G01X311902Y230393D02*
X311912Y230441D01*
G01X312172Y219379D02*
X312222Y220365D01*
G01X312220Y221327D02*
X312169Y220340D01*
G01X310538Y225050D02*
X310588Y226037D01*
G01X310586Y226999D02*
X310536Y226012D01*
G01X308239Y219379D02*
X308290Y220365D01*
G01X308288Y221327D02*
X308237Y220340D01*
G01X306596Y225050D02*
X306647Y226037D01*
G01X306644Y226999D02*
X306594Y226012D01*
G01X304298Y219379D02*
X304348Y220365D01*
G01X304346Y221327D02*
X304295Y220340D01*
G01X302664Y225050D02*
X302714Y226037D01*
G01X302712Y226999D02*
X302661Y226012D01*
G01X300365Y219379D02*
X300416Y220365D01*
G01X300414Y221327D02*
X300363Y220340D01*
G01X298722Y225050D02*
X298773Y226037D01*
G01X298770Y226999D02*
X298720Y226012D01*
G01X296424Y219379D02*
X296474Y220365D01*
G01X296472Y221327D02*
X296421Y220340D01*
G01X294790Y225050D02*
X294840Y226037D01*
G01X294838Y226999D02*
X294787Y226012D01*
G01X292491Y219379D02*
X292542Y220365D01*
G01X292540Y221327D02*
X292489Y220340D01*
G01X290848Y225050D02*
X290899Y226037D01*
G01X290896Y226999D02*
X290846Y226012D01*
G01X288550Y219379D02*
X288600Y220365D01*
G01X308316Y225353D02*
X308452Y231260D01*
G01X308448Y232147D02*
X308311Y226239D01*
G01X306436Y214231D02*
X306573Y220138D01*
G01X306568Y221024D02*
X306431Y215117D01*
G01X304384Y225353D02*
X304520Y231260D01*
G01X304515Y232147D02*
X304379Y226239D01*
G01X302495Y214231D02*
X302631Y220138D01*
G01X302626Y221024D02*
X302490Y215117D01*
G01X300442Y225353D02*
X300578Y231260D01*
G01X300574Y232147D02*
X300437Y226239D01*
G01X298562Y214231D02*
X298698Y220138D01*
G01X298694Y221024D02*
X298557Y215117D01*
G01X296510Y225353D02*
X296646Y231260D01*
G01X296641Y232147D02*
X296505Y226239D01*
G01X294621Y214231D02*
X294757Y220138D01*
G01X294752Y221024D02*
X294616Y215117D01*
G01X292568Y225353D02*
X292704Y231260D01*
G01X292700Y232147D02*
X292563Y226239D01*
G01X290688Y214231D02*
X290824Y220138D01*
G01X290820Y221024D02*
X290683Y215117D01*
G01X288636Y225353D02*
X288772Y231260D01*
G01X288767Y232147D02*
X288631Y226239D01*
G01X286747Y214231D02*
X286883Y220138D01*
G01X286878Y221024D02*
X286742Y215117D01*
G01X306946Y230393D02*
X306959Y231368D01*
G01X303996Y215984D02*
X303983Y215009D01*
G01X303014Y230393D02*
X303027Y231368D01*
G01X300064Y215984D02*
X300051Y215009D01*
G01X299072Y230393D02*
X299085Y231368D01*
G01X296122Y215984D02*
X296109Y215009D01*
G01X295140Y230393D02*
X295153Y231368D01*
G01X292190Y215984D02*
X292177Y215009D01*
G01X291198Y230393D02*
X291211Y231368D01*
G01X288248Y215984D02*
X288235Y215009D01*
G01X287266Y230393D02*
X287279Y231368D01*
G01X284316Y215984D02*
X284303Y215009D01*
G01X306064Y214822D02*
Y213838D01*
G01Y232539D02*
Y231555D01*
G01X306059Y232539D02*
Y231555D01*
G01X306025Y216515D02*
Y212342D01*
G01Y234035D02*
Y229862D01*
G01X304922D02*
Y234035D01*
G01Y212342D02*
Y216515D01*
G01X304888Y232539D02*
Y231555D01*
G01X304883Y214822D02*
Y213838D01*
G01X304878Y214822D02*
Y213838D01*
G01X304686Y215984D02*
Y209901D01*
G01Y236476D02*
Y230393D01*
G01X304607Y213838D02*
Y232539D01*
G01X304533Y232538D02*
Y231553D01*
G01X304524Y214824D02*
Y213840D01*
G01X304332Y227698D02*
Y232539D01*
G01Y213838D02*
Y218680D01*
G01X304258Y230760D02*
Y231750D01*
G01X304248Y214627D02*
Y215617D01*
G01X304174Y218760D02*
Y217696D01*
G01Y228681D02*
Y227618D01*
G01X303899D02*
Y228602D01*
G01Y218760D02*
Y217775D01*
G01X303111Y227618D02*
Y228602D01*
G01Y217775D02*
Y218760D01*
G01X302836D02*
Y217696D01*
G01Y228681D02*
Y227618D01*
G01X302762Y231750D02*
Y230760D01*
G01X302752Y215617D02*
Y214627D01*
G01X302717Y208523D02*
Y203011D01*
G01X302678Y227698D02*
Y232539D01*
G01Y213838D02*
Y218680D01*
G01X302486Y231553D02*
Y232538D01*
G01X302477Y213840D02*
Y214824D01*
G01X302403Y232539D02*
Y213838D01*
G01X302324Y215984D02*
Y209901D01*
G01Y236476D02*
Y230393D01*
G01X302132Y232539D02*
Y231555D01*
G01X302127Y232539D02*
Y231555D01*
G01X302122Y214822D02*
Y213838D01*
G01X302088Y216515D02*
Y212342D01*
G01Y234035D02*
Y229862D01*
G01X300985D02*
Y234035D01*
G01Y212342D02*
Y216515D01*
G01X300951Y214822D02*
Y213838D01*
G01X300946Y214822D02*
Y213838D01*
G01Y232539D02*
Y231555D01*
G01X300749Y215984D02*
Y209901D01*
G01Y236476D02*
Y230393D01*
G01X300670Y213838D02*
Y232539D01*
G01X300592Y214824D02*
Y213840D01*
G01Y232538D02*
Y231553D01*
G01X300395Y231555D02*
Y236396D01*
G01Y209981D02*
Y214822D01*
G01X300316Y230760D02*
Y231750D01*
G01Y214627D02*
Y215617D01*
G01X300237Y210965D02*
Y209901D01*
G01Y236476D02*
Y235412D01*
G01X299962Y210885D02*
Y209901D01*
G01Y236476D02*
Y235492D01*
G01X299568Y208523D02*
Y203011D01*
G01X299174Y235492D02*
Y236476D01*
G01Y210885D02*
Y209901D01*
G01X298899Y210965D02*
Y209901D01*
G01Y236476D02*
Y235412D01*
G01X298820Y215617D02*
Y214627D01*
G01Y231750D02*
Y230760D01*
G01X298741Y231555D02*
Y236396D01*
G01Y209981D02*
Y214822D01*
G01X298544Y213840D02*
Y214824D01*
G01Y231553D02*
Y232538D01*
G01X298466Y232539D02*
Y213838D01*
G01X298387Y215984D02*
Y209901D01*
G01Y236476D02*
Y230393D01*
G01X298190Y214822D02*
Y213838D01*
G01Y232539D02*
Y231555D01*
G01X298185Y232539D02*
Y231555D01*
G01X298151Y216515D02*
Y212342D01*
G01Y234035D02*
Y229862D01*
G01X297048D02*
Y234035D01*
G01Y212342D02*
Y216515D01*
G01X297014Y232539D02*
Y231555D01*
G01X297009Y214822D02*
Y213838D01*
G01X297004Y214822D02*
Y213838D01*
G01X296812Y215984D02*
Y209901D01*
G01Y236476D02*
Y230393D01*
G01X296733Y213838D02*
Y232539D01*
G01X296659Y232538D02*
Y231553D01*
G01X296650Y214824D02*
Y213840D01*
G01X296458Y227698D02*
Y232539D01*
G01Y213838D02*
Y218680D01*
G01X296384Y230760D02*
Y231750D01*
G01X296374Y214627D02*
Y215617D01*
G01X296300Y218760D02*
Y217696D01*
G01Y228681D02*
Y227618D01*
G01X296025D02*
Y228602D01*
G01Y218760D02*
Y217775D01*
G01X295631Y208523D02*
Y203011D01*
G01X295237Y227618D02*
Y228602D01*
G01Y217775D02*
Y218760D01*
G01X294962D02*
Y217696D01*
G01Y228681D02*
Y227618D01*
G01X294888Y231750D02*
Y230760D01*
G01X294878Y215617D02*
Y214627D01*
G01X294804Y227698D02*
Y232539D01*
G01Y213838D02*
Y218680D01*
G01X294612Y231553D02*
Y232538D01*
G01X294603Y213840D02*
Y214824D01*
G01X294529Y232539D02*
Y213838D01*
G01X294450Y215984D02*
Y209901D01*
G01Y236476D02*
Y230393D01*
G01X294258Y232539D02*
Y231555D01*
G01X294253Y232539D02*
Y231555D01*
G01X294248Y214822D02*
Y213838D01*
G01X294214Y216515D02*
Y212342D01*
G01Y234035D02*
Y229862D01*
G01X293111D02*
Y234035D01*
G01Y212342D02*
Y216515D01*
G01X293077Y214822D02*
Y213838D01*
G01X293072Y214822D02*
Y213838D01*
G01Y232539D02*
Y231555D01*
G01X292875Y215984D02*
Y209901D01*
G01Y236476D02*
Y230393D01*
G01X292796Y213838D02*
Y232539D01*
G01X292717Y214824D02*
Y213840D01*
G01Y232538D02*
Y231553D01*
G01X292521Y231555D02*
Y236396D01*
G01Y209981D02*
Y214822D01*
G01X292481Y208523D02*
Y203011D01*
G01X292442Y230760D02*
Y231750D01*
G01Y214627D02*
Y215617D01*
G01X292363Y210965D02*
Y209901D01*
G01Y236476D02*
Y235412D01*
G01X292088Y210885D02*
Y209901D01*
G01Y236476D02*
Y235492D01*
G01X291300D02*
Y236476D01*
G01Y210885D02*
Y209901D01*
G01X291025Y210965D02*
Y209901D01*
G01Y236476D02*
Y235412D01*
G01X290946Y215617D02*
Y214627D01*
G01Y231750D02*
Y230760D01*
G01X290867Y231555D02*
Y236396D01*
G01Y209981D02*
Y214822D01*
G01X290670Y213840D02*
Y214824D01*
G01Y231553D02*
Y232538D01*
G01X290592Y232539D02*
Y213838D01*
G01X290513Y215984D02*
Y209901D01*
G01Y236476D02*
Y230393D01*
G01X290316Y214822D02*
Y213838D01*
G01Y232539D02*
Y231555D01*
G01X290311Y232539D02*
Y231555D01*
G01X290277Y216515D02*
Y212342D01*
G01Y234035D02*
Y229862D01*
G01X289174D02*
Y234035D01*
G01Y212342D02*
Y216515D01*
G01X289139Y232539D02*
Y231555D01*
G01X289135Y214822D02*
Y213838D01*
G01X289130Y214822D02*
Y213838D01*
G01X288938Y215984D02*
Y209901D01*
G01Y236476D02*
Y230393D01*
G01X288859Y213838D02*
Y232539D01*
G01X288785Y232538D02*
Y231553D01*
G01X288776Y214824D02*
Y213840D01*
G01X288584Y227698D02*
Y232539D01*
G01Y213838D02*
Y218680D01*
G01X288510Y230760D02*
Y231750D01*
G01X288500Y214627D02*
Y215617D01*
G01X288426Y218760D02*
Y217696D01*
G01Y228681D02*
Y227618D01*
G01X288151Y218760D02*
Y217775D01*
G01Y228602D02*
Y227618D01*
G01X287363Y218760D02*
Y217775D01*
G01Y228602D02*
Y227618D01*
G01X287088Y218760D02*
Y217696D01*
G01Y228681D02*
Y227618D01*
G01X287014Y231750D02*
Y230760D01*
G01X287004Y215617D02*
Y214627D01*
G01X286930Y227698D02*
Y232539D01*
G01Y213838D02*
Y218680D01*
G01X286738Y231553D02*
Y232538D01*
G01X286729Y213840D02*
Y214824D01*
G01X286655Y232539D02*
Y213838D01*
G01X286576Y215984D02*
Y209901D01*
G01Y236476D02*
Y230393D01*
G01X286384Y232539D02*
Y231555D01*
G01X286379Y232539D02*
Y231555D01*
G01X286374Y214822D02*
Y213838D01*
G01X286340Y216515D02*
Y212342D01*
G01Y234035D02*
Y229862D01*
G01X285237D02*
Y234035D01*
G01Y212342D02*
Y216515D01*
G01X285202Y214822D02*
Y213838D01*
G01X285198Y214822D02*
Y213838D01*
G01Y232539D02*
Y231555D01*
G01X285001Y215984D02*
Y209901D01*
G01Y236476D02*
Y230393D01*
G01X284922Y213838D02*
Y232539D01*
G01X284843Y214824D02*
Y213840D01*
G01Y232538D02*
Y231553D01*
G01X284647Y231555D02*
Y236396D01*
G01Y209981D02*
Y214822D01*
G01X284568Y230760D02*
Y231750D01*
G01Y214627D02*
Y215617D01*
G01X284489Y210965D02*
Y209901D01*
G01Y236476D02*
Y235412D01*
G01X284214Y210885D02*
Y209901D01*
G01Y236476D02*
Y235492D01*
G01X283426D02*
Y236476D01*
G01Y210885D02*
Y209901D01*
G01X283151Y210965D02*
Y209901D01*
G01Y236476D02*
Y235412D01*
G01X283072Y215617D02*
Y214627D01*
G01Y231750D02*
Y230760D01*
G01X282993Y231555D02*
Y236396D01*
G01Y209981D02*
Y214822D01*
G01X282796Y213840D02*
Y214824D01*
G01Y231553D02*
Y232538D01*
G01X282717Y232539D02*
Y213838D01*
G01X282639Y215984D02*
Y209901D01*
G01Y236476D02*
Y230393D01*
G01X282442Y214822D02*
Y213838D01*
G01Y232539D02*
Y231555D01*
G01X282437Y232539D02*
Y231555D01*
G01X282403Y216515D02*
Y212342D01*
G01Y234035D02*
Y229862D01*
G01X303992Y231368D02*
X304005Y230393D01*
G01X303018Y215009D02*
X303004Y215984D01*
G01X300051Y231368D02*
X300064Y230393D01*
G01X299085Y215009D02*
X299072Y215984D01*
G01X296118Y231368D02*
X296131Y230393D01*
G01X295144Y215009D02*
X295130Y215984D01*
G01X292177Y231368D02*
X292190Y230393D01*
G01X291211Y215009D02*
X291198Y215984D01*
G01X288244Y231368D02*
X288257Y230393D01*
G01X287270Y215009D02*
X287256Y215984D01*
G01X284303Y231368D02*
X284316Y230393D01*
G01X283337Y215009D02*
X283324Y215984D01*
G01X280370Y231368D02*
X280383Y230393D01*
G01X302640Y226239D02*
X302504Y232147D01*
G01X302499Y231260D02*
X302635Y225353D01*
G01X300578Y215117D02*
X300442Y221024D01*
G01X300437Y220138D02*
X300574Y214231D01*
G01X298698Y226239D02*
X298562Y232147D01*
G01X298557Y231260D02*
X298694Y225353D01*
G01X296637Y215117D02*
X296500Y221024D01*
G01X296496Y220138D02*
X296632Y214231D01*
G01X294766Y226239D02*
X294630Y232147D01*
G01X294625Y231260D02*
X294761Y225353D01*
G01X292704Y215117D02*
X292568Y221024D01*
G01X292563Y220138D02*
X292700Y214231D01*
G01X290824Y226239D02*
X290688Y232147D01*
G01X290683Y231260D02*
X290820Y225353D01*
G01X288763Y215117D02*
X288626Y221024D01*
G01X288622Y220138D02*
X288758Y214231D01*
G01X286892Y226239D02*
X286756Y232147D01*
G01X286751Y231260D02*
X286887Y225353D01*
G01X284830Y215117D02*
X284694Y221024D01*
G01X284689Y220138D02*
X284825Y214231D01*
G01X282950Y226239D02*
X282814Y232147D01*
G01X282809Y231260D02*
X282946Y225353D01*
G01X280889Y215117D02*
X280752Y221024D01*
G01X280748Y220138D02*
X280884Y214231D01*
G01X279018Y226239D02*
X278882Y232147D01*
G01X278877Y231260D02*
X279013Y225353D01*
G01X298773Y220340D02*
X298722Y221327D01*
G01X298720Y220365D02*
X298770Y219379D01*
G01X296484Y226012D02*
X296433Y226999D01*
G01X296431Y226037D02*
X296481Y225050D01*
G01X294831Y220340D02*
X294780Y221327D01*
G01X294778Y220365D02*
X294829Y219379D01*
G01X292542Y226012D02*
X292491Y226999D01*
G01X292489Y226037D02*
X292540Y225050D01*
G01X290899Y220340D02*
X290848Y221327D01*
G01X290846Y220365D02*
X290896Y219379D01*
G01X288610Y226012D02*
X288559Y226999D01*
G01X288557Y226037D02*
X288607Y225050D01*
G01X286957Y220340D02*
X286906Y221327D01*
G01X286904Y220365D02*
X286955Y219379D01*
G01X284668Y226012D02*
X284617Y226999D01*
G01X284615Y226037D02*
X284666Y225050D01*
G01X283025Y220340D02*
X282974Y221327D01*
G01X282972Y220365D02*
X283022Y219379D01*
G01X280736Y226012D02*
X280685Y226999D01*
G01X280683Y226037D02*
X280733Y225050D01*
G01X279083Y220340D02*
X279032Y221327D01*
G01X279030Y220365D02*
X279081Y219379D01*
G01X276794Y226012D02*
X276743Y226999D01*
G01X276741Y226037D02*
X276792Y225050D01*
G01X275151Y220340D02*
X275100Y221327D01*
G01X275098Y220365D02*
X275148Y219379D01*
G01X346075Y214640D02*
X346329Y215009D01*
G01X346062Y215615D02*
X346284Y215937D01*
G01X342134Y214640D02*
X342388Y215009D01*
G01X342121Y215615D02*
X342342Y215937D01*
G01X338201Y214640D02*
X338455Y215009D01*
G01X338188Y215615D02*
X338410Y215937D01*
G01X334260Y214640D02*
X334514Y215009D01*
G01X334247Y215615D02*
X334468Y215937D01*
G01X343629Y230762D02*
X343408Y230441D01*
G01X343616Y231737D02*
X343362Y231368D01*
G01X306923Y215984D02*
X306914Y215937D01*
G01X307961Y230393D02*
X307970Y230441D01*
G01X302982Y215984D02*
X302972Y215937D01*
G01X304028Y230393D02*
X304038Y230441D01*
G01X299049Y215984D02*
X299040Y215937D01*
G01X300087Y230393D02*
X300096Y230441D01*
G01X295108Y215984D02*
X295098Y215937D01*
G01X296154Y230393D02*
X296164Y230441D01*
G01X291175Y215984D02*
X291166Y215937D01*
G01X292213Y230393D02*
X292222Y230441D01*
G01X287233Y215984D02*
X287224Y215937D01*
G01X288280Y230393D02*
X288290Y230441D01*
G01X283301Y215984D02*
X283292Y215937D01*
G01X288598Y221327D02*
X288547Y220340D01*
G01X286916Y225050D02*
X286966Y226037D01*
G01X286964Y226999D02*
X286913Y226012D01*
G01X284617Y219379D02*
X284668Y220365D01*
G01X284666Y221327D02*
X284615Y220340D01*
G01X282974Y225050D02*
X283025Y226037D01*
G01X283022Y226999D02*
X282972Y226012D01*
G01X280676Y219379D02*
X280726Y220365D01*
G01X280724Y221327D02*
X280673Y220340D01*
G01X279042Y225050D02*
X279092Y226037D01*
G01X279090Y226999D02*
X279039Y226012D01*
G01X276743Y219379D02*
X276794Y220365D01*
G01X276792Y221327D02*
X276741Y220340D01*
G01X275100Y225050D02*
X275151Y226037D01*
G01X275148Y226999D02*
X275098Y226012D01*
G01X272802Y219379D02*
X272852Y220365D01*
G01X272850Y221327D02*
X272799Y220340D01*
G01X271168Y225050D02*
X271218Y226037D01*
G01X271216Y226999D02*
X271165Y226012D01*
G01X268869Y219379D02*
X268920Y220365D01*
G01X268918Y221327D02*
X268867Y220340D01*
G01X267226Y225050D02*
X267277Y226037D01*
G01X267274Y226999D02*
X267224Y226012D01*
G01X284694Y225353D02*
X284830Y231260D01*
G01X284825Y232147D02*
X284689Y226239D01*
G01X282814Y214231D02*
X282950Y220138D01*
G01X282946Y221024D02*
X282809Y215117D01*
G01X280762Y225353D02*
X280898Y231260D01*
G01X280893Y232147D02*
X280757Y226239D01*
G01X278873Y214231D02*
X279009Y220138D01*
G01X279004Y221024D02*
X278868Y215117D01*
G01X276820Y225353D02*
X276956Y231260D01*
G01X276951Y232147D02*
X276815Y226239D01*
G01X274940Y214231D02*
X275076Y220138D01*
G01X275072Y221024D02*
X274935Y215117D01*
G01X272888Y225353D02*
X273024Y231260D01*
G01X273019Y232147D02*
X272883Y226239D01*
G01X270999Y214231D02*
X271135Y220138D01*
G01X271130Y221024D02*
X270994Y215117D01*
G01X268946Y225353D02*
X269082Y231260D01*
G01X269077Y232147D02*
X268941Y226239D01*
G01X267066Y214231D02*
X267202Y220138D01*
G01X267198Y221024D02*
X267061Y215117D01*
G01X283324Y230393D02*
X283337Y231368D01*
G01X280374Y215984D02*
X280361Y215009D01*
G01X279392Y230393D02*
X279405Y231368D01*
G01X276442Y215984D02*
X276429Y215009D01*
G01X275450Y230393D02*
X275463Y231368D01*
G01X272500Y215984D02*
X272487Y215009D01*
G01X271518Y230393D02*
X271531Y231368D01*
G01X268568Y215984D02*
X268555Y215009D01*
G01X267576Y230393D02*
X267589Y231368D01*
G01X281300Y229862D02*
Y234035D01*
G01Y212342D02*
Y216515D01*
G01X281265Y232539D02*
Y231555D01*
G01X281261Y214822D02*
Y213838D01*
G01X281256Y214822D02*
Y213838D01*
G01X281064Y215984D02*
Y209901D01*
G01Y236476D02*
Y230393D01*
G01X280985Y213838D02*
Y232539D01*
G01X280911Y232538D02*
Y231553D01*
G01X280902Y214824D02*
Y213840D01*
G01X280710Y227698D02*
Y232539D01*
G01Y213838D02*
Y218680D01*
G01X280636Y230760D02*
Y231750D01*
G01X280626Y214627D02*
Y215617D01*
G01X280552Y218760D02*
Y217696D01*
G01Y228681D02*
Y227618D01*
G01X280277Y218760D02*
Y217775D01*
G01Y228602D02*
Y227618D01*
G01X279489Y218760D02*
Y217775D01*
G01Y228602D02*
Y227618D01*
G01X279214Y218760D02*
Y217696D01*
G01Y228681D02*
Y227618D01*
G01X279139Y231750D02*
Y230760D01*
G01X279130Y215617D02*
Y214627D01*
G01X279095Y208523D02*
Y203011D01*
G01X279056Y227698D02*
Y232539D01*
G01Y213838D02*
Y218680D01*
G01X278864Y231553D02*
Y232538D01*
G01X278855Y213840D02*
Y214824D01*
G01X278780Y232539D02*
Y213838D01*
G01X278702Y215984D02*
Y209901D01*
G01Y236476D02*
Y230393D01*
G01X278510Y232539D02*
Y231555D01*
G01X278505Y232539D02*
Y231555D01*
G01X278500Y214822D02*
Y213838D01*
G01X278466Y216515D02*
Y212342D01*
G01Y234035D02*
Y229862D01*
G01X277363D02*
Y234035D01*
G01Y212342D02*
Y216515D01*
G01X277328Y214822D02*
Y213838D01*
G01X277324Y214822D02*
Y213838D01*
G01Y232539D02*
Y231555D01*
G01X277127Y215984D02*
Y209901D01*
G01Y236476D02*
Y230393D01*
G01X277048Y213838D02*
Y232539D01*
G01X276969Y214824D02*
Y213840D01*
G01Y232538D02*
Y231553D01*
G01X276773Y231555D02*
Y236396D01*
G01Y209981D02*
Y214822D01*
G01X276694Y230760D02*
Y231750D01*
G01Y214627D02*
Y215617D01*
G01X276615Y210965D02*
Y209901D01*
G01Y236476D02*
Y235412D01*
G01X276340Y210885D02*
Y209901D01*
G01Y236476D02*
Y235492D01*
G01X275946Y208523D02*
Y203011D01*
G01X275552Y235492D02*
Y236476D01*
G01Y210885D02*
Y209901D01*
G01X275277Y210965D02*
Y209901D01*
G01Y236476D02*
Y235412D01*
G01X275198Y215617D02*
Y214627D01*
G01Y231750D02*
Y230760D01*
G01X275119Y231555D02*
Y236396D01*
G01Y209981D02*
Y214822D01*
G01X274922Y231553D02*
Y232538D01*
G01Y213840D02*
Y214824D01*
G01X274843Y232539D02*
Y213838D01*
G01X274765Y215984D02*
Y209901D01*
G01Y236476D02*
Y230393D01*
G01X274568Y214822D02*
Y213838D01*
G01Y232539D02*
Y231555D01*
G01X274563Y232539D02*
Y231555D01*
G01X274529Y216515D02*
Y212342D01*
G01Y234035D02*
Y229862D01*
G01X273426D02*
Y234035D01*
G01Y212342D02*
Y216515D01*
G01X273391Y232539D02*
Y231555D01*
G01X273387Y214822D02*
Y213838D01*
G01X273382Y214822D02*
Y213838D01*
G01X273190Y215984D02*
Y209901D01*
G01Y236476D02*
Y230393D01*
G01X273111Y213838D02*
Y232539D01*
G01X273037Y232538D02*
Y231553D01*
G01X273028Y214824D02*
Y213840D01*
G01X272836Y227698D02*
Y232539D01*
G01Y213838D02*
Y218680D01*
G01X272762Y230760D02*
Y231750D01*
G01X272752Y214627D02*
Y215617D01*
G01X272678Y218760D02*
Y217696D01*
G01Y228681D02*
Y227618D01*
G01X272403D02*
Y228602D01*
G01Y218760D02*
Y217775D01*
G01X272009Y208523D02*
Y203011D01*
G01X271615Y227618D02*
Y228602D01*
G01Y217775D02*
Y218760D01*
G01X271340D02*
Y217696D01*
G01Y228681D02*
Y227618D01*
G01X271265Y231750D02*
Y230760D01*
G01X271256Y215617D02*
Y214627D01*
G01X271182Y227698D02*
Y232539D01*
G01Y213838D02*
Y218680D01*
G01X270990Y231553D02*
Y232538D01*
G01X270981Y213840D02*
Y214824D01*
G01X270906Y232539D02*
Y213838D01*
G01X270828Y215984D02*
Y209901D01*
G01Y236476D02*
Y230393D01*
G01X270636Y232539D02*
Y231555D01*
G01X270631Y232539D02*
Y231555D01*
G01X270626Y214822D02*
Y213838D01*
G01X270592Y216515D02*
Y212342D01*
G01Y234035D02*
Y229862D01*
G01X269489D02*
Y234035D01*
G01Y212342D02*
Y216515D01*
G01X269454Y214822D02*
Y213838D01*
G01X269450Y214822D02*
Y213838D01*
G01Y232539D02*
Y231555D01*
G01X269253Y215984D02*
Y209901D01*
G01Y236476D02*
Y230393D01*
G01X269174Y213838D02*
Y232539D01*
G01X269095Y214824D02*
Y213840D01*
G01Y232538D02*
Y231553D01*
G01X268899Y231555D02*
Y236396D01*
G01Y209981D02*
Y214822D01*
G01X268859Y208523D02*
Y203011D01*
G01X268820Y230760D02*
Y231750D01*
G01Y214627D02*
Y215617D01*
G01X268741Y210965D02*
Y209901D01*
G01Y236476D02*
Y235412D01*
G01X268466Y210885D02*
Y209901D01*
G01Y236476D02*
Y235492D01*
G01X267678D02*
Y236476D01*
G01Y210885D02*
Y209901D01*
G01X267403Y210965D02*
Y209901D01*
G01Y236476D02*
Y235412D01*
G01X267324Y215617D02*
Y214627D01*
G01Y231750D02*
Y230760D01*
G01X267245Y231555D02*
Y236396D01*
G01Y209981D02*
Y214822D01*
G01X267048Y231553D02*
Y232538D01*
G01Y213840D02*
Y214824D01*
G01X266969Y232539D02*
Y213838D01*
G01X266891Y215984D02*
Y209901D01*
G01Y236476D02*
Y230393D01*
G01X279396Y215009D02*
X279382Y215984D01*
G01X276429Y231368D02*
X276442Y230393D01*
G01X275463Y215009D02*
X275450Y215984D01*
G01X272496Y231368D02*
X272509Y230393D01*
G01X271521Y215009D02*
X271508Y215984D01*
G01X268555Y231368D02*
X268568Y230393D01*
G01X267589Y215009D02*
X267576Y215984D01*
G01X276956Y215117D02*
X276820Y221024D01*
G01X276815Y220138D02*
X276951Y214231D01*
G01X275076Y226239D02*
X274940Y232147D01*
G01X274935Y231260D02*
X275072Y225353D01*
G01X273015Y215117D02*
X272878Y221024D01*
G01X272874Y220138D02*
X273010Y214231D01*
G01X271144Y226239D02*
X271008Y232147D01*
G01X271003Y231260D02*
X271139Y225353D01*
G01X269082Y215117D02*
X268946Y221024D01*
G01X268941Y220138D02*
X269077Y214231D01*
G01X267202Y226239D02*
X267066Y232147D01*
G01X267061Y231260D02*
X267198Y225353D01*
G01X272862Y226012D02*
X272811Y226999D01*
G01X272809Y226037D02*
X272859Y225050D01*
G01X271209Y220340D02*
X271158Y221327D01*
G01X271156Y220365D02*
X271207Y219379D01*
G01X268920Y226012D02*
X268869Y226999D01*
G01X268867Y226037D02*
X268918Y225050D01*
G01X267277Y220340D02*
X267226Y221327D01*
G01X267224Y220365D02*
X267274Y219379D01*
G01X330327Y214640D02*
X330581Y215009D01*
G01X330536Y215937D02*
X330316Y215617D01*
G01X339688Y230762D02*
X339466Y230441D01*
G01X339674Y231737D02*
X339421Y231368D01*
G01X326386Y214640D02*
X326640Y215009D01*
G01X326373Y215615D02*
X326594Y215937D01*
G01X335755Y230762D02*
X335534Y230441D01*
G01X335742Y231737D02*
X335488Y231368D01*
G01X322453Y214640D02*
X322707Y215009D01*
G01X322662Y215937D02*
X322442Y215617D01*
G01X331592Y230441D02*
X331812Y230760D01*
G01X331800Y231737D02*
X331547Y231368D01*
G01X318512Y214640D02*
X318766Y215009D01*
G01X318499Y215615D02*
X318720Y215937D01*
G01X327881Y230762D02*
X327660Y230441D01*
G01X327868Y231737D02*
X327614Y231368D01*
G01X314579Y214640D02*
X314833Y215009D01*
G01X314566Y215615D02*
X314788Y215937D01*
G01X323718Y230441D02*
X323938Y230760D01*
G01X323926Y231737D02*
X323673Y231368D01*
G01X310638Y214640D02*
X310892Y215009D01*
G01X310625Y215615D02*
X310846Y215937D01*
G01X320007Y230762D02*
X319786Y230441D01*
G01X319994Y231737D02*
X319740Y231368D01*
G01X306705Y214640D02*
X306959Y215009D01*
G01X306692Y215615D02*
X306914Y215937D01*
G01X316066Y230762D02*
X315844Y230441D01*
G01X316052Y231737D02*
X315799Y231368D01*
G01X302764Y214640D02*
X303018Y215009D01*
G01X302751Y215615D02*
X302972Y215937D01*
G01X284339Y230393D02*
X284348Y230441D01*
G01X279359Y215984D02*
X279350Y215937D01*
G01X280406Y230393D02*
X280416Y230441D01*
G01X275427Y215984D02*
X275418Y215937D01*
G01X276465Y230393D02*
X276474Y230441D01*
G01X271485Y215984D02*
X271476Y215937D01*
G01X272532Y230393D02*
X272542Y230441D01*
G01X267553Y215984D02*
X267544Y215937D01*
G01X268591Y230393D02*
X268600Y230441D01*
G01X312133Y230762D02*
X311912Y230441D01*
G01X312120Y231737D02*
X311866Y231368D01*
G01X298831Y214640D02*
X299085Y215009D01*
G01X298818Y215615D02*
X299040Y215937D01*
G01X308192Y230762D02*
X307970Y230441D01*
G01X308178Y231737D02*
X307925Y231368D01*
G01X294890Y214640D02*
X295144Y215009D01*
G01X294877Y215615D02*
X295098Y215937D01*
G01X304259Y230762D02*
X304038Y230441D01*
G01X304246Y231737D02*
X303992Y231368D01*
G01X290957Y214640D02*
X291211Y215009D01*
G01X290944Y215615D02*
X291166Y215937D01*
G01X300318Y230762D02*
X300096Y230441D01*
G01X300304Y231737D02*
X300051Y231368D01*
G01X287016Y214640D02*
X287270Y215009D01*
G01X287003Y215615D02*
X287224Y215937D01*
G01X296385Y230762D02*
X296164Y230441D01*
G01X296372Y231737D02*
X296118Y231368D01*
G01X283083Y214640D02*
X283337Y215009D01*
G01X283070Y215615D02*
X283292Y215937D01*
G01X292444Y230762D02*
X292222Y230441D01*
G01X292430Y231737D02*
X292177Y231368D01*
G01X279142Y214640D02*
X279396Y215009D01*
G01X279129Y215615D02*
X279350Y215937D01*
G01X288511Y230762D02*
X288290Y230441D01*
G01X288498Y231737D02*
X288244Y231368D01*
G01X275209Y214640D02*
X275463Y215009D01*
G01X275196Y215615D02*
X275418Y215937D01*
G01X284569Y230762D02*
X284348Y230441D01*
G01X284556Y231737D02*
X284303Y231368D01*
G01X271268Y214640D02*
X271521Y215009D01*
G01X271255Y215615D02*
X271476Y215937D01*
G01X280637Y230762D02*
X280416Y230441D01*
G01X280624Y231737D02*
X280370Y231368D01*
G01X267335Y214640D02*
X267589Y215009D01*
G01X267322Y215615D02*
X267544Y215937D01*
G01X276695Y230762D02*
X276474Y230441D01*
G01X276682Y231737D02*
X276429Y231368D01*
G01X272763Y230762D02*
X272542Y230441D01*
G01X272750Y231737D02*
X272496Y231368D01*
G01X268821Y230762D02*
X268600Y230441D01*
G01X268808Y231737D02*
X268555Y231368D01*
G01X288074Y782204D02*
Y764881D01*
G01X382978Y-589495D02*
Y-583195D01*
X380080Y-587710D01*
X383996D01*
G01X396329Y-369833D02*
G03X412312Y-381271I66438J75952D01*
G01X460163Y-298390D02*
X410343Y-384681D01*
G01X407258Y-449536D02*
X406283Y-448814D01*
G01X408232Y-449536D02*
X407258D01*
G01X409207Y-448814D02*
X408232Y-449536D01*
G01X409694Y-448093D02*
X409207Y-448814D01*
G01X409694Y-446649D02*
Y-448093D01*
G01X409207Y-445927D02*
X409694Y-446649D01*
G01X406283Y-443762D02*
X409207Y-445927D01*
G01X405796Y-443040D02*
X406283Y-443762D01*
G01X405796Y-442318D02*
Y-443040D01*
G01X406283Y-441597D02*
X405796Y-442318D01*
G01X407258Y-440875D02*
X406283Y-441597D01*
G01X408232Y-440875D02*
X407258D01*
G01X409207Y-441597D02*
X408232Y-440875D01*
G01X409694Y-442318D02*
X409207Y-441597D01*
G01X413104Y-443040D02*
X414079Y-441597D01*
G01X412617Y-445206D02*
X413104Y-443040D01*
G01Y-447371D02*
X412617Y-445206D01*
G01X423336Y-440875D02*
X425772Y-449536D01*
G01X420899D02*
X423336Y-440875D01*
G01X414079Y-448814D02*
X413104Y-447371D01*
G01X415053Y-449536D02*
X414079Y-448814D01*
G01X416027Y-449536D02*
X415053D01*
G01X417002Y-448814D02*
X416027Y-449536D01*
G01X417489Y-448093D02*
X417002Y-448814D01*
G01Y-441597D02*
X417489Y-442318D01*
G01X416027Y-440875D02*
X417002Y-441597D01*
G01X415053Y-440875D02*
X416027D01*
G01X414079Y-441597D02*
X415053Y-440875D01*
G01X406283Y-448814D02*
X405309Y-447371D01*
G01X421874Y-446649D02*
X424797D01*
G01X403466Y-73347D02*
X405434Y-71378D01*
G01X403466Y-73347D02*
X405434Y-71378D01*
G01D02*
Y-42638D01*
G01Y-71378D02*
Y-42638D01*
G01X402501Y-69410D02*
Y-58386D01*
G01X400336D02*
Y-69410D01*
G01X399351D02*
Y-58386D01*
G01X397186D02*
Y-69410D01*
G01X396202D02*
Y-58386D01*
G01X394036D02*
Y-69410D01*
G01X393052D02*
Y-58386D01*
G01X390887D02*
Y-69410D01*
G01X389903D02*
Y-58386D01*
G01X387737D02*
Y-69410D01*
G01X386753D02*
Y-58386D01*
G01X384588D02*
Y-69410D01*
G01X383603D02*
Y-58386D01*
G01X381438D02*
Y-69410D01*
G01X380454D02*
Y-58386D01*
G01X378288D02*
Y-69410D01*
G01X377304D02*
Y-58386D01*
G01X375139D02*
Y-69410D01*
G01X374155D02*
Y-58386D01*
G01X371989D02*
Y-69410D01*
G01X371005D02*
Y-58386D01*
G01X368840D02*
Y-69410D01*
G01X367855D02*
Y-58386D01*
G01X365690D02*
Y-69410D01*
G01X364706D02*
Y-58386D01*
G01X362540D02*
Y-69410D01*
G01X361556D02*
Y-58386D01*
G01X359391D02*
Y-69410D01*
G01X358406D02*
Y-58386D01*
G01X356241D02*
Y-69410D01*
G01X355257D02*
Y-58386D01*
G01X353092D02*
Y-69410D01*
G01X352107D02*
Y-58386D01*
G01X349942D02*
Y-69410D01*
G01X348958D02*
Y-58386D01*
G01X400336Y-69410D02*
X402501D01*
G01X397186D02*
X399351D01*
G01X394036D02*
X396202D01*
G01X390887D02*
X393052D01*
G01X387737D02*
X389903D01*
G01X384588D02*
X386753D01*
G01X381438D02*
X383603D01*
G01X378288D02*
X380454D01*
G01X375139D02*
X377304D01*
G01X371989D02*
X374155D01*
G01X368840D02*
X371005D01*
G01X365690D02*
X367855D01*
G01X362540D02*
X364706D01*
G01X359391D02*
X361556D01*
G01X356241D02*
X358406D01*
G01X353092D02*
X355257D01*
G01X349942D02*
X352107D01*
G01X405434Y-71378D02*
Y-42638D01*
G01X403466Y-73346D02*
X405434Y-71378D01*
G01X406221Y-41851D02*
G03X405434Y-42638I0J-787D01*
G01X406221Y-41851D02*
G03X405434Y-42638I0J-787D01*
G01X439883Y-41851D02*
X406221D01*
G01X439883D02*
X406221D01*
G01X352107Y-58386D02*
X349942D01*
G01X355257D02*
X353092D01*
G01X358406D02*
X356241D01*
G01X361556D02*
X359391D01*
G01X364706D02*
X362540D01*
G01X367855D02*
X365690D01*
G01X371005D02*
X368840D01*
G01X374155D02*
X371989D01*
G01X377304D02*
X375139D01*
G01X380454D02*
X378288D01*
G01X383603D02*
X381438D01*
G01X386753D02*
X384588D01*
G01X389903D02*
X387737D01*
G01X393052D02*
X390887D01*
G01X396202D02*
X394036D01*
G01X399351D02*
X397186D01*
G01X402501D02*
X400336D01*
G01X406221Y-41850D02*
X439883D01*
G01X406221D02*
G03X405434Y-42638I1J-788D01*
G01X424693Y145965D02*
X424704Y146012D01*
G01X424688Y146063D02*
X424693Y145965D01*
G01X424683Y146239D02*
X424688Y146063D01*
G01X424778Y148861D02*
X424780Y149826D01*
G01X424776Y148414D02*
X424778Y148861D01*
G01X424773Y148009D02*
X424776Y148414D01*
G01X424769Y147656D02*
X424773Y148009D01*
G01X424765Y147364D02*
X424769Y147656D01*
G01X424760Y147143D02*
X424765Y147364D01*
G01X424755Y146999D02*
X424760Y147143D01*
G01X424789Y148520D02*
X424791Y149807D01*
G01X424786Y147925D02*
X424789Y148520D01*
G01X424781Y147384D02*
X424786Y147925D01*
G01X424776Y146913D02*
X424781Y147384D01*
G01X424770Y146524D02*
X424776Y146913D01*
G01X424764Y146230D02*
X424770Y146524D01*
G01X424757Y146037D02*
X424764Y146230D01*
G01X424692Y144988D02*
X424706Y145050D01*
G01X424685Y145118D02*
X424692Y144988D01*
G01X424678Y145353D02*
X424685Y145118D01*
G01X426411Y145965D02*
X426422Y146239D01*
G01X426406Y145948D02*
X426411Y145965D01*
G01X426400Y146012D02*
X426406Y145948D01*
G01X426412Y144988D02*
X426426Y145353D01*
G01X426405Y144965D02*
X426412Y144988D01*
G01X426398Y145050D02*
X426405Y144965D01*
G01X426334Y146524D02*
X426347Y146037D01*
G01X426328Y146913D02*
X426334Y146524D01*
G01X426323Y147384D02*
X426328Y146913D01*
G01X426319Y147925D02*
X426323Y147384D01*
G01X426316Y148520D02*
X426319Y147925D01*
G01X426314Y149153D02*
X426316Y148520D01*
G01X426313Y149807D02*
X426314Y149153D01*
G01X426340Y147364D02*
X426350Y146999D01*
G01X426335Y147656D02*
X426340Y147364D01*
G01X426331Y148009D02*
X426335Y147656D01*
G01X426328Y148414D02*
X426331Y148009D01*
G01X426326Y148861D02*
X426328Y148414D01*
G01X426324Y149336D02*
X426326Y148861D01*
G01X426324Y149826D02*
Y149336D01*
G01X426411Y140412D02*
X426400Y140365D01*
G01X426416Y140314D02*
X426411Y140412D01*
G01X426422Y140138D02*
X426416Y140314D01*
G01X426326Y137516D02*
X426324Y136551D01*
G01X426328Y137963D02*
X426326Y137516D01*
G01X426331Y138368D02*
X426328Y137963D01*
G01X426335Y138722D02*
X426331Y138368D01*
G01X426340Y139013D02*
X426335Y138722D01*
G01X426344Y139234D02*
X426340Y139013D01*
G01X426350Y139379D02*
X426344Y139234D01*
G01X426316Y137857D02*
X426313Y136570D01*
G01X426319Y138453D02*
X426316Y137857D01*
G01X426323Y138993D02*
X426319Y138453D01*
G01X426328Y139464D02*
X426323Y138993D01*
G01X426334Y139853D02*
X426328Y139464D01*
G01X426340Y140148D02*
X426334Y139853D01*
G01X426347Y140340D02*
X426340Y140148D01*
G01X426412Y141390D02*
X426398Y141327D01*
G01X426420Y141259D02*
X426412Y141390D01*
G01X426426Y141024D02*
X426420Y141259D01*
G01X424693Y140412D02*
X424683Y140138D01*
G01X424699Y140429D02*
X424693Y140412D01*
G01X424704Y140365D02*
X424699Y140429D01*
G01X424692Y141390D02*
X424678Y141024D01*
G01X424699Y141412D02*
X424692Y141390D01*
G01X424706Y141327D02*
X424699Y141412D01*
G01X424770Y139853D02*
X424757Y140340D01*
G01X424776Y139464D02*
X424770Y139853D01*
G01X424781Y138993D02*
X424776Y139464D01*
G01X424786Y138453D02*
X424781Y138993D01*
G01X424789Y137857D02*
X424786Y138453D01*
G01X424791Y137224D02*
X424789Y137857D01*
G01X424791Y136570D02*
Y137224D01*
G01X424765Y139013D02*
X424755Y139379D01*
G01X424769Y138722D02*
X424765Y139013D01*
G01X424773Y138368D02*
X424769Y138722D01*
G01X424776Y137963D02*
X424773Y138368D01*
G01X424778Y137516D02*
X424776Y137963D01*
G01X424780Y137041D02*
X424778Y137516D01*
G01X424780Y136551D02*
Y137041D01*
G01X422479Y145965D02*
X422489Y146239D01*
G01X422473Y145948D02*
X422479Y145965D01*
G01X422468Y146012D02*
X422473Y145948D01*
G01X422480Y144988D02*
X422494Y145353D01*
G01X422473Y144965D02*
X422480Y144988D01*
G01X422466Y145050D02*
X422473Y144965D01*
G01X422402Y146524D02*
X422415Y146037D01*
G01X422396Y146913D02*
X422402Y146524D01*
G01X422390Y147384D02*
X422396Y146913D01*
G01X422386Y147925D02*
X422390Y147384D01*
G01X422383Y148520D02*
X422386Y147925D01*
G01X422381Y149153D02*
X422383Y148520D01*
G01X422381Y149807D02*
Y149153D01*
G01X422376Y151677D02*
X422368Y151750D01*
G01X422379Y151547D02*
X422376Y151677D01*
G01X422383Y151359D02*
X422379Y151547D01*
G01X422386Y151120D02*
X422383Y151359D01*
G01X422388Y150838D02*
X422386Y151120D01*
G01X422390Y150521D02*
X422388Y150838D01*
G01X422391Y150180D02*
X422390Y150521D01*
G01X422391Y149826D02*
Y150180D01*
G01X422407Y147364D02*
X422417Y146999D01*
G01X422403Y147656D02*
X422407Y147364D01*
G01X422399Y148009D02*
X422403Y147656D01*
G01X422396Y148414D02*
X422399Y148009D01*
G01X422394Y148861D02*
X422396Y148414D01*
G01X422392Y149336D02*
X422394Y148861D01*
G01X422391Y149826D02*
X422392Y149336D01*
G01X420761Y145965D02*
X420772Y146012D01*
G01X420755Y146063D02*
X420761Y145965D01*
G01X420750Y146239D02*
X420755Y146063D01*
G01X420846Y148861D02*
X420848Y149826D01*
G01X420844Y148414D02*
X420846Y148861D01*
G01X420841Y148009D02*
X420844Y148414D01*
G01X420837Y147656D02*
X420841Y148009D01*
G01X420832Y147364D02*
X420837Y147656D01*
G01X420827Y147143D02*
X420832Y147364D01*
G01X420822Y146999D02*
X420827Y147143D01*
G01X420850Y150521D02*
X420848Y149826D01*
G01X420851Y150838D02*
X420850Y150521D01*
G01X420854Y151120D02*
X420851Y150838D01*
G01X420857Y151359D02*
X420854Y151120D01*
G01X420860Y151547D02*
X420857Y151359D01*
G01X420864Y151677D02*
X420860Y151547D01*
G01X420868Y151746D02*
X420864Y151677D01*
G01X420872Y151750D02*
X420868Y151746D01*
G01X420856Y148520D02*
X420859Y149807D01*
G01X420853Y147925D02*
X420856Y148520D01*
G01X420849Y147384D02*
X420853Y147925D01*
G01X420844Y146913D02*
X420849Y147384D01*
G01X420838Y146524D02*
X420844Y146913D01*
G01X420832Y146230D02*
X420838Y146524D01*
G01X420825Y146037D02*
X420832Y146230D01*
G01X420760Y144988D02*
X420774Y145050D01*
G01X420752Y145118D02*
X420760Y144988D01*
G01X420746Y145353D02*
X420752Y145118D01*
G01Y140412D02*
X420741Y140138D01*
G01X420757Y140429D02*
X420752Y140412D01*
G01X420762Y140365D02*
X420757Y140429D01*
G01X420750Y141390D02*
X420736Y141024D01*
G01X420757Y141412D02*
X420750Y141390D01*
G01X420765Y141327D02*
X420757Y141412D01*
G01X420829Y139853D02*
X420815Y140340D01*
G01X420835Y139464D02*
X420829Y139853D01*
G01X420840Y138993D02*
X420835Y139464D01*
G01X420844Y138453D02*
X420840Y138993D01*
G01X420847Y137857D02*
X420844Y138453D01*
G01X420849Y137224D02*
X420847Y137857D01*
G01X420850Y136570D02*
X420849Y137224D01*
G01X420855Y134700D02*
X420862Y134627D01*
G01X420851Y134830D02*
X420855Y134700D01*
G01X420848Y135018D02*
X420851Y134830D01*
G01X420845Y135257D02*
X420848Y135018D01*
G01X420842Y135540D02*
X420845Y135257D01*
G01X420840Y135857D02*
X420842Y135540D01*
G01X420839Y136198D02*
X420840Y135857D01*
G01X420839Y136551D02*
Y136198D01*
G01X420823Y139013D02*
X420813Y139379D01*
G01X420827Y138722D02*
X420823Y139013D01*
G01X420831Y138368D02*
X420827Y138722D01*
G01X420834Y137963D02*
X420831Y138368D01*
G01X420837Y137516D02*
X420834Y137963D01*
G01X420838Y137041D02*
X420837Y137516D01*
G01X420839Y136551D02*
X420838Y137041D01*
G01X422469Y140412D02*
X422459Y140365D01*
G01X422475Y140314D02*
X422469Y140412D01*
G01X422480Y140138D02*
X422475Y140314D01*
G01X422384Y137516D02*
X422382Y136551D01*
G01X422387Y137963D02*
X422384Y137516D01*
G01X422390Y138368D02*
X422387Y137963D01*
G01X422393Y138722D02*
X422390Y138368D01*
G01X422398Y139013D02*
X422393Y138722D01*
G01X422403Y139234D02*
X422398Y139013D01*
G01X422408Y139379D02*
X422403Y139234D01*
G01X422381Y135857D02*
X422382Y136551D01*
G01X422379Y135540D02*
X422381Y135857D01*
G01X422376Y135257D02*
X422379Y135540D01*
G01X422373Y135018D02*
X422376Y135257D01*
G01X422370Y134830D02*
X422373Y135018D01*
G01X422366Y134700D02*
X422370Y134830D01*
G01X422362Y134632D02*
X422366Y134700D01*
G01X422359Y134627D02*
X422362Y134632D01*
G01X422374Y137857D02*
X422371Y136570D01*
G01X422377Y138453D02*
X422374Y137857D01*
G01X422381Y138993D02*
X422377Y138453D01*
G01X422386Y139464D02*
X422381Y138993D01*
G01X422392Y139853D02*
X422386Y139464D01*
G01X422399Y140148D02*
X422392Y139853D01*
G01X422406Y140340D02*
X422399Y140148D01*
G01X422471Y141390D02*
X422456Y141327D01*
G01X422478Y141259D02*
X422471Y141390D01*
G01X422485Y141024D02*
X422478Y141259D01*
G01X416819Y145965D02*
X416830Y146012D01*
G01X416814Y146063D02*
X416819Y145965D01*
G01X416809Y146239D02*
X416814Y146063D01*
G01X416904Y148861D02*
X416906Y149826D01*
G01X416902Y148414D02*
X416904Y148861D01*
G01X416899Y148009D02*
X416902Y148414D01*
G01X416895Y147656D02*
X416899Y148009D01*
G01X416891Y147364D02*
X416895Y147656D01*
G01X416886Y147143D02*
X416891Y147364D01*
G01X416881Y146999D02*
X416886Y147143D01*
G01X416915Y148520D02*
X416917Y149807D01*
G01X416912Y147925D02*
X416915Y148520D01*
G01X416907Y147384D02*
X416912Y147925D01*
G01X416902Y146913D02*
X416907Y147384D01*
G01X416896Y146524D02*
X416902Y146913D01*
G01X416890Y146230D02*
X416896Y146524D01*
G01X416883Y146037D02*
X416890Y146230D01*
G01X416818Y144988D02*
X416832Y145050D01*
G01X416811Y145118D02*
X416818Y144988D01*
G01X416804Y145353D02*
X416811Y145118D01*
G01X418537Y145965D02*
X418548Y146239D01*
G01X418532Y145948D02*
X418537Y145965D01*
G01X418526Y146012D02*
X418532Y145948D01*
G01X418538Y144988D02*
X418552Y145353D01*
G01X418531Y144965D02*
X418538Y144988D01*
G01X418524Y145050D02*
X418531Y144965D01*
G01X418460Y146524D02*
X418473Y146037D01*
G01X418454Y146913D02*
X418460Y146524D01*
G01X418449Y147384D02*
X418454Y146913D01*
G01X418445Y147925D02*
X418449Y147384D01*
G01X418442Y148520D02*
X418445Y147925D01*
G01X418440Y149153D02*
X418442Y148520D01*
G01X418439Y149807D02*
X418440Y149153D01*
G01X418466Y147364D02*
X418476Y146999D01*
G01X418461Y147656D02*
X418466Y147364D01*
G01X418457Y148009D02*
X418461Y147656D01*
G01X418454Y148414D02*
X418457Y148009D01*
G01X418452Y148861D02*
X418454Y148414D01*
G01X418450Y149336D02*
X418452Y148861D01*
G01X418450Y149826D02*
Y149336D01*
G01X418537Y140412D02*
X418526Y140365D01*
G01X418542Y140314D02*
X418537Y140412D01*
G01X418548Y140138D02*
X418542Y140314D01*
G01X418452Y137516D02*
X418450Y136551D01*
G01X418454Y137963D02*
X418452Y137516D01*
G01X418457Y138368D02*
X418454Y137963D01*
G01X418461Y138722D02*
X418457Y138368D01*
G01X418466Y139013D02*
X418461Y138722D01*
G01X418470Y139234D02*
X418466Y139013D01*
G01X418476Y139379D02*
X418470Y139234D01*
G01X418442Y137857D02*
X418439Y136570D01*
G01X418445Y138453D02*
X418442Y137857D01*
G01X418449Y138993D02*
X418445Y138453D01*
G01X418454Y139464D02*
X418449Y138993D01*
G01X418460Y139853D02*
X418454Y139464D01*
G01X418466Y140148D02*
X418460Y139853D01*
G01X418473Y140340D02*
X418466Y140148D01*
G01X418538Y141390D02*
X418524Y141327D01*
G01X418546Y141259D02*
X418538Y141390D01*
G01X418552Y141024D02*
X418546Y141259D01*
G01X416819Y140412D02*
X416809Y140138D01*
G01X416825Y140429D02*
X416819Y140412D01*
G01X416830Y140365D02*
X416825Y140429D01*
G01X416818Y141390D02*
X416804Y141024D01*
G01X416825Y141412D02*
X416818Y141390D01*
G01X416832Y141327D02*
X416825Y141412D01*
G01X416896Y139853D02*
X416883Y140340D01*
G01X416902Y139464D02*
X416896Y139853D01*
G01X416907Y138993D02*
X416902Y139464D01*
G01X416912Y138453D02*
X416907Y138993D01*
G01X416915Y137857D02*
X416912Y138453D01*
G01X416917Y137224D02*
X416915Y137857D01*
G01X416917Y136570D02*
Y137224D01*
G01X416891Y139013D02*
X416881Y139379D01*
G01X416895Y138722D02*
X416891Y139013D01*
G01X416899Y138368D02*
X416895Y138722D01*
G01X416902Y137963D02*
X416899Y138368D01*
G01X416904Y137516D02*
X416902Y137963D01*
G01X416906Y137041D02*
X416904Y137516D01*
G01X416906Y136551D02*
Y137041D01*
G01X414605Y145965D02*
X414615Y146239D01*
G01X414599Y145948D02*
X414605Y145965D01*
G01X414594Y146012D02*
X414599Y145948D01*
G01X414606Y144988D02*
X414620Y145353D01*
G01X414599Y144965D02*
X414606Y144988D01*
G01X414592Y145050D02*
X414599Y144965D01*
G01X414527Y146524D02*
X414541Y146037D01*
G01X414522Y146913D02*
X414527Y146524D01*
G01X414516Y147384D02*
X414522Y146913D01*
G01X414512Y147925D02*
X414516Y147384D01*
G01X414509Y148520D02*
X414512Y147925D01*
G01X414507Y149153D02*
X414509Y148520D01*
G01X414507Y149807D02*
Y149153D01*
G01X414502Y151677D02*
X414494Y151750D01*
G01X414505Y151547D02*
X414502Y151677D01*
G01X414509Y151359D02*
X414505Y151547D01*
G01X414512Y151120D02*
X414509Y151359D01*
G01X414514Y150838D02*
X414512Y151120D01*
G01X414516Y150521D02*
X414514Y150838D01*
G01X414517Y150180D02*
X414516Y150521D01*
G01X414517Y149826D02*
Y150180D01*
G01X414533Y147364D02*
X414543Y146999D01*
G01X414529Y147656D02*
X414533Y147364D01*
G01X414525Y148009D02*
X414529Y147656D01*
G01X414522Y148414D02*
X414525Y148009D01*
G01X414519Y148861D02*
X414522Y148414D01*
G01X414518Y149336D02*
X414519Y148861D01*
G01X414517Y149826D02*
X414518Y149336D01*
G01X412887Y145965D02*
X412898Y146012D01*
G01X412881Y146063D02*
X412887Y145965D01*
G01X412876Y146239D02*
X412881Y146063D01*
G01X412972Y148861D02*
X412974Y149826D01*
G01X412970Y148414D02*
X412972Y148861D01*
G01X412967Y148009D02*
X412970Y148414D01*
G01X412963Y147656D02*
X412967Y148009D01*
G01X412958Y147364D02*
X412963Y147656D01*
G01X412953Y147143D02*
X412958Y147364D01*
G01X412948Y146999D02*
X412953Y147143D01*
G01X412976Y150521D02*
X412974Y149826D01*
G01X412977Y150838D02*
X412976Y150521D01*
G01X412980Y151120D02*
X412977Y150838D01*
G01X412983Y151359D02*
X412980Y151120D01*
G01X412986Y151547D02*
X412983Y151359D01*
G01X412990Y151677D02*
X412986Y151547D01*
G01X412994Y151746D02*
X412990Y151677D01*
G01X412998Y151750D02*
X412994Y151746D01*
G01X412982Y148520D02*
X412985Y149807D01*
G01X412979Y147925D02*
X412982Y148520D01*
G01X412975Y147384D02*
X412979Y147925D01*
G01X412970Y146913D02*
X412975Y147384D01*
G01X412964Y146524D02*
X412970Y146913D01*
G01X412958Y146230D02*
X412964Y146524D01*
G01X412951Y146037D02*
X412958Y146230D01*
G01X412886Y144988D02*
X412900Y145050D01*
G01X412878Y145118D02*
X412886Y144988D01*
G01X412872Y145353D02*
X412878Y145118D01*
G01X412877Y140412D02*
X412867Y140138D01*
G01X412883Y140429D02*
X412877Y140412D01*
G01X412888Y140365D02*
X412883Y140429D01*
G01X412876Y141390D02*
X412862Y141024D01*
G01X412883Y141412D02*
X412876Y141390D01*
G01X412891Y141327D02*
X412883Y141412D01*
G01X412955Y139853D02*
X412941Y140340D01*
G01X412961Y139464D02*
X412955Y139853D01*
G01X412966Y138993D02*
X412961Y139464D01*
G01X412970Y138453D02*
X412966Y138993D01*
G01X412973Y137857D02*
X412970Y138453D01*
G01X412975Y137224D02*
X412973Y137857D01*
G01X412976Y136570D02*
X412975Y137224D01*
G01X412981Y134700D02*
X412988Y134627D01*
G01X412977Y134830D02*
X412981Y134700D01*
G01X412973Y135018D02*
X412977Y134830D01*
G01X412971Y135257D02*
X412973Y135018D01*
G01X412968Y135540D02*
X412971Y135257D01*
G01X412966Y135857D02*
X412968Y135540D01*
G01X412965Y136198D02*
X412966Y135857D01*
G01X412965Y136551D02*
Y136198D01*
G01X412949Y139013D02*
X412939Y139379D01*
G01X412953Y138722D02*
X412949Y139013D01*
G01X412957Y138368D02*
X412953Y138722D01*
G01X412960Y137963D02*
X412957Y138368D01*
G01X412963Y137516D02*
X412960Y137963D01*
G01X412964Y137041D02*
X412963Y137516D01*
G01X412965Y136551D02*
X412964Y137041D01*
G01X414595Y140412D02*
X414585Y140365D01*
G01X414601Y140314D02*
X414595Y140412D01*
G01X414606Y140138D02*
X414601Y140314D01*
G01X414510Y137516D02*
X414508Y136551D01*
G01X414512Y137963D02*
X414510Y137516D01*
G01X414516Y138368D02*
X414512Y137963D01*
G01X414519Y138722D02*
X414516Y138368D01*
G01X414524Y139013D02*
X414519Y138722D01*
G01X414529Y139234D02*
X414524Y139013D01*
G01X414534Y139379D02*
X414529Y139234D01*
G01X414507Y135857D02*
X414508Y136551D01*
G01X414505Y135540D02*
X414507Y135857D01*
G01X414502Y135257D02*
X414505Y135540D01*
G01X414499Y135018D02*
X414502Y135257D01*
G01X414496Y134830D02*
X414499Y135018D01*
G01X414492Y134700D02*
X414496Y134830D01*
G01X414488Y134632D02*
X414492Y134700D01*
G01X414484Y134627D02*
X414488Y134632D01*
G01X414500Y137857D02*
X414497Y136570D01*
G01X414503Y138453D02*
X414500Y137857D01*
G01X414507Y138993D02*
X414503Y138453D01*
G01X414512Y139464D02*
X414507Y138993D01*
G01X414518Y139853D02*
X414512Y139464D01*
G01X414525Y140148D02*
X414518Y139853D01*
G01X414532Y140340D02*
X414525Y140148D01*
G01X414597Y141390D02*
X414582Y141327D01*
G01X414604Y141259D02*
X414597Y141390D01*
G01X414611Y141024D02*
X414604Y141259D01*
G01X410663Y140412D02*
X410652Y140365D01*
G01X410668Y140314D02*
X410663Y140412D01*
G01X410674Y140138D02*
X410668Y140314D01*
G01X410578Y137516D02*
X410576Y136551D01*
G01X410580Y137963D02*
X410578Y137516D01*
G01X410583Y138368D02*
X410580Y137963D01*
G01X410587Y138722D02*
X410583Y138368D01*
G01X410592Y139013D02*
X410587Y138722D01*
G01X410596Y139234D02*
X410592Y139013D01*
G01X410602Y139379D02*
X410596Y139234D01*
G01X410568Y137857D02*
X410565Y136570D01*
G01X410571Y138453D02*
X410568Y137857D01*
G01X410575Y138993D02*
X410571Y138453D01*
G01X410580Y139464D02*
X410575Y138993D01*
G01X410586Y139853D02*
X410580Y139464D01*
G01X410592Y140148D02*
X410586Y139853D01*
G01X410599Y140340D02*
X410592Y140148D01*
G01X410664Y141390D02*
X410650Y141327D01*
G01X410671Y141259D02*
X410664Y141390D01*
G01X410678Y141024D02*
X410671Y141259D01*
G01X408945Y140412D02*
X408935Y140138D01*
G01X408951Y140429D02*
X408945Y140412D01*
G01X408956Y140365D02*
X408951Y140429D01*
G01X408944Y141390D02*
X408930Y141024D01*
G01X408951Y141412D02*
X408944Y141390D01*
G01X408958Y141327D02*
X408951Y141412D01*
G01X409022Y139853D02*
X409009Y140340D01*
G01X409028Y139464D02*
X409022Y139853D01*
G01X409033Y138993D02*
X409028Y139464D01*
G01X409038Y138453D02*
X409033Y138993D01*
G01X409041Y137857D02*
X409038Y138453D01*
G01X409043Y137224D02*
X409041Y137857D01*
G01X409043Y136570D02*
Y137224D01*
G01X409017Y139013D02*
X409007Y139379D01*
G01X409021Y138722D02*
X409017Y139013D01*
G01X409025Y138368D02*
X409021Y138722D01*
G01X409028Y137963D02*
X409025Y138368D01*
G01X409030Y137516D02*
X409028Y137963D01*
G01X409032Y137041D02*
X409030Y137516D01*
G01X409032Y136551D02*
Y137041D01*
G01X408945Y145965D02*
X408956Y146012D01*
G01X408940Y146063D02*
X408945Y145965D01*
G01X408935Y146239D02*
X408940Y146063D01*
G01X409030Y148861D02*
X409032Y149826D01*
G01X409028Y148414D02*
X409030Y148861D01*
G01X409025Y148009D02*
X409028Y148414D01*
G01X409021Y147656D02*
X409025Y148009D01*
G01X409017Y147364D02*
X409021Y147656D01*
G01X409012Y147143D02*
X409017Y147364D01*
G01X409007Y146999D02*
X409012Y147143D01*
G01X409041Y148520D02*
X409043Y149807D01*
G01X409038Y147925D02*
X409041Y148520D01*
G01X409033Y147384D02*
X409038Y147925D01*
G01X409028Y146913D02*
X409033Y147384D01*
G01X409022Y146524D02*
X409028Y146913D01*
G01X409016Y146230D02*
X409022Y146524D01*
G01X409009Y146037D02*
X409016Y146230D01*
G01X408944Y144988D02*
X408958Y145050D01*
G01X408937Y145118D02*
X408944Y144988D01*
G01X408930Y145353D02*
X408937Y145118D01*
G01X410663Y145965D02*
X410674Y146239D01*
G01X410658Y145948D02*
X410663Y145965D01*
G01X410652Y146012D02*
X410658Y145948D01*
G01X410664Y144988D02*
X410678Y145353D01*
G01X410657Y144965D02*
X410664Y144988D01*
G01X410650Y145050D02*
X410657Y144965D01*
G01X410586Y146524D02*
X410599Y146037D01*
G01X410580Y146913D02*
X410586Y146524D01*
G01X410575Y147384D02*
X410580Y146913D01*
G01X410571Y147925D02*
X410575Y147384D01*
G01X410568Y148520D02*
X410571Y147925D01*
G01X410566Y149153D02*
X410568Y148520D01*
G01X410565Y149807D02*
X410566Y149153D01*
G01X410592Y147364D02*
X410602Y146999D01*
G01X410587Y147656D02*
X410592Y147364D01*
G01X410583Y148009D02*
X410587Y147656D01*
G01X410580Y148414D02*
X410583Y148009D01*
G01X410578Y148861D02*
X410580Y148414D01*
G01X410576Y149336D02*
X410578Y148861D01*
G01X410576Y149826D02*
Y149336D01*
G01X406731Y145965D02*
X406741Y146239D01*
G01X406725Y145948D02*
X406731Y145965D01*
G01X406720Y146012D02*
X406725Y145948D01*
G01X406732Y144988D02*
X406746Y145353D01*
G01X406725Y144965D02*
X406732Y144988D01*
G01X406718Y145050D02*
X406725Y144965D01*
G01X406653Y146524D02*
X406667Y146037D01*
G01X406648Y146913D02*
X406653Y146524D01*
G01X406642Y147384D02*
X406648Y146913D01*
G01X406638Y147925D02*
X406642Y147384D01*
G01X406635Y148520D02*
X406638Y147925D01*
G01X406633Y149153D02*
X406635Y148520D01*
G01X406632Y149807D02*
X406633Y149153D01*
G01X406628Y151677D02*
X406620Y151750D01*
G01X406631Y151547D02*
X406628Y151677D01*
G01X406635Y151359D02*
X406631Y151547D01*
G01X406638Y151120D02*
X406635Y151359D01*
G01X406640Y150838D02*
X406638Y151120D01*
G01X406642Y150521D02*
X406640Y150838D01*
G01X406643Y150180D02*
X406642Y150521D01*
G01X406643Y149826D02*
Y150180D01*
G01X406659Y147364D02*
X406669Y146999D01*
G01X406655Y147656D02*
X406659Y147364D01*
G01X406651Y148009D02*
X406655Y147656D01*
G01X406648Y148414D02*
X406651Y148009D01*
G01X406645Y148861D02*
X406648Y148414D01*
G01X406644Y149336D02*
X406645Y148861D01*
G01X406643Y149826D02*
X406644Y149336D01*
G01X405013Y145965D02*
X405024Y146012D01*
G01X405007Y146063D02*
X405013Y145965D01*
G01X405002Y146239D02*
X405007Y146063D01*
G01X405098Y148861D02*
X405100Y149826D01*
G01X405096Y148414D02*
X405098Y148861D01*
G01X405093Y148009D02*
X405096Y148414D01*
G01X405089Y147656D02*
X405093Y148009D01*
G01X405084Y147364D02*
X405089Y147656D01*
G01X405079Y147143D02*
X405084Y147364D01*
G01X405074Y146999D02*
X405079Y147143D01*
G01X405102Y150521D02*
X405100Y149826D01*
G01X405103Y150838D02*
X405102Y150521D01*
G01X405106Y151120D02*
X405103Y150838D01*
G01X405109Y151359D02*
X405106Y151120D01*
G01X405112Y151547D02*
X405109Y151359D01*
G01X405116Y151677D02*
X405112Y151547D01*
G01X405120Y151746D02*
X405116Y151677D01*
G01X405124Y151750D02*
X405120Y151746D01*
G01X405108Y148520D02*
X405111Y149807D01*
G01X405105Y147925D02*
X405108Y148520D01*
G01X405101Y147384D02*
X405105Y147925D01*
G01X405096Y146913D02*
X405101Y147384D01*
G01X405090Y146524D02*
X405096Y146913D01*
G01X405084Y146230D02*
X405090Y146524D01*
G01X405077Y146037D02*
X405084Y146230D01*
G01X405012Y144988D02*
X405026Y145050D01*
G01X405004Y145118D02*
X405012Y144988D01*
G01X404998Y145353D02*
X405004Y145118D01*
G01X405003Y140412D02*
X404993Y140138D01*
G01X405009Y140429D02*
X405003Y140412D01*
G01X405014Y140365D02*
X405009Y140429D01*
G01X405002Y141390D02*
X404988Y141024D01*
G01X405009Y141412D02*
X405002Y141390D01*
G01X405017Y141327D02*
X405009Y141412D01*
G01X405081Y139853D02*
X405067Y140340D01*
G01X405087Y139464D02*
X405081Y139853D01*
G01X405092Y138993D02*
X405087Y139464D01*
G01X405096Y138453D02*
X405092Y138993D01*
G01X405099Y137857D02*
X405096Y138453D01*
G01X405101Y137224D02*
X405099Y137857D01*
G01X405102Y136570D02*
X405101Y137224D01*
G01X405107Y134700D02*
X405114Y134627D01*
G01X405103Y134830D02*
X405107Y134700D01*
G01X405099Y135018D02*
X405103Y134830D01*
G01X405097Y135257D02*
X405099Y135018D01*
G01X405094Y135540D02*
X405097Y135257D01*
G01X405092Y135857D02*
X405094Y135540D01*
G01X405091Y136198D02*
X405092Y135857D01*
G01X405091Y136551D02*
Y136198D01*
G01X405075Y139013D02*
X405065Y139379D01*
G01X405079Y138722D02*
X405075Y139013D01*
G01X405083Y138368D02*
X405079Y138722D01*
G01X405086Y137963D02*
X405083Y138368D01*
G01X405089Y137516D02*
X405086Y137963D01*
G01X405090Y137041D02*
X405089Y137516D01*
G01X405091Y136551D02*
X405090Y137041D01*
G01X406721Y140412D02*
X406711Y140365D01*
G01X406727Y140314D02*
X406721Y140412D01*
G01X406732Y140138D02*
X406727Y140314D01*
G01X406636Y137516D02*
X406634Y136551D01*
G01X406638Y137963D02*
X406636Y137516D01*
G01X406642Y138368D02*
X406638Y137963D01*
G01X406645Y138722D02*
X406642Y138368D01*
G01X406650Y139013D02*
X406645Y138722D01*
G01X406655Y139234D02*
X406650Y139013D01*
G01X406660Y139379D02*
X406655Y139234D01*
G01X406633Y135857D02*
X406634Y136551D01*
G01X406631Y135540D02*
X406633Y135857D01*
G01X406628Y135257D02*
X406631Y135540D01*
G01X406625Y135018D02*
X406628Y135257D01*
G01X406622Y134830D02*
X406625Y135018D01*
G01X406618Y134700D02*
X406622Y134830D01*
G01X406614Y134632D02*
X406618Y134700D01*
G01X406610Y134627D02*
X406614Y134632D01*
G01X406626Y137857D02*
X406623Y136570D01*
G01X406629Y138453D02*
X406626Y137857D01*
G01X406633Y138993D02*
X406629Y138453D01*
G01X406638Y139464D02*
X406633Y138993D01*
G01X406644Y139853D02*
X406638Y139464D01*
G01X406651Y140148D02*
X406644Y139853D01*
G01X406658Y140340D02*
X406651Y140148D01*
G01X406723Y141390D02*
X406708Y141327D01*
G01X406730Y141259D02*
X406723Y141390D01*
G01X406737Y141024D02*
X406730Y141259D01*
G01X401071Y145965D02*
X401082Y146012D01*
G01X401066Y146063D02*
X401071Y145965D01*
G01X401061Y146239D02*
X401066Y146063D01*
G01X401156Y148861D02*
X401158Y149826D01*
G01X401154Y148414D02*
X401156Y148861D01*
G01X401151Y148009D02*
X401154Y148414D01*
G01X401147Y147656D02*
X401151Y148009D01*
G01X401143Y147364D02*
X401147Y147656D01*
G01X401138Y147143D02*
X401143Y147364D01*
G01X401133Y146999D02*
X401138Y147143D01*
G01X401167Y148520D02*
X401169Y149807D01*
G01X401164Y147925D02*
X401167Y148520D01*
G01X401159Y147384D02*
X401164Y147925D01*
G01X401154Y146913D02*
X401159Y147384D01*
G01X401148Y146524D02*
X401154Y146913D01*
G01X401142Y146230D02*
X401148Y146524D01*
G01X401135Y146037D02*
X401142Y146230D01*
G01X401070Y144988D02*
X401084Y145050D01*
G01X401063Y145118D02*
X401070Y144988D01*
G01X401056Y145353D02*
X401063Y145118D01*
G01X402790Y144988D02*
X402804Y145353D01*
G01X402783Y144965D02*
X402790Y144988D01*
G01X402776Y145050D02*
X402783Y144965D01*
G01X402712Y146524D02*
X402725Y146037D01*
G01X402706Y146913D02*
X402712Y146524D01*
G01X402701Y147384D02*
X402706Y146913D01*
G01X402697Y147925D02*
X402701Y147384D01*
G01X402694Y148520D02*
X402697Y147925D01*
G01X402692Y149153D02*
X402694Y148520D01*
G01X402691Y149807D02*
X402692Y149153D01*
G01X402718Y147364D02*
X402728Y146999D01*
G01X402713Y147656D02*
X402718Y147364D01*
G01X402709Y148009D02*
X402713Y147656D01*
G01X402706Y148414D02*
X402709Y148009D01*
G01X402704Y148861D02*
X402706Y148414D01*
G01X402702Y149336D02*
X402704Y148861D01*
G01X402702Y149826D02*
Y149336D01*
G01X402789Y145965D02*
X402799Y146239D01*
G01X402784Y145948D02*
X402789Y145965D01*
G01X402778Y146012D02*
X402784Y145948D01*
G01X402789Y140412D02*
X402778Y140365D01*
G01X402794Y140314D02*
X402789Y140412D01*
G01X402799Y140138D02*
X402794Y140314D01*
G01X402704Y137516D02*
X402702Y136551D01*
G01X402706Y137963D02*
X402704Y137516D01*
G01X402709Y138368D02*
X402706Y137963D01*
G01X402713Y138722D02*
X402709Y138368D01*
G01X402718Y139013D02*
X402713Y138722D01*
G01X402722Y139234D02*
X402718Y139013D01*
G01X402728Y139379D02*
X402722Y139234D01*
G01X402694Y137857D02*
X402691Y136570D01*
G01X402697Y138453D02*
X402694Y137857D01*
G01X402701Y138993D02*
X402697Y138453D01*
G01X402706Y139464D02*
X402701Y138993D01*
G01X402712Y139853D02*
X402706Y139464D01*
G01X402718Y140148D02*
X402712Y139853D01*
G01X402725Y140340D02*
X402718Y140148D01*
G01X402790Y141390D02*
X402776Y141327D01*
G01X402797Y141259D02*
X402790Y141390D01*
G01X402804Y141024D02*
X402797Y141259D01*
G01X401070Y141390D02*
X401056Y141024D01*
G01X401077Y141412D02*
X401070Y141390D01*
G01X401084Y141327D02*
X401077Y141412D01*
G01X401148Y139853D02*
X401135Y140340D01*
G01X401154Y139464D02*
X401148Y139853D01*
G01X401159Y138993D02*
X401154Y139464D01*
G01X401164Y138453D02*
X401159Y138993D01*
G01X401167Y137857D02*
X401164Y138453D01*
G01X401169Y137224D02*
X401167Y137857D01*
G01X401169Y136570D02*
Y137224D01*
G01X401143Y139013D02*
X401133Y139379D01*
G01X401147Y138722D02*
X401143Y139013D01*
G01X401151Y138368D02*
X401147Y138722D01*
G01X401154Y137963D02*
X401151Y138368D01*
G01X401156Y137516D02*
X401154Y137963D01*
G01X401158Y137041D02*
X401156Y137516D01*
G01X401158Y136551D02*
Y137041D01*
G01X401071Y140412D02*
X401061Y140138D01*
G01X401077Y140429D02*
X401071Y140412D01*
G01X401082Y140365D02*
X401077Y140429D01*
G01X397139Y145965D02*
X397150Y146012D01*
G01X397133Y146063D02*
X397139Y145965D01*
G01X397128Y146239D02*
X397133Y146063D01*
G01X397224Y148861D02*
X397226Y149826D01*
G01X397222Y148414D02*
X397224Y148861D01*
G01X397219Y148009D02*
X397222Y148414D01*
G01X397215Y147656D02*
X397219Y148009D01*
G01X397210Y147364D02*
X397215Y147656D01*
G01X397205Y147143D02*
X397210Y147364D01*
G01X397200Y146999D02*
X397205Y147143D01*
G01X397228Y150521D02*
X397226Y149826D01*
G01X397229Y150838D02*
X397228Y150521D01*
G01X397232Y151120D02*
X397229Y150838D01*
G01X397235Y151359D02*
X397232Y151120D01*
G01X397238Y151547D02*
X397235Y151359D01*
G01X397242Y151677D02*
X397238Y151547D01*
G01X397246Y151746D02*
X397242Y151677D01*
G01X397250Y151750D02*
X397246Y151746D01*
G01X397234Y148520D02*
X397237Y149807D01*
G01X397231Y147925D02*
X397234Y148520D01*
G01X397227Y147384D02*
X397231Y147925D01*
G01X397222Y146913D02*
X397227Y147384D01*
G01X397216Y146524D02*
X397222Y146913D01*
G01X397210Y146230D02*
X397216Y146524D01*
G01X397203Y146037D02*
X397210Y146230D01*
G01X397138Y144988D02*
X397152Y145050D01*
G01X397130Y145118D02*
X397138Y144988D01*
G01X397124Y145353D02*
X397130Y145118D01*
G01X398858Y144988D02*
X398872Y145353D01*
G01X398851Y144965D02*
X398858Y144988D01*
G01X398843Y145050D02*
X398851Y144965D01*
G01X398779Y146524D02*
X398793Y146037D01*
G01X398774Y146913D02*
X398779Y146524D01*
G01X398768Y147384D02*
X398774Y146913D01*
G01X398764Y147925D02*
X398768Y147384D01*
G01X398761Y148520D02*
X398764Y147925D01*
G01X398759Y149153D02*
X398761Y148520D01*
G01X398758Y149807D02*
X398759Y149153D01*
G01X398754Y151677D02*
X398746Y151750D01*
G01X398757Y151547D02*
X398754Y151677D01*
G01X398761Y151359D02*
X398757Y151547D01*
G01X398764Y151120D02*
X398761Y151359D01*
G01X398766Y150838D02*
X398764Y151120D01*
G01X398768Y150521D02*
X398766Y150838D01*
G01X398769Y150180D02*
X398768Y150521D01*
G01X398769Y149826D02*
Y150180D01*
G01X398785Y147364D02*
X398795Y146999D01*
G01X398781Y147656D02*
X398785Y147364D01*
G01X398777Y148009D02*
X398781Y147656D01*
G01X398774Y148414D02*
X398777Y148009D01*
G01X398771Y148861D02*
X398774Y148414D01*
G01X398770Y149336D02*
X398771Y148861D01*
G01X398769Y149826D02*
X398770Y149336D01*
G01X398857Y145965D02*
X398867Y146239D01*
G01X398851Y145948D02*
X398857Y145965D01*
G01X398846Y146012D02*
X398851Y145948D01*
G01X398847Y140412D02*
X398836Y140365D01*
G01X398853Y140314D02*
X398847Y140412D01*
G01X398858Y140138D02*
X398853Y140314D01*
G01X398762Y137516D02*
X398760Y136551D01*
G01X398764Y137963D02*
X398762Y137516D01*
G01X398768Y138368D02*
X398764Y137963D01*
G01X398771Y138722D02*
X398768Y138368D01*
G01X398776Y139013D02*
X398771Y138722D01*
G01X398781Y139234D02*
X398776Y139013D01*
G01X398786Y139379D02*
X398781Y139234D01*
G01X398759Y135857D02*
X398760Y136551D01*
G01X398757Y135540D02*
X398759Y135857D01*
G01X398754Y135257D02*
X398757Y135540D01*
G01X398751Y135018D02*
X398754Y135257D01*
G01X398748Y134830D02*
X398751Y135018D01*
G01X398744Y134700D02*
X398748Y134830D01*
G01X398740Y134632D02*
X398744Y134700D01*
G01X398736Y134627D02*
X398740Y134632D01*
G01X398752Y137857D02*
X398749Y136570D01*
G01X398755Y138453D02*
X398752Y137857D01*
G01X398759Y138993D02*
X398755Y138453D01*
G01X398764Y139464D02*
X398759Y138993D01*
G01X398770Y139853D02*
X398764Y139464D01*
G01X398777Y140148D02*
X398770Y139853D01*
G01X398784Y140340D02*
X398777Y140148D01*
G01X398849Y141390D02*
X398834Y141327D01*
G01X398856Y141259D02*
X398849Y141390D01*
G01X398863Y141024D02*
X398856Y141259D01*
G01X397128Y141390D02*
X397114Y141024D01*
G01X397135Y141412D02*
X397128Y141390D01*
G01X397143Y141327D02*
X397135Y141412D01*
G01X397207Y139853D02*
X397193Y140340D01*
G01X397213Y139464D02*
X397207Y139853D01*
G01X397218Y138993D02*
X397213Y139464D01*
G01X397222Y138453D02*
X397218Y138993D01*
G01X397225Y137857D02*
X397222Y138453D01*
G01X397227Y137224D02*
X397225Y137857D01*
G01X397228Y136570D02*
X397227Y137224D01*
G01X397233Y134700D02*
X397240Y134627D01*
G01X397229Y134830D02*
X397233Y134700D01*
G01X397225Y135018D02*
X397229Y134830D01*
G01X397223Y135257D02*
X397225Y135018D01*
G01X397220Y135540D02*
X397223Y135257D01*
G01X397218Y135857D02*
X397220Y135540D01*
G01X397217Y136198D02*
X397218Y135857D01*
G01X397217Y136551D02*
Y136198D01*
G01X397201Y139013D02*
X397191Y139379D01*
G01X397205Y138722D02*
X397201Y139013D01*
G01X397209Y138368D02*
X397205Y138722D01*
G01X397212Y137963D02*
X397209Y138368D01*
G01X397215Y137516D02*
X397212Y137963D01*
G01X397216Y137041D02*
X397215Y137516D01*
G01X397217Y136551D02*
X397216Y137041D01*
G01X397129Y140412D02*
X397119Y140138D01*
G01X397135Y140429D02*
X397129Y140412D01*
G01X397140Y140365D02*
X397135Y140429D01*
G01X393197Y145965D02*
X393208Y146012D01*
G01X393192Y146063D02*
X393197Y145965D01*
G01X393187Y146239D02*
X393192Y146063D01*
G01X393282Y148861D02*
X393284Y149826D01*
G01X393280Y148414D02*
X393282Y148861D01*
G01X393277Y148009D02*
X393280Y148414D01*
G01X393273Y147656D02*
X393277Y148009D01*
G01X393269Y147364D02*
X393273Y147656D01*
G01X393264Y147143D02*
X393269Y147364D01*
G01X393258Y146999D02*
X393264Y147143D01*
G01X393293Y148520D02*
X393295Y149807D01*
G01X393290Y147925D02*
X393293Y148520D01*
G01X393285Y147384D02*
X393290Y147925D01*
G01X393280Y146913D02*
X393285Y147384D01*
G01X393274Y146524D02*
X393280Y146913D01*
G01X393268Y146230D02*
X393274Y146524D01*
G01X393261Y146037D02*
X393268Y146230D01*
G01X393196Y144988D02*
X393210Y145050D01*
G01X393189Y145118D02*
X393196Y144988D01*
G01X393182Y145353D02*
X393189Y145118D01*
G01X394916Y144988D02*
X394930Y145353D01*
G01X394909Y144965D02*
X394916Y144988D01*
G01X394902Y145050D02*
X394909Y144965D01*
G01X394838Y146524D02*
X394851Y146037D01*
G01X394832Y146913D02*
X394838Y146524D01*
G01X394827Y147384D02*
X394832Y146913D01*
G01X394823Y147925D02*
X394827Y147384D01*
G01X394819Y148520D02*
X394823Y147925D01*
G01X394818Y149153D02*
X394819Y148520D01*
G01X394817Y149807D02*
X394818Y149153D01*
G01X394844Y147364D02*
X394854Y146999D01*
G01X394839Y147656D02*
X394844Y147364D01*
G01X394835Y148009D02*
X394839Y147656D01*
G01X394832Y148414D02*
X394835Y148009D01*
G01X394830Y148861D02*
X394832Y148414D01*
G01X394828Y149336D02*
X394830Y148861D01*
G01X394828Y149826D02*
Y149336D01*
G01X394915Y145965D02*
X394925Y146239D01*
G01X394910Y145948D02*
X394915Y145965D01*
G01X394904Y146012D02*
X394910Y145948D01*
G01X394915Y140412D02*
X394904Y140365D01*
G01X394920Y140314D02*
X394915Y140412D01*
G01X394925Y140138D02*
X394920Y140314D01*
G01X394830Y137516D02*
X394828Y136551D01*
G01X394832Y137963D02*
X394830Y137516D01*
G01X394835Y138368D02*
X394832Y137963D01*
G01X394839Y138722D02*
X394835Y138368D01*
G01X394844Y139013D02*
X394839Y138722D01*
G01X394848Y139234D02*
X394844Y139013D01*
G01X394854Y139379D02*
X394848Y139234D01*
G01X394819Y137857D02*
X394817Y136570D01*
G01X394823Y138453D02*
X394819Y137857D01*
G01X394827Y138993D02*
X394823Y138453D01*
G01X394832Y139464D02*
X394827Y138993D01*
G01X394838Y139853D02*
X394832Y139464D01*
G01X394844Y140148D02*
X394838Y139853D01*
G01X394851Y140340D02*
X394844Y140148D01*
G01X394916Y141390D02*
X394902Y141327D01*
G01X394923Y141259D02*
X394916Y141390D01*
G01X394930Y141024D02*
X394923Y141259D01*
G01X393196Y141390D02*
X393182Y141024D01*
G01X393203Y141412D02*
X393196Y141390D01*
G01X393210Y141327D02*
X393203Y141412D01*
G01X393274Y139853D02*
X393261Y140340D01*
G01X393280Y139464D02*
X393274Y139853D01*
G01X393285Y138993D02*
X393280Y139464D01*
G01X393290Y138453D02*
X393285Y138993D01*
G01X393293Y137857D02*
X393290Y138453D01*
G01X393295Y137224D02*
X393293Y137857D01*
G01X393295Y136570D02*
Y137224D01*
G01X393269Y139013D02*
X393258Y139379D01*
G01X393273Y138722D02*
X393269Y139013D01*
G01X393277Y138368D02*
X393273Y138722D01*
G01X393280Y137963D02*
X393277Y138368D01*
G01X393282Y137516D02*
X393280Y137963D01*
G01X393284Y137041D02*
X393282Y137516D01*
G01X393284Y136551D02*
Y137041D01*
G01X393197Y140412D02*
X393187Y140138D01*
G01X393203Y140429D02*
X393197Y140412D01*
G01X393208Y140365D02*
X393203Y140429D01*
G01X389265Y145965D02*
X389276Y146012D01*
G01X389259Y146063D02*
X389265Y145965D01*
G01X389254Y146239D02*
X389259Y146063D01*
G01X389350Y148861D02*
X389352Y149826D01*
G01X389348Y148414D02*
X389350Y148861D01*
G01X389345Y148009D02*
X389348Y148414D01*
G01X389341Y147656D02*
X389345Y148009D01*
G01X389336Y147364D02*
X389341Y147656D01*
G01X389331Y147143D02*
X389336Y147364D01*
G01X389326Y146999D02*
X389331Y147143D01*
G01X389354Y150521D02*
X389352Y149826D01*
G01X389355Y150838D02*
X389354Y150521D01*
G01X389358Y151120D02*
X389355Y150838D01*
G01X389361Y151359D02*
X389358Y151120D01*
G01X389364Y151547D02*
X389361Y151359D01*
G01X389368Y151677D02*
X389364Y151547D01*
G01X389372Y151746D02*
X389368Y151677D01*
G01X389376Y151750D02*
X389372Y151746D01*
G01X389360Y148520D02*
X389363Y149807D01*
G01X389357Y147925D02*
X389360Y148520D01*
G01X389353Y147384D02*
X389357Y147925D01*
G01X389348Y146913D02*
X389353Y147384D01*
G01X389342Y146524D02*
X389348Y146913D01*
G01X389335Y146230D02*
X389342Y146524D01*
G01X389328Y146037D02*
X389335Y146230D01*
G01X389263Y144988D02*
X389278Y145050D01*
G01X389256Y145118D02*
X389263Y144988D01*
G01X389250Y145353D02*
X389256Y145118D01*
G01X390984Y144988D02*
X390998Y145353D01*
G01X390977Y144965D02*
X390984Y144988D01*
G01X390969Y145050D02*
X390977Y144965D01*
G01X390905Y146524D02*
X390919Y146037D01*
G01X390900Y146913D02*
X390905Y146524D01*
G01X390894Y147384D02*
X390900Y146913D01*
G01X390890Y147925D02*
X390894Y147384D01*
G01X390887Y148520D02*
X390890Y147925D01*
G01X390885Y149153D02*
X390887Y148520D01*
G01X390884Y149807D02*
X390885Y149153D01*
G01X390880Y151677D02*
X390872Y151750D01*
G01X390883Y151547D02*
X390880Y151677D01*
G01X390887Y151359D02*
X390883Y151547D01*
G01X390890Y151120D02*
X390887Y151359D01*
G01X390892Y150838D02*
X390890Y151120D01*
G01X390894Y150521D02*
X390892Y150838D01*
G01X390895Y150180D02*
X390894Y150521D01*
G01X390895Y149826D02*
Y150180D01*
G01X390911Y147364D02*
X390921Y146999D01*
G01X390907Y147656D02*
X390911Y147364D01*
G01X390903Y148009D02*
X390907Y147656D01*
G01X390900Y148414D02*
X390903Y148009D01*
G01X390897Y148861D02*
X390900Y148414D01*
G01X390896Y149336D02*
X390897Y148861D01*
G01X390895Y149826D02*
X390896Y149336D01*
G01X390983Y145965D02*
X390993Y146239D01*
G01X390977Y145948D02*
X390983Y145965D01*
G01X390972Y146012D02*
X390977Y145948D01*
G01X390973Y140412D02*
X390962Y140365D01*
G01X390979Y140314D02*
X390973Y140412D01*
G01X390984Y140138D02*
X390979Y140314D01*
G01X390888Y137516D02*
X390886Y136551D01*
G01X390890Y137963D02*
X390888Y137516D01*
G01X390894Y138368D02*
X390890Y137963D01*
G01X390897Y138722D02*
X390894Y138368D01*
G01X390902Y139013D02*
X390897Y138722D01*
G01X390907Y139234D02*
X390902Y139013D01*
G01X390912Y139379D02*
X390907Y139234D01*
G01X390885Y135857D02*
X390886Y136551D01*
G01X390883Y135540D02*
X390885Y135857D01*
G01X390880Y135257D02*
X390883Y135540D01*
G01X390877Y135018D02*
X390880Y135257D01*
G01X390874Y134830D02*
X390877Y135018D01*
G01X390870Y134700D02*
X390874Y134830D01*
G01X390866Y134632D02*
X390870Y134700D01*
G01X390862Y134627D02*
X390866Y134632D01*
G01X390878Y137857D02*
X390875Y136570D01*
G01X390881Y138453D02*
X390878Y137857D01*
G01X390885Y138993D02*
X390881Y138453D01*
G01X390890Y139464D02*
X390885Y138993D01*
G01X390896Y139853D02*
X390890Y139464D01*
G01X390903Y140148D02*
X390896Y139853D01*
G01X390910Y140340D02*
X390903Y140148D01*
G01X390975Y141390D02*
X390960Y141327D01*
G01X390982Y141259D02*
X390975Y141390D01*
G01X390989Y141024D02*
X390982Y141259D01*
G01X389254Y141390D02*
X389240Y141024D01*
G01X389261Y141412D02*
X389254Y141390D01*
G01X389269Y141327D02*
X389261Y141412D01*
G01X389333Y139853D02*
X389319Y140340D01*
G01X389339Y139464D02*
X389333Y139853D01*
G01X389344Y138993D02*
X389339Y139464D01*
G01X389348Y138453D02*
X389344Y138993D01*
G01X389351Y137857D02*
X389348Y138453D01*
G01X389353Y137224D02*
X389351Y137857D01*
G01X389354Y136570D02*
X389353Y137224D01*
G01X389359Y134700D02*
X389366Y134627D01*
G01X389355Y134830D02*
X389359Y134700D01*
G01X389351Y135018D02*
X389355Y134830D01*
G01X389349Y135257D02*
X389351Y135018D01*
G01X389346Y135540D02*
X389349Y135257D01*
G01X389344Y135857D02*
X389346Y135540D01*
G01X389343Y136198D02*
X389344Y135857D01*
G01X389343Y136551D02*
Y136198D01*
G01X389327Y139013D02*
X389317Y139379D01*
G01X389331Y138722D02*
X389327Y139013D01*
G01X389335Y138368D02*
X389331Y138722D01*
G01X389338Y137963D02*
X389335Y138368D01*
G01X389341Y137516D02*
X389338Y137963D01*
G01X389342Y137041D02*
X389341Y137516D01*
G01X389343Y136551D02*
X389342Y137041D01*
G01X389255Y140412D02*
X389245Y140138D01*
G01X389261Y140429D02*
X389255Y140412D01*
G01X389266Y140365D02*
X389261Y140429D01*
G01X385323Y145965D02*
X385334Y146012D01*
G01X385318Y146063D02*
X385323Y145965D01*
G01X385313Y146239D02*
X385318Y146063D01*
G01X385408Y148861D02*
X385410Y149826D01*
G01X385406Y148414D02*
X385408Y148861D01*
G01X385403Y148009D02*
X385406Y148414D01*
G01X385399Y147656D02*
X385403Y148009D01*
G01X385395Y147364D02*
X385399Y147656D01*
G01X385390Y147143D02*
X385395Y147364D01*
G01X385384Y146999D02*
X385390Y147143D01*
G01X385419Y148520D02*
X385421Y149807D01*
G01X385416Y147925D02*
X385419Y148520D01*
G01X385411Y147384D02*
X385416Y147925D01*
G01X385406Y146913D02*
X385411Y147384D01*
G01X385400Y146524D02*
X385406Y146913D01*
G01X385394Y146230D02*
X385400Y146524D01*
G01X385387Y146037D02*
X385394Y146230D01*
G01X385322Y144988D02*
X385336Y145050D01*
G01X385315Y145118D02*
X385322Y144988D01*
G01X385308Y145353D02*
X385315Y145118D01*
G01X387041Y145965D02*
X387051Y146239D01*
G01X387036Y145948D02*
X387041Y145965D01*
G01X387030Y146012D02*
X387036Y145948D01*
G01X387042Y144988D02*
X387056Y145353D01*
G01X387035Y144965D02*
X387042Y144988D01*
G01X387028Y145050D02*
X387035Y144965D01*
G01X386964Y146524D02*
X386977Y146037D01*
G01X386958Y146913D02*
X386964Y146524D01*
G01X386953Y147384D02*
X386958Y146913D01*
G01X386949Y147925D02*
X386953Y147384D01*
G01X386945Y148520D02*
X386949Y147925D01*
G01X386944Y149153D02*
X386945Y148520D01*
G01X386943Y149807D02*
X386944Y149153D01*
G01X386969Y147364D02*
X386980Y146999D01*
G01X386965Y147656D02*
X386969Y147364D01*
G01X386961Y148009D02*
X386965Y147656D01*
G01X386958Y148414D02*
X386961Y148009D01*
G01X386956Y148861D02*
X386958Y148414D01*
G01X386954Y149336D02*
X386956Y148861D01*
G01X386954Y149826D02*
Y149336D01*
G01X387041Y140412D02*
X387030Y140365D01*
G01X387046Y140314D02*
X387041Y140412D01*
G01X387051Y140138D02*
X387046Y140314D01*
G01X386956Y137516D02*
X386954Y136551D01*
G01X386958Y137963D02*
X386956Y137516D01*
G01X386961Y138368D02*
X386958Y137963D01*
G01X386965Y138722D02*
X386961Y138368D01*
G01X386969Y139013D02*
X386965Y138722D01*
G01X386974Y139234D02*
X386969Y139013D01*
G01X386980Y139379D02*
X386974Y139234D01*
G01X386945Y137857D02*
X386943Y136570D01*
G01X386949Y138453D02*
X386945Y137857D01*
G01X386953Y138993D02*
X386949Y138453D01*
G01X386958Y139464D02*
X386953Y138993D01*
G01X386964Y139853D02*
X386958Y139464D01*
G01X386970Y140148D02*
X386964Y139853D01*
G01X386977Y140340D02*
X386970Y140148D01*
G01X387042Y141390D02*
X387028Y141327D01*
G01X387049Y141259D02*
X387042Y141390D01*
G01X387056Y141024D02*
X387049Y141259D01*
G01X385323Y140412D02*
X385313Y140138D01*
G01X385329Y140429D02*
X385323Y140412D01*
G01X385334Y140365D02*
X385329Y140429D01*
G01X385322Y141390D02*
X385308Y141024D01*
G01X385329Y141412D02*
X385322Y141390D01*
G01X385336Y141327D02*
X385329Y141412D01*
G01X385400Y139853D02*
X385387Y140340D01*
G01X385406Y139464D02*
X385400Y139853D01*
G01X385411Y138993D02*
X385406Y139464D01*
G01X385416Y138453D02*
X385411Y138993D01*
G01X385419Y137857D02*
X385416Y138453D01*
G01X385421Y137224D02*
X385419Y137857D01*
G01X385421Y136570D02*
Y137224D01*
G01X385395Y139013D02*
X385384Y139379D01*
G01X385399Y138722D02*
X385395Y139013D01*
G01X385403Y138368D02*
X385399Y138722D01*
G01X385406Y137963D02*
X385403Y138368D01*
G01X385408Y137516D02*
X385406Y137963D01*
G01X385410Y137041D02*
X385408Y137516D01*
G01X385410Y136551D02*
Y137041D01*
G01X383109Y145965D02*
X383119Y146239D01*
G01X383103Y145948D02*
X383109Y145965D01*
G01X383098Y146012D02*
X383103Y145948D01*
G01X383110Y144988D02*
X383124Y145353D01*
G01X383103Y144965D02*
X383110Y144988D01*
G01X383095Y145050D02*
X383103Y144965D01*
G01X383031Y146524D02*
X383045Y146037D01*
G01X383026Y146913D02*
X383031Y146524D01*
G01X383020Y147384D02*
X383026Y146913D01*
G01X383016Y147925D02*
X383020Y147384D01*
G01X383013Y148520D02*
X383016Y147925D01*
G01X383011Y149153D02*
X383013Y148520D01*
G01X383010Y149807D02*
X383011Y149153D01*
G01X383006Y151677D02*
X382998Y151750D01*
G01X383009Y151547D02*
X383006Y151677D01*
G01X383013Y151359D02*
X383009Y151547D01*
G01X383016Y151120D02*
X383013Y151359D01*
G01X383018Y150838D02*
X383016Y151120D01*
G01X383020Y150521D02*
X383018Y150838D01*
G01X383021Y150180D02*
X383020Y150521D01*
G01X383021Y149826D02*
Y150180D01*
G01X383037Y147364D02*
X383047Y146999D01*
G01X383033Y147656D02*
X383037Y147364D01*
G01X383029Y148009D02*
X383033Y147656D01*
G01X383026Y148414D02*
X383029Y148009D01*
G01X383023Y148861D02*
X383026Y148414D01*
G01X383022Y149336D02*
X383023Y148861D01*
G01X383021Y149826D02*
X383022Y149336D01*
G01X381391Y145965D02*
X381402Y146012D01*
G01X381385Y146063D02*
X381391Y145965D01*
G01X381380Y146239D02*
X381385Y146063D01*
G01X381476Y148861D02*
X381478Y149826D01*
G01X381474Y148414D02*
X381476Y148861D01*
G01X381471Y148009D02*
X381474Y148414D01*
G01X381467Y147656D02*
X381471Y148009D01*
G01X381462Y147364D02*
X381467Y147656D01*
G01X381457Y147143D02*
X381462Y147364D01*
G01X381452Y146999D02*
X381457Y147143D01*
G01X381480Y150521D02*
X381478Y149826D01*
G01X381481Y150838D02*
X381480Y150521D01*
G01X381484Y151120D02*
X381481Y150838D01*
G01X381487Y151359D02*
X381484Y151120D01*
G01X381490Y151547D02*
X381487Y151359D01*
G01X381494Y151677D02*
X381490Y151547D01*
G01X381498Y151746D02*
X381494Y151677D01*
G01X381502Y151750D02*
X381498Y151746D01*
G01X381486Y148520D02*
X381489Y149807D01*
G01X381483Y147925D02*
X381486Y148520D01*
G01X381479Y147384D02*
X381483Y147925D01*
G01X381474Y146913D02*
X381479Y147384D01*
G01X381468Y146524D02*
X381474Y146913D01*
G01X381461Y146230D02*
X381468Y146524D01*
G01X381454Y146037D02*
X381461Y146230D01*
G01X381389Y144988D02*
X381404Y145050D01*
G01X381382Y145118D02*
X381389Y144988D01*
G01X381376Y145353D02*
X381382Y145118D01*
G01X381381Y140412D02*
X381371Y140138D01*
G01X381387Y140429D02*
X381381Y140412D01*
G01X381392Y140365D02*
X381387Y140429D01*
G01X381380Y141390D02*
X381366Y141024D01*
G01X381387Y141412D02*
X381380Y141390D01*
G01X381395Y141327D02*
X381387Y141412D01*
G01X381459Y139853D02*
X381445Y140340D01*
G01X381465Y139464D02*
X381459Y139853D01*
G01X381470Y138993D02*
X381465Y139464D01*
G01X381474Y138453D02*
X381470Y138993D01*
G01X381477Y137857D02*
X381474Y138453D01*
G01X381479Y137224D02*
X381477Y137857D01*
G01X381480Y136570D02*
X381479Y137224D01*
G01X381484Y134700D02*
X381492Y134627D01*
G01X381481Y134830D02*
X381484Y134700D01*
G01X381477Y135018D02*
X381481Y134830D01*
G01X381474Y135257D02*
X381477Y135018D01*
G01X381472Y135540D02*
X381474Y135257D01*
G01X381470Y135857D02*
X381472Y135540D01*
G01X381469Y136198D02*
X381470Y135857D01*
G01X381469Y136551D02*
Y136198D01*
G01X381453Y139013D02*
X381443Y139379D01*
G01X381457Y138722D02*
X381453Y139013D01*
G01X381461Y138368D02*
X381457Y138722D01*
G01X381464Y137963D02*
X381461Y138368D01*
G01X381467Y137516D02*
X381464Y137963D01*
G01X381468Y137041D02*
X381467Y137516D01*
G01X381469Y136551D02*
X381468Y137041D01*
G01X383099Y140412D02*
X383088Y140365D01*
G01X383105Y140314D02*
X383099Y140412D01*
G01X383110Y140138D02*
X383105Y140314D01*
G01X383014Y137516D02*
X383012Y136551D01*
G01X383016Y137963D02*
X383014Y137516D01*
G01X383020Y138368D02*
X383016Y137963D01*
G01X383023Y138722D02*
X383020Y138368D01*
G01X383028Y139013D02*
X383023Y138722D01*
G01X383033Y139234D02*
X383028Y139013D01*
G01X383038Y139379D02*
X383033Y139234D01*
G01X383010Y135857D02*
X383012Y136551D01*
G01X383009Y135540D02*
X383010Y135857D01*
G01X383006Y135257D02*
X383009Y135540D01*
G01X383003Y135018D02*
X383006Y135257D01*
G01X383000Y134830D02*
X383003Y135018D01*
G01X382996Y134700D02*
X383000Y134830D01*
G01X382992Y134632D02*
X382996Y134700D01*
G01X382988Y134627D02*
X382992Y134632D01*
G01X383004Y137857D02*
X383001Y136570D01*
G01X383007Y138453D02*
X383004Y137857D01*
G01X383011Y138993D02*
X383007Y138453D01*
G01X383016Y139464D02*
X383011Y138993D01*
G01X383022Y139853D02*
X383016Y139464D01*
G01X383029Y140148D02*
X383022Y139853D01*
G01X383036Y140340D02*
X383029Y140148D01*
G01X383101Y141390D02*
X383086Y141327D01*
G01X383108Y141259D02*
X383101Y141390D01*
G01X383115Y141024D02*
X383108Y141259D01*
G01X377449Y145965D02*
X377460Y146012D01*
G01X377444Y146063D02*
X377449Y145965D01*
G01X377439Y146239D02*
X377444Y146063D01*
G01X377534Y148861D02*
X377536Y149826D01*
G01X377532Y148414D02*
X377534Y148861D01*
G01X377529Y148009D02*
X377532Y148414D01*
G01X377525Y147656D02*
X377529Y148009D01*
G01X377521Y147364D02*
X377525Y147656D01*
G01X377516Y147143D02*
X377521Y147364D01*
G01X377510Y146999D02*
X377516Y147143D01*
G01X377545Y148520D02*
X377547Y149807D01*
G01X377542Y147925D02*
X377545Y148520D01*
G01X377537Y147384D02*
X377542Y147925D01*
G01X377532Y146913D02*
X377537Y147384D01*
G01X377526Y146524D02*
X377532Y146913D01*
G01X377520Y146230D02*
X377526Y146524D01*
G01X377513Y146037D02*
X377520Y146230D01*
G01X377448Y144988D02*
X377462Y145050D01*
G01X377441Y145118D02*
X377448Y144988D01*
G01X377434Y145353D02*
X377441Y145118D01*
G01X379167Y145965D02*
X379177Y146239D01*
G01X379162Y145948D02*
X379167Y145965D01*
G01X379156Y146012D02*
X379162Y145948D01*
G01X379168Y144988D02*
X379182Y145353D01*
G01X379161Y144965D02*
X379168Y144988D01*
G01X379154Y145050D02*
X379161Y144965D01*
G01X379090Y146524D02*
X379103Y146037D01*
G01X379084Y146913D02*
X379090Y146524D01*
G01X379079Y147384D02*
X379084Y146913D01*
G01X379075Y147925D02*
X379079Y147384D01*
G01X379071Y148520D02*
X379075Y147925D01*
G01X379070Y149153D02*
X379071Y148520D01*
G01X379069Y149807D02*
X379070Y149153D01*
G01X379095Y147364D02*
X379106Y146999D01*
G01X379091Y147656D02*
X379095Y147364D01*
G01X379087Y148009D02*
X379091Y147656D01*
G01X379084Y148414D02*
X379087Y148009D01*
G01X379082Y148861D02*
X379084Y148414D01*
G01X379080Y149336D02*
X379082Y148861D01*
G01X379080Y149826D02*
Y149336D01*
G01X379167Y140412D02*
X379156Y140365D01*
G01X379172Y140314D02*
X379167Y140412D01*
G01X379177Y140138D02*
X379172Y140314D01*
G01X379082Y137516D02*
X379080Y136551D01*
G01X379084Y137963D02*
X379082Y137516D01*
G01X379087Y138368D02*
X379084Y137963D01*
G01X379091Y138722D02*
X379087Y138368D01*
G01X379095Y139013D02*
X379091Y138722D01*
G01X379100Y139234D02*
X379095Y139013D01*
G01X379106Y139379D02*
X379100Y139234D01*
G01X379071Y137857D02*
X379069Y136570D01*
G01X379075Y138453D02*
X379071Y137857D01*
G01X379079Y138993D02*
X379075Y138453D01*
G01X379084Y139464D02*
X379079Y138993D01*
G01X379090Y139853D02*
X379084Y139464D01*
G01X379096Y140148D02*
X379090Y139853D01*
G01X379103Y140340D02*
X379096Y140148D01*
G01X379168Y141390D02*
X379154Y141327D01*
G01X379175Y141259D02*
X379168Y141390D01*
G01X379182Y141024D02*
X379175Y141259D01*
G01X377449Y140412D02*
X377439Y140138D01*
G01X377455Y140429D02*
X377449Y140412D01*
G01X377460Y140365D02*
X377455Y140429D01*
G01X377448Y141390D02*
X377434Y141024D01*
G01X377455Y141412D02*
X377448Y141390D01*
G01X377462Y141327D02*
X377455Y141412D01*
G01X377526Y139853D02*
X377513Y140340D01*
G01X377532Y139464D02*
X377526Y139853D01*
G01X377537Y138993D02*
X377532Y139464D01*
G01X377542Y138453D02*
X377537Y138993D01*
G01X377545Y137857D02*
X377542Y138453D01*
G01X377547Y137224D02*
X377545Y137857D01*
G01X377547Y136570D02*
Y137224D01*
G01X377521Y139013D02*
X377510Y139379D01*
G01X377525Y138722D02*
X377521Y139013D01*
G01X377529Y138368D02*
X377525Y138722D01*
G01X377532Y137963D02*
X377529Y138368D01*
G01X377534Y137516D02*
X377532Y137963D01*
G01X377536Y137041D02*
X377534Y137516D01*
G01X377536Y136551D02*
Y137041D01*
G01X375235Y145965D02*
X375245Y146239D01*
G01X375229Y145948D02*
X375235Y145965D01*
G01X375224Y146012D02*
X375229Y145948D01*
G01X375236Y144988D02*
X375250Y145353D01*
G01X375229Y144965D02*
X375236Y144988D01*
G01X375221Y145050D02*
X375229Y144965D01*
G01X375157Y146524D02*
X375171Y146037D01*
G01X375151Y146913D02*
X375157Y146524D01*
G01X375146Y147384D02*
X375151Y146913D01*
G01X375142Y147925D02*
X375146Y147384D01*
G01X375139Y148520D02*
X375142Y147925D01*
G01X375137Y149153D02*
X375139Y148520D01*
G01X375136Y149807D02*
X375137Y149153D01*
G01X375132Y151677D02*
X375124Y151750D01*
G01X375135Y151547D02*
X375132Y151677D01*
G01X375139Y151359D02*
X375135Y151547D01*
G01X375142Y151120D02*
X375139Y151359D01*
G01X375144Y150838D02*
X375142Y151120D01*
G01X375146Y150521D02*
X375144Y150838D01*
G01X375147Y150180D02*
X375146Y150521D01*
G01X375147Y149826D02*
Y150180D01*
G01X375163Y147364D02*
X375173Y146999D01*
G01X375159Y147656D02*
X375163Y147364D01*
G01X375155Y148009D02*
X375159Y147656D01*
G01X375152Y148414D02*
X375155Y148009D01*
G01X375149Y148861D02*
X375152Y148414D01*
G01X375148Y149336D02*
X375149Y148861D01*
G01X375147Y149826D02*
X375148Y149336D01*
G01X373517Y145965D02*
X373528Y146012D01*
G01X373511Y146063D02*
X373517Y145965D01*
G01X373506Y146239D02*
X373511Y146063D01*
G01X373602Y148861D02*
X373604Y149826D01*
G01X373600Y148414D02*
X373602Y148861D01*
G01X373597Y148009D02*
X373600Y148414D01*
G01X373593Y147656D02*
X373597Y148009D01*
G01X373588Y147364D02*
X373593Y147656D01*
G01X373583Y147143D02*
X373588Y147364D01*
G01X373578Y146999D02*
X373583Y147143D01*
G01X373606Y150521D02*
X373604Y149826D01*
G01X373607Y150838D02*
X373606Y150521D01*
G01X373610Y151120D02*
X373607Y150838D01*
G01X373613Y151359D02*
X373610Y151120D01*
G01X373616Y151547D02*
X373613Y151359D01*
G01X373620Y151677D02*
X373616Y151547D01*
G01X373624Y151746D02*
X373620Y151677D01*
G01X373628Y151750D02*
X373624Y151746D01*
G01X373612Y148520D02*
X373615Y149807D01*
G01X373609Y147925D02*
X373612Y148520D01*
G01X373605Y147384D02*
X373609Y147925D01*
G01X373600Y146913D02*
X373605Y147384D01*
G01X373594Y146524D02*
X373600Y146913D01*
G01X373587Y146230D02*
X373594Y146524D01*
G01X373580Y146037D02*
X373587Y146230D01*
G01X373515Y144988D02*
X373530Y145050D01*
G01X373508Y145118D02*
X373515Y144988D01*
G01X373502Y145353D02*
X373508Y145118D01*
G01X373507Y140412D02*
X373497Y140138D01*
G01X373513Y140429D02*
X373507Y140412D01*
G01X373518Y140365D02*
X373513Y140429D01*
G01X373506Y141390D02*
X373492Y141024D01*
G01X373513Y141412D02*
X373506Y141390D01*
G01X373521Y141327D02*
X373513Y141412D01*
G01X373585Y139853D02*
X373571Y140340D01*
G01X373591Y139464D02*
X373585Y139853D01*
G01X373596Y138993D02*
X373591Y139464D01*
G01X373600Y138453D02*
X373596Y138993D01*
G01X373603Y137857D02*
X373600Y138453D01*
G01X373605Y137224D02*
X373603Y137857D01*
G01X373606Y136570D02*
X373605Y137224D01*
G01X373610Y134700D02*
X373618Y134627D01*
G01X373607Y134830D02*
X373610Y134700D01*
G01X373603Y135018D02*
X373607Y134830D01*
G01X373600Y135257D02*
X373603Y135018D01*
G01X373598Y135540D02*
X373600Y135257D01*
G01X373596Y135857D02*
X373598Y135540D01*
G01X373595Y136198D02*
X373596Y135857D01*
G01X373595Y136551D02*
Y136198D01*
G01X373579Y139013D02*
X373569Y139379D01*
G01X373583Y138722D02*
X373579Y139013D01*
G01X373587Y138368D02*
X373583Y138722D01*
G01X373590Y137963D02*
X373587Y138368D01*
G01X373593Y137516D02*
X373590Y137963D01*
G01X373594Y137041D02*
X373593Y137516D01*
G01X373595Y136551D02*
X373594Y137041D01*
G01X375225Y140412D02*
X375214Y140365D01*
G01X375231Y140314D02*
X375225Y140412D01*
G01X375236Y140138D02*
X375231Y140314D01*
G01X375140Y137516D02*
X375138Y136551D01*
G01X375142Y137963D02*
X375140Y137516D01*
G01X375146Y138368D02*
X375142Y137963D01*
G01X375149Y138722D02*
X375146Y138368D01*
G01X375154Y139013D02*
X375149Y138722D01*
G01X375159Y139234D02*
X375154Y139013D01*
G01X375164Y139379D02*
X375159Y139234D01*
G01X375136Y135857D02*
X375138Y136551D01*
G01X375135Y135540D02*
X375136Y135857D01*
G01X375132Y135257D02*
X375135Y135540D01*
G01X375129Y135018D02*
X375132Y135257D01*
G01X375126Y134830D02*
X375129Y135018D01*
G01X375122Y134700D02*
X375126Y134830D01*
G01X375118Y134632D02*
X375122Y134700D01*
G01X375114Y134627D02*
X375118Y134632D01*
G01X375130Y137857D02*
X375127Y136570D01*
G01X375133Y138453D02*
X375130Y137857D01*
G01X375137Y138993D02*
X375133Y138453D01*
G01X375142Y139464D02*
X375137Y138993D01*
G01X375148Y139853D02*
X375142Y139464D01*
G01X375155Y140148D02*
X375148Y139853D01*
G01X375162Y140340D02*
X375155Y140148D01*
G01X375227Y141390D02*
X375212Y141327D01*
G01X375234Y141259D02*
X375227Y141390D01*
G01X375241Y141024D02*
X375234Y141259D01*
G01X369575Y145965D02*
X369586Y146012D01*
G01X369570Y146063D02*
X369575Y145965D01*
G01X369565Y146239D02*
X369570Y146063D01*
G01X369660Y148861D02*
X369662Y149826D01*
G01X369658Y148414D02*
X369660Y148861D01*
G01X369655Y148009D02*
X369658Y148414D01*
G01X369651Y147656D02*
X369655Y148009D01*
G01X369647Y147364D02*
X369651Y147656D01*
G01X369642Y147143D02*
X369647Y147364D01*
G01X369636Y146999D02*
X369642Y147143D01*
G01X369671Y148520D02*
X369673Y149807D01*
G01X369668Y147925D02*
X369671Y148520D01*
G01X369663Y147384D02*
X369668Y147925D01*
G01X369658Y146913D02*
X369663Y147384D01*
G01X369652Y146524D02*
X369658Y146913D01*
G01X369646Y146230D02*
X369652Y146524D01*
G01X369639Y146037D02*
X369646Y146230D01*
G01X369574Y144988D02*
X369588Y145050D01*
G01X369567Y145118D02*
X369574Y144988D01*
G01X369560Y145353D02*
X369567Y145118D01*
G01X371293Y145965D02*
X371303Y146239D01*
G01X371288Y145948D02*
X371293Y145965D01*
G01X371282Y146012D02*
X371288Y145948D01*
G01X371294Y144988D02*
X371308Y145353D01*
G01X371287Y144965D02*
X371294Y144988D01*
G01X371280Y145050D02*
X371287Y144965D01*
G01X371216Y146524D02*
X371229Y146037D01*
G01X371210Y146913D02*
X371216Y146524D01*
G01X371205Y147384D02*
X371210Y146913D01*
G01X371201Y147925D02*
X371205Y147384D01*
G01X371197Y148520D02*
X371201Y147925D01*
G01X371195Y149153D02*
X371197Y148520D01*
G01X371195Y149807D02*
Y149153D01*
G01X371221Y147364D02*
X371232Y146999D01*
G01X371217Y147656D02*
X371221Y147364D01*
G01X371213Y148009D02*
X371217Y147656D01*
G01X371210Y148414D02*
X371213Y148009D01*
G01X371208Y148861D02*
X371210Y148414D01*
G01X371206Y149336D02*
X371208Y148861D01*
G01X371206Y149826D02*
Y149336D01*
G01X371293Y140412D02*
X371282Y140365D01*
G01X371298Y140314D02*
X371293Y140412D01*
G01X371303Y140138D02*
X371298Y140314D01*
G01X371208Y137516D02*
X371206Y136551D01*
G01X371210Y137963D02*
X371208Y137516D01*
G01X371213Y138368D02*
X371210Y137963D01*
G01X371217Y138722D02*
X371213Y138368D01*
G01X371221Y139013D02*
X371217Y138722D01*
G01X371226Y139234D02*
X371221Y139013D01*
G01X371232Y139379D02*
X371226Y139234D01*
G01X371197Y137857D02*
X371195Y136570D01*
G01X371201Y138453D02*
X371197Y137857D01*
G01X371205Y138993D02*
X371201Y138453D01*
G01X371210Y139464D02*
X371205Y138993D01*
G01X371216Y139853D02*
X371210Y139464D01*
G01X371222Y140148D02*
X371216Y139853D01*
G01X371229Y140340D02*
X371222Y140148D01*
G01X371294Y141390D02*
X371280Y141327D01*
G01X371301Y141259D02*
X371294Y141390D01*
G01X371308Y141024D02*
X371301Y141259D01*
G01X369575Y140412D02*
X369565Y140138D01*
G01X369581Y140429D02*
X369575Y140412D01*
G01X369586Y140365D02*
X369581Y140429D01*
G01X369574Y141390D02*
X369560Y141024D01*
G01X369581Y141412D02*
X369574Y141390D01*
G01X369588Y141327D02*
X369581Y141412D01*
G01X369652Y139853D02*
X369639Y140340D01*
G01X369658Y139464D02*
X369652Y139853D01*
G01X369663Y138993D02*
X369658Y139464D01*
G01X369668Y138453D02*
X369663Y138993D01*
G01X369671Y137857D02*
X369668Y138453D01*
G01X369673Y137224D02*
X369671Y137857D01*
G01X369673Y136570D02*
Y137224D01*
G01X369647Y139013D02*
X369636Y139379D01*
G01X369651Y138722D02*
X369647Y139013D01*
G01X369655Y138368D02*
X369651Y138722D01*
G01X369658Y137963D02*
X369655Y138368D01*
G01X369660Y137516D02*
X369658Y137963D01*
G01X369662Y137041D02*
X369660Y137516D01*
G01X369662Y136551D02*
Y137041D01*
G01X367361Y145965D02*
X367371Y146239D01*
G01X367355Y145948D02*
X367361Y145965D01*
G01X367350Y146012D02*
X367355Y145948D01*
G01X367362Y144988D02*
X367376Y145353D01*
G01X367355Y144965D02*
X367362Y144988D01*
G01X367347Y145050D02*
X367355Y144965D01*
G01X367283Y146524D02*
X367297Y146037D01*
G01X367277Y146913D02*
X367283Y146524D01*
G01X367272Y147384D02*
X367277Y146913D01*
G01X367268Y147925D02*
X367272Y147384D01*
G01X367265Y148520D02*
X367268Y147925D01*
G01X367263Y149153D02*
X367265Y148520D01*
G01X367262Y149807D02*
X367263Y149153D01*
G01X367258Y151677D02*
X367250Y151750D01*
G01X367261Y151547D02*
X367258Y151677D01*
G01X367265Y151359D02*
X367261Y151547D01*
G01X367268Y151120D02*
X367265Y151359D01*
G01X367270Y150838D02*
X367268Y151120D01*
G01X367272Y150521D02*
X367270Y150838D01*
G01X367273Y150180D02*
X367272Y150521D01*
G01X367273Y149826D02*
Y150180D01*
G01X367289Y147364D02*
X367299Y146999D01*
G01X367285Y147656D02*
X367289Y147364D01*
G01X367281Y148009D02*
X367285Y147656D01*
G01X367278Y148414D02*
X367281Y148009D01*
G01X367275Y148861D02*
X367278Y148414D01*
G01X367274Y149336D02*
X367275Y148861D01*
G01X367273Y149826D02*
X367274Y149336D01*
G01X365643Y145965D02*
X365654Y146012D01*
G01X365637Y146063D02*
X365643Y145965D01*
G01X365632Y146239D02*
X365637Y146063D01*
G01X365728Y148861D02*
X365730Y149826D01*
G01X365726Y148414D02*
X365728Y148861D01*
G01X365723Y148009D02*
X365726Y148414D01*
G01X365719Y147656D02*
X365723Y148009D01*
G01X365714Y147364D02*
X365719Y147656D01*
G01X365709Y147143D02*
X365714Y147364D01*
G01X365704Y146999D02*
X365709Y147143D01*
G01X365732Y150521D02*
X365730Y149826D01*
G01X365733Y150838D02*
X365732Y150521D01*
G01X365736Y151120D02*
X365733Y150838D01*
G01X365739Y151359D02*
X365736Y151120D01*
G01X365742Y151547D02*
X365739Y151359D01*
G01X365746Y151677D02*
X365742Y151547D01*
G01X365750Y151746D02*
X365746Y151677D01*
G01X365754Y151750D02*
X365750Y151746D01*
G01X365738Y148520D02*
X365741Y149807D01*
G01X365735Y147925D02*
X365738Y148520D01*
G01X365731Y147384D02*
X365735Y147925D01*
G01X365726Y146913D02*
X365731Y147384D01*
G01X365720Y146524D02*
X365726Y146913D01*
G01X365713Y146230D02*
X365720Y146524D01*
G01X365706Y146037D02*
X365713Y146230D01*
G01X365641Y144988D02*
X365656Y145050D01*
G01X365634Y145118D02*
X365641Y144988D01*
G01X365628Y145353D02*
X365634Y145118D01*
G01X365633Y140412D02*
X365623Y140138D01*
G01X365639Y140429D02*
X365633Y140412D01*
G01X365644Y140365D02*
X365639Y140429D01*
G01X365632Y141390D02*
X365618Y141024D01*
G01X365639Y141412D02*
X365632Y141390D01*
G01X365647Y141327D02*
X365639Y141412D01*
G01X365711Y139853D02*
X365697Y140340D01*
G01X365717Y139464D02*
X365711Y139853D01*
G01X365722Y138993D02*
X365717Y139464D01*
G01X365726Y138453D02*
X365722Y138993D01*
G01X365729Y137857D02*
X365726Y138453D01*
G01X365731Y137224D02*
X365729Y137857D01*
G01X365732Y136570D02*
X365731Y137224D01*
G01X365736Y134700D02*
X365744Y134627D01*
G01X365733Y134830D02*
X365736Y134700D01*
G01X365729Y135018D02*
X365733Y134830D01*
G01X365726Y135257D02*
X365729Y135018D01*
G01X365724Y135540D02*
X365726Y135257D01*
G01X365722Y135857D02*
X365724Y135540D01*
G01X365721Y136198D02*
X365722Y135857D01*
G01X365721Y136551D02*
Y136198D01*
G01X365705Y139013D02*
X365695Y139379D01*
G01X365709Y138722D02*
X365705Y139013D01*
G01X365713Y138368D02*
X365709Y138722D01*
G01X365716Y137963D02*
X365713Y138368D01*
G01X365719Y137516D02*
X365716Y137963D01*
G01X365720Y137041D02*
X365719Y137516D01*
G01X365721Y136551D02*
X365720Y137041D01*
G01X367351Y140412D02*
X367340Y140365D01*
G01X367357Y140314D02*
X367351Y140412D01*
G01X367362Y140138D02*
X367357Y140314D01*
G01X367266Y137516D02*
X367264Y136551D01*
G01X367268Y137963D02*
X367266Y137516D01*
G01X367272Y138368D02*
X367268Y137963D01*
G01X367275Y138722D02*
X367272Y138368D01*
G01X367280Y139013D02*
X367275Y138722D01*
G01X367285Y139234D02*
X367280Y139013D01*
G01X367290Y139379D02*
X367285Y139234D01*
G01X367262Y135857D02*
X367264Y136551D01*
G01X367261Y135540D02*
X367262Y135857D01*
G01X367258Y135257D02*
X367261Y135540D01*
G01X367255Y135018D02*
X367258Y135257D01*
G01X367252Y134830D02*
X367255Y135018D01*
G01X367248Y134700D02*
X367252Y134830D01*
G01X367244Y134632D02*
X367248Y134700D01*
G01X367240Y134627D02*
X367244Y134632D01*
G01X367256Y137857D02*
X367253Y136570D01*
G01X367259Y138453D02*
X367256Y137857D01*
G01X367263Y138993D02*
X367259Y138453D01*
G01X367268Y139464D02*
X367263Y138993D01*
G01X367274Y139853D02*
X367268Y139464D01*
G01X367281Y140148D02*
X367274Y139853D01*
G01X367288Y140340D02*
X367281Y140148D01*
G01X367353Y141390D02*
X367338Y141327D01*
G01X367360Y141259D02*
X367353Y141390D01*
G01X367367Y141024D02*
X367360Y141259D01*
G01X361701Y145965D02*
X361712Y146012D01*
G01X361696Y146063D02*
X361701Y145965D01*
G01X361691Y146239D02*
X361696Y146063D01*
G01X361786Y148861D02*
X361788Y149826D01*
G01X361784Y148414D02*
X361786Y148861D01*
G01X361781Y148009D02*
X361784Y148414D01*
G01X361777Y147656D02*
X361781Y148009D01*
G01X361773Y147364D02*
X361777Y147656D01*
G01X361768Y147143D02*
X361773Y147364D01*
G01X361762Y146999D02*
X361768Y147143D01*
G01X361797Y148520D02*
X361799Y149807D01*
G01X361793Y147925D02*
X361797Y148520D01*
G01X361789Y147384D02*
X361793Y147925D01*
G01X361784Y146913D02*
X361789Y147384D01*
G01X361778Y146524D02*
X361784Y146913D01*
G01X361772Y146230D02*
X361778Y146524D01*
G01X361765Y146037D02*
X361772Y146230D01*
G01X361700Y144988D02*
X361714Y145050D01*
G01X361693Y145118D02*
X361700Y144988D01*
G01X361686Y145353D02*
X361693Y145118D01*
G01X363419Y145965D02*
X363429Y146239D01*
G01X363414Y145948D02*
X363419Y145965D01*
G01X363408Y146012D02*
X363414Y145948D01*
G01X363420Y144988D02*
X363434Y145353D01*
G01X363413Y144965D02*
X363420Y144988D01*
G01X363406Y145050D02*
X363413Y144965D01*
G01X363342Y146524D02*
X363355Y146037D01*
G01X363336Y146913D02*
X363342Y146524D01*
G01X363331Y147384D02*
X363336Y146913D01*
G01X363327Y147925D02*
X363331Y147384D01*
G01X363323Y148520D02*
X363327Y147925D01*
G01X363321Y149153D02*
X363323Y148520D01*
G01X363321Y149807D02*
Y149153D01*
G01X363347Y147364D02*
X363358Y146999D01*
G01X363343Y147656D02*
X363347Y147364D01*
G01X363339Y148009D02*
X363343Y147656D01*
G01X363336Y148414D02*
X363339Y148009D01*
G01X363334Y148861D02*
X363336Y148414D01*
G01X363332Y149336D02*
X363334Y148861D01*
G01X363332Y149826D02*
Y149336D01*
G01X363419Y140412D02*
X363408Y140365D01*
G01X363424Y140314D02*
X363419Y140412D01*
G01X363429Y140138D02*
X363424Y140314D01*
G01X363334Y137516D02*
X363332Y136551D01*
G01X363336Y137963D02*
X363334Y137516D01*
G01X363339Y138368D02*
X363336Y137963D01*
G01X363343Y138722D02*
X363339Y138368D01*
G01X363347Y139013D02*
X363343Y138722D01*
G01X363352Y139234D02*
X363347Y139013D01*
G01X363358Y139379D02*
X363352Y139234D01*
G01X363323Y137857D02*
X363321Y136570D01*
G01X363327Y138453D02*
X363323Y137857D01*
G01X363331Y138993D02*
X363327Y138453D01*
G01X363336Y139464D02*
X363331Y138993D01*
G01X363342Y139853D02*
X363336Y139464D01*
G01X363348Y140148D02*
X363342Y139853D01*
G01X363355Y140340D02*
X363348Y140148D01*
G01X363420Y141390D02*
X363406Y141327D01*
G01X363427Y141259D02*
X363420Y141390D01*
G01X363434Y141024D02*
X363427Y141259D01*
G01X361701Y140412D02*
X361691Y140138D01*
G01X361707Y140429D02*
X361701Y140412D01*
G01X361712Y140365D02*
X361707Y140429D01*
G01X361700Y141390D02*
X361686Y141024D01*
G01X361707Y141412D02*
X361700Y141390D01*
G01X361714Y141327D02*
X361707Y141412D01*
G01X361778Y139853D02*
X361765Y140340D01*
G01X361784Y139464D02*
X361778Y139853D01*
G01X361789Y138993D02*
X361784Y139464D01*
G01X361793Y138453D02*
X361789Y138993D01*
G01X361797Y137857D02*
X361793Y138453D01*
G01X361799Y137224D02*
X361797Y137857D01*
G01X361799Y136570D02*
Y137224D01*
G01X361773Y139013D02*
X361762Y139379D01*
G01X361777Y138722D02*
X361773Y139013D01*
G01X361781Y138368D02*
X361777Y138722D01*
G01X361784Y137963D02*
X361781Y138368D01*
G01X361786Y137516D02*
X361784Y137963D01*
G01X361788Y137041D02*
X361786Y137516D01*
G01X361788Y136551D02*
Y137041D01*
G01X359487Y145965D02*
X359497Y146239D01*
G01X359481Y145948D02*
X359487Y145965D01*
G01X359476Y146012D02*
X359481Y145948D01*
G01X359488Y144988D02*
X359502Y145353D01*
G01X359481Y144965D02*
X359488Y144988D01*
G01X359473Y145050D02*
X359481Y144965D01*
G01X359409Y146524D02*
X359423Y146037D01*
G01X359403Y146913D02*
X359409Y146524D01*
G01X359398Y147384D02*
X359403Y146913D01*
G01X359394Y147925D02*
X359398Y147384D01*
G01X359391Y148520D02*
X359394Y147925D01*
G01X359389Y149153D02*
X359391Y148520D01*
G01X359388Y149807D02*
X359389Y149153D01*
G01X359384Y151677D02*
X359376Y151750D01*
G01X359387Y151547D02*
X359384Y151677D01*
G01X359391Y151359D02*
X359387Y151547D01*
G01X359394Y151120D02*
X359391Y151359D01*
G01X359396Y150838D02*
X359394Y151120D01*
G01X359398Y150521D02*
X359396Y150838D01*
G01X359399Y150180D02*
X359398Y150521D01*
G01X359399Y149826D02*
Y150180D01*
G01X359415Y147364D02*
X359425Y146999D01*
G01X359411Y147656D02*
X359415Y147364D01*
G01X359407Y148009D02*
X359411Y147656D01*
G01X359404Y148414D02*
X359407Y148009D01*
G01X359401Y148861D02*
X359404Y148414D01*
G01X359400Y149336D02*
X359401Y148861D01*
G01X359399Y149826D02*
X359400Y149336D01*
G01X357769Y145965D02*
X357780Y146012D01*
G01X357763Y146063D02*
X357769Y145965D01*
G01X357758Y146239D02*
X357763Y146063D01*
G01X357854Y148861D02*
X357856Y149826D01*
G01X357852Y148414D02*
X357854Y148861D01*
G01X357849Y148009D02*
X357852Y148414D01*
G01X357845Y147656D02*
X357849Y148009D01*
G01X357840Y147364D02*
X357845Y147656D01*
G01X357835Y147143D02*
X357840Y147364D01*
G01X357830Y146999D02*
X357835Y147143D01*
G01X357858Y150521D02*
X357856Y149826D01*
G01X357859Y150838D02*
X357858Y150521D01*
G01X357862Y151120D02*
X357859Y150838D01*
G01X357865Y151359D02*
X357862Y151120D01*
G01X357868Y151547D02*
X357865Y151359D01*
G01X357872Y151677D02*
X357868Y151547D01*
G01X357876Y151746D02*
X357872Y151677D01*
G01X357880Y151750D02*
X357876Y151746D01*
G01X357864Y148520D02*
X357867Y149807D01*
G01X357861Y147925D02*
X357864Y148520D01*
G01X357857Y147384D02*
X357861Y147925D01*
G01X357852Y146913D02*
X357857Y147384D01*
G01X357846Y146524D02*
X357852Y146913D01*
G01X357839Y146230D02*
X357846Y146524D01*
G01X357832Y146037D02*
X357839Y146230D01*
G01X357767Y144988D02*
X357782Y145050D01*
G01X357760Y145118D02*
X357767Y144988D01*
G01X357753Y145353D02*
X357760Y145118D01*
G01X357759Y140412D02*
X357749Y140138D01*
G01X357765Y140429D02*
X357759Y140412D01*
G01X357770Y140365D02*
X357765Y140429D01*
G01X357758Y141390D02*
X357744Y141024D01*
G01X357765Y141412D02*
X357758Y141390D01*
G01X357773Y141327D02*
X357765Y141412D01*
G01X357837Y139853D02*
X357823Y140340D01*
G01X357843Y139464D02*
X357837Y139853D01*
G01X357848Y138993D02*
X357843Y139464D01*
G01X357852Y138453D02*
X357848Y138993D01*
G01X357855Y137857D02*
X357852Y138453D01*
G01X357857Y137224D02*
X357855Y137857D01*
G01X357858Y136570D02*
X357857Y137224D01*
G01X357862Y134700D02*
X357870Y134627D01*
G01X357859Y134830D02*
X357862Y134700D01*
G01X357855Y135018D02*
X357859Y134830D01*
G01X357852Y135257D02*
X357855Y135018D01*
G01X357850Y135540D02*
X357852Y135257D01*
G01X357848Y135857D02*
X357850Y135540D01*
G01X357847Y136198D02*
X357848Y135857D01*
G01X357847Y136551D02*
Y136198D01*
G01X357831Y139013D02*
X357821Y139379D01*
G01X357835Y138722D02*
X357831Y139013D01*
G01X357839Y138368D02*
X357835Y138722D01*
G01X357842Y137963D02*
X357839Y138368D01*
G01X357845Y137516D02*
X357842Y137963D01*
G01X357846Y137041D02*
X357845Y137516D01*
G01X357847Y136551D02*
X357846Y137041D01*
G01X359477Y140412D02*
X359466Y140365D01*
G01X359483Y140314D02*
X359477Y140412D01*
G01X359488Y140138D02*
X359483Y140314D01*
G01X359392Y137516D02*
X359390Y136551D01*
G01X359394Y137963D02*
X359392Y137516D01*
G01X359397Y138368D02*
X359394Y137963D01*
G01X359401Y138722D02*
X359397Y138368D01*
G01X359406Y139013D02*
X359401Y138722D01*
G01X359411Y139234D02*
X359406Y139013D01*
G01X359416Y139379D02*
X359411Y139234D01*
G01X359388Y135857D02*
X359390Y136551D01*
G01X359387Y135540D02*
X359388Y135857D01*
G01X359384Y135257D02*
X359387Y135540D01*
G01X359381Y135018D02*
X359384Y135257D01*
G01X359378Y134830D02*
X359381Y135018D01*
G01X359374Y134700D02*
X359378Y134830D01*
G01X359370Y134632D02*
X359374Y134700D01*
G01X359366Y134627D02*
X359370Y134632D01*
G01X359382Y137857D02*
X359379Y136570D01*
G01X359385Y138453D02*
X359382Y137857D01*
G01X359389Y138993D02*
X359385Y138453D01*
G01X359394Y139464D02*
X359389Y138993D01*
G01X359400Y139853D02*
X359394Y139464D01*
G01X359407Y140148D02*
X359400Y139853D01*
G01X359414Y140340D02*
X359407Y140148D01*
G01X359479Y141390D02*
X359464Y141327D01*
G01X359486Y141259D02*
X359479Y141390D01*
G01X359493Y141024D02*
X359486Y141259D01*
G01X353827Y145965D02*
X353838Y146012D01*
G01X353822Y146063D02*
X353827Y145965D01*
G01X353817Y146239D02*
X353822Y146063D01*
G01X353912Y148861D02*
X353914Y149826D01*
G01X353910Y148414D02*
X353912Y148861D01*
G01X353907Y148009D02*
X353910Y148414D01*
G01X353903Y147656D02*
X353907Y148009D01*
G01X353899Y147364D02*
X353903Y147656D01*
G01X353894Y147143D02*
X353899Y147364D01*
G01X353888Y146999D02*
X353894Y147143D01*
G01X353923Y148520D02*
X353925Y149807D01*
G01X353919Y147925D02*
X353923Y148520D01*
G01X353915Y147384D02*
X353919Y147925D01*
G01X353910Y146913D02*
X353915Y147384D01*
G01X353904Y146524D02*
X353910Y146913D01*
G01X353898Y146230D02*
X353904Y146524D01*
G01X353891Y146037D02*
X353898Y146230D01*
G01X353826Y144988D02*
X353840Y145050D01*
G01X353819Y145118D02*
X353826Y144988D01*
G01X353812Y145353D02*
X353819Y145118D01*
G01X355545Y145965D02*
X355555Y146239D01*
G01X355539Y145948D02*
X355545Y145965D01*
G01X355534Y146012D02*
X355539Y145948D01*
G01X355546Y144988D02*
X355560Y145353D01*
G01X355539Y144965D02*
X355546Y144988D01*
G01X355532Y145050D02*
X355539Y144965D01*
G01X355468Y146524D02*
X355481Y146037D01*
G01X355462Y146913D02*
X355468Y146524D01*
G01X355457Y147384D02*
X355462Y146913D01*
G01X355453Y147925D02*
X355457Y147384D01*
G01X355449Y148520D02*
X355453Y147925D01*
G01X355447Y149153D02*
X355449Y148520D01*
G01X355447Y149807D02*
Y149153D01*
G01X355473Y147364D02*
X355484Y146999D01*
G01X355469Y147656D02*
X355473Y147364D01*
G01X355465Y148009D02*
X355469Y147656D01*
G01X355462Y148414D02*
X355465Y148009D01*
G01X355460Y148861D02*
X355462Y148414D01*
G01X355458Y149336D02*
X355460Y148861D01*
G01X355458Y149826D02*
Y149336D01*
G01X355545Y140412D02*
X355534Y140365D01*
G01X355550Y140314D02*
X355545Y140412D01*
G01X355555Y140138D02*
X355550Y140314D01*
G01X355460Y137516D02*
X355458Y136551D01*
G01X355462Y137963D02*
X355460Y137516D01*
G01X355465Y138368D02*
X355462Y137963D01*
G01X355469Y138722D02*
X355465Y138368D01*
G01X355473Y139013D02*
X355469Y138722D01*
G01X355478Y139234D02*
X355473Y139013D01*
G01X355484Y139379D02*
X355478Y139234D01*
G01X355449Y137857D02*
X355447Y136570D01*
G01X355453Y138453D02*
X355449Y137857D01*
G01X355457Y138993D02*
X355453Y138453D01*
G01X355462Y139464D02*
X355457Y138993D01*
G01X355468Y139853D02*
X355462Y139464D01*
G01X355474Y140148D02*
X355468Y139853D01*
G01X355481Y140340D02*
X355474Y140148D01*
G01X355546Y141390D02*
X355532Y141327D01*
G01X355553Y141259D02*
X355546Y141390D01*
G01X355560Y141024D02*
X355553Y141259D01*
G01X353827Y140412D02*
X353817Y140138D01*
G01X353833Y140429D02*
X353827Y140412D01*
G01X353838Y140365D02*
X353833Y140429D01*
G01X353826Y141390D02*
X353812Y141024D01*
G01X353833Y141412D02*
X353826Y141390D01*
G01X353840Y141327D02*
X353833Y141412D01*
G01X353904Y139853D02*
X353891Y140340D01*
G01X353910Y139464D02*
X353904Y139853D01*
G01X353915Y138993D02*
X353910Y139464D01*
G01X353919Y138453D02*
X353915Y138993D01*
G01X353923Y137857D02*
X353919Y138453D01*
G01X353925Y137224D02*
X353923Y137857D01*
G01X353925Y136570D02*
Y137224D01*
G01X353899Y139013D02*
X353888Y139379D01*
G01X353903Y138722D02*
X353899Y139013D01*
G01X353907Y138368D02*
X353903Y138722D01*
G01X353910Y137963D02*
X353907Y138368D01*
G01X353912Y137516D02*
X353910Y137963D01*
G01X353914Y137041D02*
X353912Y137516D01*
G01X353914Y136551D02*
Y137041D01*
G01X351613Y145965D02*
X351623Y146239D01*
G01X351607Y145948D02*
X351613Y145965D01*
G01X351602Y146012D02*
X351607Y145948D01*
G01X351614Y144988D02*
X351628Y145353D01*
G01X351607Y144965D02*
X351614Y144988D01*
G01X351599Y145050D02*
X351607Y144965D01*
G01X351535Y146524D02*
X351549Y146037D01*
G01X351529Y146913D02*
X351535Y146524D01*
G01X351524Y147384D02*
X351529Y146913D01*
G01X351520Y147925D02*
X351524Y147384D01*
G01X351517Y148520D02*
X351520Y147925D01*
G01X351515Y149153D02*
X351517Y148520D01*
G01X351514Y149807D02*
X351515Y149153D01*
G01X351510Y151677D02*
X351502Y151750D01*
G01X351513Y151547D02*
X351510Y151677D01*
G01X351517Y151359D02*
X351513Y151547D01*
G01X351520Y151120D02*
X351517Y151359D01*
G01X351522Y150838D02*
X351520Y151120D01*
G01X351524Y150521D02*
X351522Y150838D01*
G01X351525Y150180D02*
X351524Y150521D01*
G01X351525Y149826D02*
Y150180D01*
G01X351541Y147364D02*
X351551Y146999D01*
G01X351537Y147656D02*
X351541Y147364D01*
G01X351533Y148009D02*
X351537Y147656D01*
G01X351530Y148414D02*
X351533Y148009D01*
G01X351527Y148861D02*
X351530Y148414D01*
G01X351526Y149336D02*
X351527Y148861D01*
G01X351525Y149826D02*
X351526Y149336D01*
G01X349895Y145965D02*
X349906Y146012D01*
G01X349889Y146063D02*
X349895Y145965D01*
G01X349884Y146239D02*
X349889Y146063D01*
G01X349980Y148861D02*
X349982Y149826D01*
G01X349978Y148414D02*
X349980Y148861D01*
G01X349975Y148009D02*
X349978Y148414D01*
G01X349971Y147656D02*
X349975Y148009D01*
G01X349966Y147364D02*
X349971Y147656D01*
G01X349961Y147143D02*
X349966Y147364D01*
G01X349956Y146999D02*
X349961Y147143D01*
G01X349984Y150521D02*
X349982Y149826D01*
G01X349985Y150838D02*
X349984Y150521D01*
G01X349988Y151120D02*
X349985Y150838D01*
G01X349991Y151359D02*
X349988Y151120D01*
G01X349994Y151547D02*
X349991Y151359D01*
G01X349998Y151677D02*
X349994Y151547D01*
G01X350002Y151746D02*
X349998Y151677D01*
G01X350006Y151750D02*
X350002Y151746D01*
G01X349990Y148520D02*
X349993Y149807D01*
G01X349987Y147925D02*
X349990Y148520D01*
G01X349983Y147384D02*
X349987Y147925D01*
G01X349978Y146913D02*
X349983Y147384D01*
G01X349972Y146524D02*
X349978Y146913D01*
G01X349965Y146230D02*
X349972Y146524D01*
G01X349958Y146037D02*
X349965Y146230D01*
G01X349893Y144988D02*
X349908Y145050D01*
G01X349886Y145118D02*
X349893Y144988D01*
G01X349879Y145353D02*
X349886Y145118D01*
G01X349885Y140412D02*
X349875Y140138D01*
G01X349891Y140429D02*
X349885Y140412D01*
G01X349896Y140365D02*
X349891Y140429D01*
G01X349884Y141390D02*
X349870Y141024D01*
G01X349891Y141412D02*
X349884Y141390D01*
G01X349899Y141327D02*
X349891Y141412D01*
G01X349963Y139853D02*
X349949Y140340D01*
G01X349969Y139464D02*
X349963Y139853D01*
G01X349974Y138993D02*
X349969Y139464D01*
G01X349978Y138453D02*
X349974Y138993D01*
G01X349981Y137857D02*
X349978Y138453D01*
G01X349983Y137224D02*
X349981Y137857D01*
G01X349984Y136570D02*
X349983Y137224D01*
G01X349988Y134700D02*
X349996Y134627D01*
G01X349985Y134830D02*
X349988Y134700D01*
G01X349981Y135018D02*
X349985Y134830D01*
G01X349978Y135257D02*
X349981Y135018D01*
G01X349976Y135540D02*
X349978Y135257D01*
G01X349974Y135857D02*
X349976Y135540D01*
G01X349973Y136198D02*
X349974Y135857D01*
G01X349973Y136551D02*
Y136198D01*
G01X349957Y139013D02*
X349947Y139379D01*
G01X349961Y138722D02*
X349957Y139013D01*
G01X349965Y138368D02*
X349961Y138722D01*
G01X349968Y137963D02*
X349965Y138368D01*
G01X349971Y137516D02*
X349968Y137963D01*
G01X349972Y137041D02*
X349971Y137516D01*
G01X349973Y136551D02*
X349972Y137041D01*
G01X351603Y140412D02*
X351592Y140365D01*
G01X351609Y140314D02*
X351603Y140412D01*
G01X351614Y140138D02*
X351609Y140314D01*
G01X351518Y137516D02*
X351516Y136551D01*
G01X351520Y137963D02*
X351518Y137516D01*
G01X351523Y138368D02*
X351520Y137963D01*
G01X351527Y138722D02*
X351523Y138368D01*
G01X351532Y139013D02*
X351527Y138722D01*
G01X351537Y139234D02*
X351532Y139013D01*
G01X351542Y139379D02*
X351537Y139234D01*
G01X351514Y135857D02*
X351516Y136551D01*
G01X351513Y135540D02*
X351514Y135857D01*
G01X351510Y135257D02*
X351513Y135540D01*
G01X351507Y135018D02*
X351510Y135257D01*
G01X351504Y134830D02*
X351507Y135018D01*
G01X351500Y134700D02*
X351504Y134830D01*
G01X351496Y134632D02*
X351500Y134700D01*
G01X351492Y134627D02*
X351496Y134632D01*
G01X351508Y137857D02*
X351505Y136570D01*
G01X351511Y138453D02*
X351508Y137857D01*
G01X351515Y138993D02*
X351511Y138453D01*
G01X351520Y139464D02*
X351515Y138993D01*
G01X351526Y139853D02*
X351520Y139464D01*
G01X351533Y140148D02*
X351526Y139853D01*
G01X351540Y140340D02*
X351533Y140148D01*
G01X351605Y141390D02*
X351590Y141327D01*
G01X351612Y141259D02*
X351605Y141390D01*
G01X351619Y141024D02*
X351612Y141259D01*
G01X347671Y145965D02*
X347681Y146239D01*
G01X347665Y145948D02*
X347671Y145965D01*
G01X347660Y146012D02*
X347665Y145948D01*
G01X347672Y144988D02*
X347686Y145353D01*
G01X347665Y144965D02*
X347672Y144988D01*
G01X347658Y145050D02*
X347665Y144965D01*
G01X347594Y146524D02*
X347607Y146037D01*
G01X347588Y146913D02*
X347594Y146524D01*
G01X347583Y147384D02*
X347588Y146913D01*
G01X347579Y147925D02*
X347583Y147384D01*
G01X347575Y148520D02*
X347579Y147925D01*
G01X347573Y149153D02*
X347575Y148520D01*
G01X347573Y149807D02*
Y149153D01*
G01X347599Y147364D02*
X347610Y146999D01*
G01X347595Y147656D02*
X347599Y147364D01*
G01X347591Y148009D02*
X347595Y147656D01*
G01X347588Y148414D02*
X347591Y148009D01*
G01X347586Y148861D02*
X347588Y148414D01*
G01X347584Y149336D02*
X347586Y148861D01*
G01X347584Y149826D02*
Y149336D01*
G01X347671Y140412D02*
X347660Y140365D01*
G01X347676Y140314D02*
X347671Y140412D01*
G01X347681Y140138D02*
X347676Y140314D01*
G01X347586Y137516D02*
X347584Y136551D01*
G01X347588Y137963D02*
X347586Y137516D01*
G01X347591Y138368D02*
X347588Y137963D01*
G01X347595Y138722D02*
X347591Y138368D01*
G01X347599Y139013D02*
X347595Y138722D01*
G01X347604Y139234D02*
X347599Y139013D01*
G01X347610Y139379D02*
X347604Y139234D01*
G01X347575Y137857D02*
X347573Y136570D01*
G01X347579Y138453D02*
X347575Y137857D01*
G01X347583Y138993D02*
X347579Y138453D01*
G01X347588Y139464D02*
X347583Y138993D01*
G01X347594Y139853D02*
X347588Y139464D01*
G01X347600Y140148D02*
X347594Y139853D01*
G01X347607Y140340D02*
X347600Y140148D01*
G01X347672Y141390D02*
X347658Y141327D01*
G01X347679Y141259D02*
X347672Y141390D01*
G01X347686Y141024D02*
X347679Y141259D01*
G01X347561Y151754D02*
X347560Y151750D01*
G01X347561Y151756D02*
Y151754D01*
G01X347562Y151756D02*
X347561D01*
G01X355435Y151754D02*
X355434Y151750D01*
G01X355435Y151756D02*
Y151754D01*
G01X355436Y151756D02*
X355435D01*
G01X347561Y150768D02*
X347560Y150762D01*
G01X347561Y150771D02*
Y150768D01*
G01X347562Y150772D02*
X347561Y150771D01*
G01X355435Y150768D02*
X355434Y150762D01*
G01X355435Y150771D02*
Y150768D01*
G01X355436Y150772D02*
X355435Y150771D01*
G01X353937Y135610D02*
X353938Y135615D01*
G01X353937Y135606D02*
Y135610D01*
G01X353936Y135605D02*
X353937Y135606D01*
G01X363309Y151754D02*
X363308Y151750D01*
G01X363309Y151756D02*
Y151754D01*
G01X363310Y151756D02*
X363309D01*
G01X353937Y134624D02*
X353938Y134627D01*
G01X353937Y134622D02*
Y134624D01*
G01X353936Y134621D02*
X353937Y134622D01*
G01X371183Y151754D02*
X371182Y151750D01*
G01X371183Y151756D02*
Y151754D01*
G01X371184Y151756D02*
X371183D01*
G01X361811Y134624D02*
X361812Y134627D01*
G01X361811Y134622D02*
Y134624D01*
G01X361810Y134621D02*
X361811Y134622D01*
G01X379057Y151754D02*
X379056Y151750D01*
G01X379057Y151756D02*
Y151754D01*
G01X379058Y151756D02*
X379057D01*
G01X369685Y134624D02*
X369686Y134627D01*
G01X369685Y134622D02*
Y134624D01*
G01X369684Y134621D02*
X369685Y134622D01*
G01X386931Y151754D02*
X386930Y151750D01*
G01X386931Y151756D02*
Y151754D01*
G01X386932Y151756D02*
X386931D01*
G01X347561Y135606D02*
X347562Y135605D01*
G01X347561Y135610D02*
Y135606D01*
G01X347560Y135615D02*
X347561Y135610D01*
G01X347829Y133893D02*
X347836Y133840D01*
G01X347823Y134024D02*
X347829Y133893D01*
G01X347818Y134231D02*
X347823Y134024D01*
G01X349736Y152484D02*
X349730Y152538D01*
G01X349742Y152353D02*
X349736Y152484D01*
G01X349748Y152147D02*
X349742Y152353D01*
G01X351762Y133893D02*
X351768Y133840D01*
G01X351756Y134024D02*
X351762Y133893D01*
G01X351750Y134231D02*
X351756Y134024D01*
G01X347831Y134866D02*
X347836Y134824D01*
G01X347827Y134965D02*
X347831Y134866D01*
G01X347822Y135117D02*
X347827Y134965D01*
G01X349735Y151511D02*
X349730Y151553D01*
G01X349739Y151413D02*
X349735Y151511D01*
G01X349743Y151260D02*
X349739Y151413D01*
G01X351763Y134866D02*
X351768Y134824D01*
G01X351759Y134965D02*
X351763Y134866D01*
G01X351755Y135117D02*
X351759Y134965D01*
G01X349992Y135645D02*
X349996Y135615D01*
G01X349987Y135841D02*
X349992Y135645D01*
G01X349985Y136168D02*
X349987Y135841D01*
G01X349984Y136570D02*
X349985Y136168D01*
G01X351506Y150733D02*
X351502Y150762D01*
G01X351511Y150537D02*
X351506Y150733D01*
G01X351513Y150209D02*
X351511Y150537D01*
G01X351514Y149807D02*
X351513Y150209D01*
G01X347566Y150699D02*
X347562Y150772D01*
G01X347569Y150490D02*
X347566Y150699D01*
G01X347572Y150178D02*
X347569Y150490D01*
G01X347573Y149807D02*
X347572Y150178D01*
G01X347570Y151608D02*
X347562Y151756D01*
G01X347577Y151193D02*
X347570Y151608D01*
G01X347582Y150573D02*
X347577Y151193D01*
G01X347584Y149826D02*
X347582Y150573D01*
G01X353928Y134770D02*
X353936Y134621D01*
G01X353921Y135184D02*
X353928Y134770D01*
G01X353916Y135804D02*
X353921Y135184D01*
G01X353914Y136551D02*
X353916Y135804D01*
G01X353932Y135678D02*
X353936Y135605D01*
G01X353929Y135887D02*
X353932Y135678D01*
G01X353926Y136200D02*
X353929Y135887D01*
G01X353925Y136570D02*
X353926Y136200D01*
G01X347582Y135804D02*
X347584Y136551D01*
G01X347577Y135184D02*
X347582Y135804D01*
G01X347570Y134770D02*
X347577Y135184D01*
G01X347562Y134621D02*
X347570Y134770D01*
G01X353916Y150573D02*
X353914Y149826D01*
G01X353921Y151193D02*
X353916Y150573D01*
G01X353928Y151608D02*
X353921Y151193D01*
G01X353936Y151756D02*
X353928Y151608D01*
G01X355456Y135804D02*
X355458Y136551D01*
G01X355451Y135184D02*
X355456Y135804D01*
G01X355444Y134770D02*
X355451Y135184D01*
G01X355436Y134621D02*
X355444Y134770D01*
G01X347572Y136200D02*
X347573Y136570D01*
G01X347569Y135887D02*
X347572Y136200D01*
G01X347566Y135678D02*
X347569Y135887D01*
G01X347562Y135605D02*
X347566Y135678D01*
G01X353926Y150178D02*
X353925Y149807D01*
G01X353929Y150490D02*
X353926Y150178D01*
G01X353932Y150699D02*
X353929Y150490D01*
G01X353936Y150772D02*
X353932Y150699D01*
G01X355446Y136200D02*
X355447Y136570D01*
G01X355443Y135887D02*
X355446Y136200D01*
G01X355440Y135678D02*
X355443Y135887D01*
G01X355436Y135605D02*
X355440Y135678D01*
G01X347827Y151413D02*
X347822Y151260D01*
G01X347831Y151511D02*
X347827Y151413D01*
G01X347836Y151553D02*
X347831Y151511D01*
G01X349730Y134965D02*
X349734Y135117D01*
G01X349725Y134866D02*
X349730Y134965D01*
G01X349721Y134824D02*
X349725Y134866D01*
G01X351768Y151413D02*
X351764Y151260D01*
G01X351773Y151511D02*
X351768Y151413D01*
G01X351777Y151553D02*
X351773Y151511D01*
G01X353671Y134965D02*
X353676Y135117D01*
G01X353667Y134866D02*
X353671Y134965D01*
G01X353662Y134824D02*
X353667Y134866D01*
G01X355701Y151413D02*
X355696Y151260D01*
G01X355705Y151511D02*
X355701Y151413D01*
G01X355710Y151553D02*
X355705Y151511D01*
G01X357604Y134965D02*
X357608Y135117D01*
G01X357599Y134866D02*
X357604Y134965D01*
G01X357595Y134824D02*
X357599Y134866D01*
G01X359642Y151413D02*
X359638Y151260D01*
G01X359647Y151511D02*
X359642Y151413D01*
G01X359651Y151553D02*
X359647Y151511D01*
G01X347823Y152353D02*
X347818Y152147D01*
G01X347829Y152484D02*
X347823Y152353D01*
G01X347836Y152538D02*
X347829Y152484D01*
G01X351765Y152353D02*
X351759Y152147D01*
G01X351771Y152484D02*
X351765Y152353D01*
G01X351777Y152538D02*
X351771Y152484D01*
G01X349733Y134024D02*
X349739Y134231D01*
G01X349727Y133893D02*
X349733Y134024D01*
G01X349721Y133840D02*
X349727Y133893D01*
G01X355697Y152353D02*
X355692Y152147D01*
G01X355703Y152484D02*
X355697Y152353D01*
G01X355710Y152538D02*
X355703Y152484D01*
G01X353675Y134024D02*
X353680Y134231D01*
G01X353669Y133893D02*
X353675Y134024D01*
G01X353662Y133840D02*
X353669Y133893D01*
G01X359639Y152353D02*
X359633Y152147D01*
G01X359645Y152484D02*
X359639Y152353D01*
G01X359651Y152538D02*
X359645Y152484D01*
G01X357607Y134024D02*
X357613Y134231D01*
G01X357601Y133893D02*
X357607Y134024D01*
G01X357595Y133840D02*
X357601Y133893D01*
G01X349994Y150209D02*
X349993Y149807D01*
G01X349997Y150537D02*
X349994Y150209D01*
G01X350001Y150733D02*
X349997Y150537D01*
G01X350005Y150762D02*
X350001Y150733D01*
G01X351504Y136168D02*
X351505Y136570D01*
G01X351501Y135841D02*
X351504Y136168D01*
G01X351497Y135645D02*
X351501Y135841D01*
G01X351493Y135615D02*
X351497Y135645D01*
G01X357868Y150209D02*
X357867Y149807D01*
G01X357871Y150537D02*
X357868Y150209D01*
G01X357875Y150733D02*
X357871Y150537D01*
G01X357879Y150762D02*
X357875Y150733D01*
G01X359378Y136168D02*
X359379Y136570D01*
G01X359375Y135841D02*
X359378Y136168D01*
G01X359371Y135645D02*
X359375Y135841D01*
G01X359367Y135615D02*
X359371Y135645D01*
G01X363309Y150768D02*
X363308Y150762D01*
G01X363309Y150771D02*
Y150768D01*
G01X363310Y150772D02*
X363309Y150771D01*
G01X361811Y135610D02*
X361812Y135615D01*
G01X361811Y135606D02*
Y135610D01*
G01X361810Y135605D02*
X361811Y135606D01*
G01X371183Y150768D02*
X371182Y150762D01*
G01X371183Y150771D02*
Y150768D01*
G01X371184Y150772D02*
X371183Y150771D01*
G01X369685Y135610D02*
X369686Y135615D01*
G01X369685Y135606D02*
Y135610D01*
G01X369684Y135605D02*
X369685Y135606D01*
G01X379057Y150768D02*
X379056Y150762D01*
G01X379057Y150771D02*
Y150768D01*
G01X379058Y150772D02*
X379057Y150771D01*
G01X377559Y135610D02*
X377560Y135615D01*
G01X377559Y135606D02*
Y135610D01*
G01X377558Y135605D02*
X377559Y135606D01*
G01X386931Y150768D02*
X386930Y150762D01*
G01X386931Y150771D02*
Y150768D01*
G01X386932Y150772D02*
X386931Y150771D01*
G01X377559Y134624D02*
X377560Y134627D01*
G01X377559Y134622D02*
Y134624D01*
G01X377558Y134621D02*
X377559Y134622D01*
G01X394805Y151754D02*
X394804Y151750D01*
G01X394805Y151756D02*
Y151754D01*
G01X394806Y151756D02*
X394805D01*
G01X385433Y134624D02*
X385434Y134627D01*
G01X385433Y134622D02*
Y134624D01*
G01X385432Y134621D02*
X385433Y134622D01*
G01X402679Y151754D02*
X402678Y151750D01*
G01X402679Y151756D02*
Y151754D01*
G01X402680Y151756D02*
X402679D01*
G01X393307Y134624D02*
X393308Y134627D01*
G01X393307Y134622D02*
Y134624D01*
G01X393306Y134621D02*
X393307Y134622D01*
G01X410553Y151754D02*
X410552Y151750D01*
G01X410553Y151756D02*
Y151754D01*
G01X410554Y151756D02*
X410553D01*
G01X401181Y134624D02*
X401182Y134627D01*
G01X401181Y134622D02*
Y134624D01*
G01X401180Y134621D02*
X401181Y134622D01*
G01X418427Y151754D02*
X418426Y151750D01*
G01X418427Y151756D02*
Y151754D01*
G01X418428Y151756D02*
X418427D01*
G01X353937Y150771D02*
X353936Y150772D01*
G01X353937Y150768D02*
Y150771D01*
G01X353938Y150762D02*
X353937Y150768D01*
G01X355435Y135606D02*
X355436Y135605D01*
G01X355435Y135610D02*
Y135606D01*
G01X355434Y135615D02*
X355435Y135610D01*
G01X361811Y150771D02*
X361810Y150772D01*
G01X361811Y150768D02*
Y150771D01*
G01X361812Y150762D02*
X361811Y150768D01*
G01X363309Y135606D02*
X363310Y135605D01*
G01X363309Y135610D02*
Y135606D01*
G01X363308Y135615D02*
X363309Y135610D01*
G01X369685Y150771D02*
X369684Y150772D01*
G01X369685Y150768D02*
Y150771D01*
G01X369686Y150762D02*
X369685Y150768D01*
G01X371183Y135606D02*
X371184Y135605D01*
G01X371183Y135610D02*
Y135606D01*
G01X371182Y135615D02*
X371183Y135610D01*
G01X353669Y152484D02*
X353662Y152538D01*
G01X353675Y152353D02*
X353669Y152484D01*
G01X353680Y152147D02*
X353675Y152353D01*
G01X355703Y133893D02*
X355710Y133840D01*
G01X355697Y134024D02*
X355703Y133893D01*
G01X355692Y134231D02*
X355697Y134024D01*
G01X357610Y152484D02*
X357604Y152538D01*
G01X357616Y152353D02*
X357610Y152484D01*
G01X357622Y152147D02*
X357616Y152353D01*
G01X359636Y133893D02*
X359642Y133840D01*
G01X359630Y134024D02*
X359636Y133893D01*
G01X359624Y134231D02*
X359630Y134024D01*
G01X361543Y152484D02*
X361536Y152538D01*
G01X361549Y152353D02*
X361543Y152484D01*
G01X361554Y152147D02*
X361549Y152353D01*
G01X363577Y133893D02*
X363584Y133840D01*
G01X363571Y134024D02*
X363577Y133893D01*
G01X363566Y134231D02*
X363571Y134024D01*
G01X365484Y152484D02*
X365478Y152538D01*
G01X365490Y152353D02*
X365484Y152484D01*
G01X365496Y152147D02*
X365490Y152353D01*
G01X367510Y133893D02*
X367516Y133840D01*
G01X367504Y134024D02*
X367510Y133893D01*
G01X367498Y134231D02*
X367504Y134024D01*
G01X369417Y152484D02*
X369410Y152538D01*
G01X369423Y152353D02*
X369417Y152484D01*
G01X369428Y152147D02*
X369423Y152353D01*
G01X371451Y133893D02*
X371458Y133840D01*
G01X371445Y134024D02*
X371451Y133893D01*
G01X371440Y134231D02*
X371445Y134024D01*
G01X373358Y152484D02*
X373352Y152538D01*
G01X373364Y152353D02*
X373358Y152484D01*
G01X373370Y152147D02*
X373364Y152353D01*
G01X375384Y133893D02*
X375390Y133840D01*
G01X375378Y134024D02*
X375384Y133893D01*
G01X375372Y134231D02*
X375378Y134024D01*
G01X377291Y152484D02*
X377284Y152538D01*
G01X377297Y152353D02*
X377291Y152484D01*
G01X377302Y152147D02*
X377297Y152353D01*
G01X353667Y151511D02*
X353662Y151553D01*
G01X353671Y151413D02*
X353667Y151511D01*
G01X353676Y151260D02*
X353671Y151413D01*
G01X355705Y134866D02*
X355710Y134824D01*
G01X355701Y134965D02*
X355705Y134866D01*
G01X355696Y135117D02*
X355701Y134965D01*
G01X357609Y151511D02*
X357604Y151553D01*
G01X357613Y151413D02*
X357609Y151511D01*
G01X357617Y151260D02*
X357613Y151413D01*
G01X359637Y134866D02*
X359642Y134824D01*
G01X359633Y134965D02*
X359637Y134866D01*
G01X359629Y135117D02*
X359633Y134965D01*
G01X361541Y151511D02*
X361536Y151553D01*
G01X361545Y151413D02*
X361541Y151511D01*
G01X361550Y151260D02*
X361545Y151413D01*
G01X363579Y134866D02*
X363584Y134824D01*
G01X363575Y134965D02*
X363579Y134866D01*
G01X363570Y135117D02*
X363575Y134965D01*
G01X365483Y151511D02*
X365478Y151553D01*
G01X365487Y151413D02*
X365483Y151511D01*
G01X365491Y151260D02*
X365487Y151413D01*
G01X367511Y134866D02*
X367516Y134824D01*
G01X367507Y134965D02*
X367511Y134866D01*
G01X367503Y135117D02*
X367507Y134965D01*
G01X369415Y151511D02*
X369410Y151553D01*
G01X369419Y151413D02*
X369415Y151511D01*
G01X369424Y151260D02*
X369419Y151413D01*
G01X371453Y134866D02*
X371458Y134824D01*
G01X371449Y134965D02*
X371453Y134866D01*
G01X371444Y135117D02*
X371449Y134965D01*
G01X373357Y151511D02*
X373352Y151553D01*
G01X373361Y151413D02*
X373357Y151511D01*
G01X373365Y151260D02*
X373361Y151413D01*
G01X375385Y134866D02*
X375390Y134824D01*
G01X375381Y134965D02*
X375385Y134866D01*
G01X375377Y135117D02*
X375381Y134965D01*
G01X377289Y151511D02*
X377284Y151553D01*
G01X377293Y151413D02*
X377289Y151511D01*
G01X377298Y151260D02*
X377293Y151413D01*
G01X357866Y135645D02*
X357870Y135615D01*
G01X357861Y135841D02*
X357866Y135645D01*
G01X357859Y136168D02*
X357861Y135841D01*
G01X357858Y136570D02*
X357859Y136168D01*
G01X359380Y150733D02*
X359376Y150762D01*
G01X359385Y150537D02*
X359380Y150733D01*
G01X359387Y150209D02*
X359385Y150537D01*
G01X359388Y149807D02*
X359387Y150209D01*
G01X365740Y135645D02*
X365744Y135615D01*
G01X365735Y135841D02*
X365740Y135645D01*
G01X365733Y136168D02*
X365735Y135841D01*
G01X365732Y136570D02*
X365733Y136168D01*
G01X367255Y150733D02*
X367250Y150762D01*
G01X367259Y150537D02*
X367255Y150733D01*
G01X367261Y150209D02*
X367259Y150537D01*
G01X367262Y149807D02*
X367261Y150209D01*
G01X373614Y135645D02*
X373618Y135615D01*
G01X373610Y135841D02*
X373614Y135645D01*
G01X373607Y136168D02*
X373610Y135841D01*
G01X373606Y136570D02*
X373607Y136168D01*
G01X375129Y150733D02*
X375124Y150762D01*
G01X375133Y150537D02*
X375129Y150733D01*
G01X375135Y150209D02*
X375133Y150537D01*
G01X375136Y149807D02*
X375135Y150209D01*
G01X355440Y150699D02*
X355436Y150772D01*
G01X355443Y150490D02*
X355440Y150699D01*
G01X355446Y150178D02*
X355443Y150490D01*
G01X355447Y149807D02*
X355446Y150178D01*
G01X355444Y151608D02*
X355436Y151756D01*
G01X355451Y151193D02*
X355444Y151608D01*
G01X355456Y150573D02*
X355451Y151193D01*
G01X355458Y149826D02*
X355456Y150573D01*
G01X361802Y134770D02*
X361810Y134621D01*
G01X361795Y135184D02*
X361802Y134770D01*
G01X361790Y135804D02*
X361795Y135184D01*
G01X361788Y136551D02*
X361790Y135804D01*
G01X361806Y135678D02*
X361810Y135605D01*
G01X361803Y135887D02*
X361806Y135678D01*
G01X361800Y136200D02*
X361803Y135887D01*
G01X361799Y136570D02*
X361800Y136200D01*
G01X363314Y150699D02*
X363310Y150772D01*
G01X363317Y150490D02*
X363314Y150699D01*
G01X363320Y150178D02*
X363317Y150490D01*
G01X363321Y149807D02*
X363320Y150178D01*
G01X363318Y151608D02*
X363310Y151756D01*
G01X363325Y151193D02*
X363318Y151608D01*
G01X363330Y150573D02*
X363325Y151193D01*
G01X363332Y149826D02*
X363330Y150573D01*
G01X369676Y134770D02*
X369684Y134621D01*
G01X369669Y135184D02*
X369676Y134770D01*
G01X369664Y135804D02*
X369669Y135184D01*
G01X369662Y136551D02*
X369664Y135804D01*
G01X369680Y135678D02*
X369684Y135605D01*
G01X369677Y135887D02*
X369680Y135678D01*
G01X369674Y136200D02*
X369677Y135887D01*
G01X369673Y136570D02*
X369674Y136200D01*
G01X371188Y150699D02*
X371184Y150772D01*
G01X371191Y150490D02*
X371188Y150699D01*
G01X371194Y150178D02*
X371191Y150490D01*
G01X371195Y149807D02*
X371194Y150178D01*
G01X371192Y151608D02*
X371184Y151756D01*
G01X371199Y151193D02*
X371192Y151608D01*
G01X371204Y150573D02*
X371199Y151193D01*
G01X371206Y149826D02*
X371204Y150573D01*
G01X377550Y134770D02*
X377558Y134621D01*
G01X377543Y135184D02*
X377550Y134770D01*
G01X377538Y135804D02*
X377543Y135184D01*
G01X377536Y136551D02*
X377538Y135804D01*
G01X377554Y135678D02*
X377558Y135605D01*
G01X377551Y135887D02*
X377554Y135678D01*
G01X377548Y136200D02*
X377551Y135887D01*
G01X377547Y136570D02*
X377548Y136200D01*
G01X379062Y150699D02*
X379058Y150772D01*
G01X379065Y150490D02*
X379062Y150699D01*
G01X379068Y150178D02*
X379065Y150490D01*
G01X379069Y149807D02*
X379068Y150178D01*
G01X379066Y151608D02*
X379058Y151756D01*
G01X379073Y151193D02*
X379066Y151608D01*
G01X379078Y150573D02*
X379073Y151193D01*
G01X379080Y149826D02*
X379078Y150573D01*
G01X361790D02*
X361788Y149826D01*
G01X361795Y151193D02*
X361790Y150573D01*
G01X361802Y151608D02*
X361795Y151193D01*
G01X361810Y151756D02*
X361802Y151608D01*
G01X363330Y135804D02*
X363332Y136551D01*
G01X363325Y135184D02*
X363330Y135804D01*
G01X363318Y134770D02*
X363325Y135184D01*
G01X363310Y134621D02*
X363318Y134770D01*
G01X369664Y150573D02*
X369662Y149826D01*
G01X369669Y151193D02*
X369664Y150573D01*
G01X369676Y151608D02*
X369669Y151193D01*
G01X369684Y151756D02*
X369676Y151608D01*
G01X371204Y135804D02*
X371206Y136551D01*
G01X371199Y135184D02*
X371204Y135804D01*
G01X371192Y134770D02*
X371199Y135184D01*
G01X371184Y134621D02*
X371192Y134770D01*
G01X377538Y150573D02*
X377536Y149826D01*
G01X377543Y151193D02*
X377538Y150573D01*
G01X377550Y151608D02*
X377543Y151193D01*
G01X377558Y151756D02*
X377550Y151608D01*
G01X379078Y135804D02*
X379080Y136551D01*
G01X379073Y135184D02*
X379078Y135804D01*
G01X379066Y134770D02*
X379073Y135184D01*
G01X379058Y134621D02*
X379066Y134770D01*
G01X361800Y150178D02*
X361799Y149807D01*
G01X361803Y150490D02*
X361800Y150178D01*
G01X361806Y150699D02*
X361803Y150490D01*
G01X361810Y150772D02*
X361806Y150699D01*
G01X363320Y136200D02*
X363321Y136570D01*
G01X363317Y135887D02*
X363320Y136200D01*
G01X363314Y135678D02*
X363317Y135887D01*
G01X363310Y135605D02*
X363314Y135678D01*
G01X369674Y150178D02*
X369673Y149807D01*
G01X369677Y150490D02*
X369674Y150178D01*
G01X369680Y150699D02*
X369677Y150490D01*
G01X369684Y150772D02*
X369680Y150699D01*
G01X371194Y136200D02*
X371195Y136570D01*
G01X371191Y135887D02*
X371194Y136200D01*
G01X371188Y135678D02*
X371191Y135887D01*
G01X371184Y135605D02*
X371188Y135678D01*
G01X377548Y150178D02*
X377547Y149807D01*
G01X377551Y150490D02*
X377548Y150178D01*
G01X377554Y150699D02*
X377551Y150490D01*
G01X377558Y150772D02*
X377554Y150699D01*
G01X379068Y136200D02*
X379069Y136570D01*
G01X379065Y135887D02*
X379068Y136200D01*
G01X379062Y135678D02*
X379065Y135887D01*
G01X379058Y135605D02*
X379062Y135678D01*
G01X361545Y134965D02*
X361550Y135117D01*
G01X361541Y134866D02*
X361545Y134965D01*
G01X361536Y134824D02*
X361541Y134866D01*
G01X363575Y151413D02*
X363570Y151260D01*
G01X363579Y151511D02*
X363575Y151413D01*
G01X363584Y151553D02*
X363579Y151511D01*
G01X365478Y134965D02*
X365482Y135117D01*
G01X365473Y134866D02*
X365478Y134965D01*
G01X365469Y134824D02*
X365473Y134866D01*
G01X367516Y151413D02*
X367512Y151260D01*
G01X367521Y151511D02*
X367516Y151413D01*
G01X367525Y151553D02*
X367521Y151511D01*
G01X369419Y134965D02*
X369424Y135117D01*
G01X369415Y134866D02*
X369419Y134965D01*
G01X369410Y134824D02*
X369415Y134866D01*
G01X371449Y151413D02*
X371444Y151260D01*
G01X371453Y151511D02*
X371449Y151413D01*
G01X371458Y151553D02*
X371453Y151511D01*
G01X373352Y134965D02*
X373356Y135117D01*
G01X373347Y134866D02*
X373352Y134965D01*
G01X373343Y134824D02*
X373347Y134866D01*
G01X375390Y151413D02*
X375386Y151260D01*
G01X375395Y151511D02*
X375390Y151413D01*
G01X375399Y151553D02*
X375395Y151511D01*
G01X377293Y134965D02*
X377298Y135117D01*
G01X377289Y134866D02*
X377293Y134965D01*
G01X377284Y134824D02*
X377289Y134866D01*
G01X379323Y151413D02*
X379318Y151260D01*
G01X379327Y151511D02*
X379323Y151413D01*
G01X379332Y151553D02*
X379327Y151511D01*
G01X381226Y134965D02*
X381230Y135117D01*
G01X381221Y134866D02*
X381226Y134965D01*
G01X381217Y134824D02*
X381221Y134866D01*
G01X383264Y151413D02*
X383260Y151260D01*
G01X383269Y151511D02*
X383264Y151413D01*
G01X383273Y151553D02*
X383269Y151511D01*
G01X385167Y134965D02*
X385172Y135117D01*
G01X385163Y134866D02*
X385167Y134965D01*
G01X385158Y134824D02*
X385163Y134866D01*
G01X363571Y152353D02*
X363566Y152147D01*
G01X363577Y152484D02*
X363571Y152353D01*
G01X363584Y152538D02*
X363577Y152484D01*
G01X361549Y134024D02*
X361554Y134231D01*
G01X361543Y133893D02*
X361549Y134024D01*
G01X361536Y133840D02*
X361543Y133893D01*
G01X367513Y152353D02*
X367507Y152147D01*
G01X367519Y152484D02*
X367513Y152353D01*
G01X367525Y152538D02*
X367519Y152484D01*
G01X365481Y134024D02*
X365487Y134231D01*
G01X365475Y133893D02*
X365481Y134024D01*
G01X365469Y133840D02*
X365475Y133893D01*
G01X371445Y152353D02*
X371440Y152147D01*
G01X371451Y152484D02*
X371445Y152353D01*
G01X371458Y152538D02*
X371451Y152484D01*
G01X369423Y134024D02*
X369428Y134231D01*
G01X369417Y133893D02*
X369423Y134024D01*
G01X369410Y133840D02*
X369417Y133893D01*
G01X375387Y152353D02*
X375381Y152147D01*
G01X375393Y152484D02*
X375387Y152353D01*
G01X375399Y152538D02*
X375393Y152484D01*
G01X373355Y134024D02*
X373361Y134231D01*
G01X373349Y133893D02*
X373355Y134024D01*
G01X373343Y133840D02*
X373349Y133893D01*
G01X379319Y152353D02*
X379314Y152147D01*
G01X379325Y152484D02*
X379319Y152353D01*
G01X379332Y152538D02*
X379325Y152484D01*
G01X377297Y134024D02*
X377302Y134231D01*
G01X377291Y133893D02*
X377297Y134024D01*
G01X377284Y133840D02*
X377291Y133893D01*
G01X383261Y152353D02*
X383255Y152147D01*
G01X383267Y152484D02*
X383261Y152353D01*
G01X383273Y152538D02*
X383267Y152484D01*
G01X381229Y134024D02*
X381235Y134231D01*
G01X381223Y133893D02*
X381229Y134024D01*
G01X381217Y133840D02*
X381223Y133893D01*
G01X387193Y152353D02*
X387188Y152147D01*
G01X387199Y152484D02*
X387193Y152353D01*
G01X387206Y152538D02*
X387199Y152484D01*
G01X385171Y134024D02*
X385176Y134231D01*
G01X385165Y133893D02*
X385171Y134024D01*
G01X385158Y133840D02*
X385165Y133893D01*
G01X365742Y150209D02*
X365741Y149807D01*
G01X365745Y150537D02*
X365742Y150209D01*
G01X365749Y150733D02*
X365745Y150537D01*
G01X365753Y150762D02*
X365749Y150733D01*
G01X367252Y136168D02*
X367253Y136570D01*
G01X367249Y135841D02*
X367252Y136168D01*
G01X367245Y135645D02*
X367249Y135841D01*
G01X367241Y135615D02*
X367245Y135645D01*
G01X373616Y150209D02*
X373615Y149807D01*
G01X373619Y150537D02*
X373616Y150209D01*
G01X373623Y150733D02*
X373619Y150537D01*
G01X373627Y150762D02*
X373623Y150733D01*
G01X375126Y136168D02*
X375127Y136570D01*
G01X375123Y135841D02*
X375126Y136168D01*
G01X375119Y135645D02*
X375123Y135841D01*
G01X375115Y135615D02*
X375119Y135645D01*
G01X381490Y150209D02*
X381489Y149807D01*
G01X381493Y150537D02*
X381490Y150209D01*
G01X381497Y150733D02*
X381493Y150537D01*
G01X381502Y150762D02*
X381497Y150733D01*
G01X383000Y136168D02*
X383001Y136570D01*
G01X382997Y135841D02*
X383000Y136168D01*
G01X382993Y135645D02*
X382997Y135841D01*
G01X382989Y135615D02*
X382993Y135645D01*
G01X389364Y150209D02*
X389363Y149807D01*
G01X389367Y150537D02*
X389364Y150209D01*
G01X389371Y150733D02*
X389367Y150537D01*
G01X389376Y150762D02*
X389371Y150733D01*
G01X385433Y135610D02*
X385434Y135615D01*
G01X385433Y135606D02*
Y135610D01*
G01X385432Y135605D02*
X385433Y135606D01*
G01X410553Y150768D02*
X410552Y150762D01*
G01X410553Y150771D02*
Y150768D01*
G01X410554Y150772D02*
X410553Y150771D01*
G01X409055Y135610D02*
X409056Y135615D01*
G01X409055Y135606D02*
Y135610D01*
G01X409054Y135605D02*
X409055Y135606D01*
G01X409056Y134624D02*
Y134627D01*
G01X409055Y134622D02*
X409056Y134624D01*
G01X409054Y134621D02*
X409055Y134622D01*
G01X426301Y151754D02*
X426300Y151750D01*
G01X426301Y151756D02*
Y151754D01*
G01X426302Y151756D02*
X426301D01*
G01X416930Y134624D02*
Y134627D01*
G01X416929Y134622D02*
X416930Y134624D01*
G01X416928Y134621D02*
X416929Y134622D01*
G01X424804Y134624D02*
Y134627D01*
G01X424803Y134622D02*
X424804Y134624D01*
G01X424802Y134621D02*
X424803Y134622D01*
G01X424499Y134823D02*
X424483Y134822D01*
G01X424514Y134823D02*
X424499D01*
G01X424529Y134824D02*
X424514Y134823D01*
G01X420557D02*
X420542Y134822D01*
G01X420572Y134823D02*
X420557D01*
G01X420587Y134824D02*
X420572Y134823D01*
G01X416624D02*
X416609Y134822D01*
G01X416639Y134823D02*
X416624D01*
G01X416655Y134824D02*
X416639Y134823D01*
G01X412683D02*
X412668Y134822D01*
G01X412698Y134823D02*
X412683D01*
G01X412713Y134824D02*
X412698Y134823D01*
G01X408750D02*
X408735Y134822D01*
G01X408765Y134823D02*
X408750D01*
G01X408780Y134824D02*
X408765Y134823D01*
G01X404809D02*
X404794Y134822D01*
G01X404824Y134823D02*
X404809D01*
G01X404839Y134824D02*
X404824Y134823D01*
G01X400876D02*
X400861Y134822D01*
G01X400891Y134823D02*
X400876D01*
G01X400906Y134824D02*
X400891Y134823D01*
G01X393002D02*
X392987Y134822D01*
G01X393017Y134823D02*
X393002D01*
G01X393032Y134824D02*
X393017Y134823D01*
G01X385128D02*
X385113Y134822D01*
G01X385143Y134823D02*
X385128D01*
G01X385158Y134824D02*
X385143Y134823D01*
G01X381187D02*
X381172Y134822D01*
G01X381202Y134823D02*
X381187D01*
G01X381217Y134824D02*
X381202Y134823D01*
G01X377254D02*
X377239Y134822D01*
G01X377269Y134823D02*
X377254D01*
G01X377284Y134824D02*
X377269Y134823D01*
G01X373313D02*
X373298Y134822D01*
G01X373328Y134823D02*
X373313D01*
G01X373343Y134824D02*
X373328Y134823D01*
G01X369380D02*
X369365Y134822D01*
G01X369395Y134823D02*
X369380D01*
G01X369410Y134824D02*
X369395Y134823D01*
G01X365439D02*
X365424Y134822D01*
G01X365454Y134823D02*
X365439D01*
G01X365469Y134824D02*
X365454Y134823D01*
G01X361506D02*
X361491Y134822D01*
G01X361521Y134823D02*
X361506D01*
G01X361536Y134824D02*
X361521Y134823D01*
G01X357565D02*
X357550Y134822D01*
G01X357580Y134823D02*
X357565D01*
G01X357595Y134824D02*
X357580Y134823D01*
G01X353632D02*
X353617Y134822D01*
G01X353647Y134823D02*
X353632D01*
G01X353662Y134824D02*
X353647Y134823D01*
G01X349691D02*
X349676Y134822D01*
G01X349706Y134823D02*
X349691D01*
G01X349721Y134824D02*
X349706Y134823D01*
G01X424499Y133838D02*
X424483D01*
G01X424514Y133839D02*
X424499Y133838D01*
G01X424529Y133840D02*
X424514Y133839D01*
G01X420557Y133838D02*
X420542D01*
G01X420572Y133839D02*
X420557Y133838D01*
G01X420587Y133840D02*
X420572Y133839D01*
G01X416624Y133838D02*
X416609D01*
G01X416639Y133839D02*
X416624Y133838D01*
G01X416655Y133840D02*
X416639Y133839D01*
G01X412683Y133838D02*
X412668D01*
G01X412698Y133839D02*
X412683Y133838D01*
G01X412713Y133840D02*
X412698Y133839D01*
G01X408750Y133838D02*
X408735D01*
G01X408765Y133839D02*
X408750Y133838D01*
G01X408780Y133840D02*
X408765Y133839D01*
G01X404809Y133838D02*
X404794D01*
G01X404824Y133839D02*
X404809Y133838D01*
G01X404839Y133840D02*
X404824Y133839D01*
G01X396935Y133838D02*
X396920D01*
G01X396950Y133839D02*
X396935Y133838D01*
G01X396965Y133840D02*
X396950Y133839D01*
G01X389061Y133838D02*
X389046D01*
G01X389076Y133839D02*
X389061Y133838D01*
G01X389091Y133840D02*
X389076Y133839D01*
G01X385128Y133838D02*
X385113D01*
G01X385143Y133839D02*
X385128Y133838D01*
G01X385158Y133840D02*
X385143Y133839D01*
G01X381187Y133838D02*
X381172D01*
G01X381202Y133839D02*
X381187Y133838D01*
G01X381217Y133840D02*
X381202Y133839D01*
G01X377254Y133838D02*
X377239D01*
G01X377269Y133839D02*
X377254Y133838D01*
G01X377284Y133840D02*
X377269Y133839D01*
G01X373313Y133838D02*
X373298D01*
G01X373328Y133839D02*
X373313Y133838D01*
G01X373343Y133840D02*
X373328Y133839D01*
G01X369380Y133838D02*
X369365D01*
G01X369395Y133839D02*
X369380Y133838D01*
G01X369410Y133840D02*
X369395Y133839D01*
G01X365439Y133838D02*
X365424D01*
G01X365454Y133839D02*
X365439Y133838D01*
G01X365469Y133840D02*
X365454Y133839D01*
G01X361506Y133838D02*
X361491D01*
G01X361521Y133839D02*
X361506Y133838D01*
G01X361536Y133840D02*
X361521Y133839D01*
G01X357565Y133838D02*
X357550D01*
G01X357580Y133839D02*
X357565Y133838D01*
G01X357595Y133840D02*
X357580Y133839D01*
G01X353632Y133838D02*
X353617D01*
G01X353647Y133839D02*
X353632Y133838D01*
G01X353662Y133840D02*
X353647Y133839D01*
G01X349691Y133838D02*
X349676D01*
G01X349706Y133839D02*
X349691Y133838D01*
G01X349721Y133840D02*
X349706Y133839D01*
G01X347851D02*
X347836Y133840D01*
G01X347866Y133838D02*
X347851Y133839D01*
G01X347881Y133838D02*
X347866D01*
G01X351783Y133839D02*
X351768Y133840D01*
G01X351798Y133838D02*
X351783Y133839D01*
G01X351813Y133838D02*
X351798D01*
G01X355725Y133839D02*
X355710Y133840D01*
G01X355740Y133838D02*
X355725Y133839D01*
G01X355755Y133838D02*
X355740D01*
G01X359657Y133839D02*
X359642Y133840D01*
G01X359672Y133838D02*
X359657Y133839D01*
G01X359687Y133838D02*
X359672D01*
G01X363599Y133839D02*
X363584Y133840D01*
G01X363614Y133838D02*
X363599Y133839D01*
G01X363629Y133838D02*
X363614D01*
G01X367531Y133839D02*
X367516Y133840D01*
G01X367546Y133838D02*
X367531Y133839D01*
G01X367561Y133838D02*
X367546D01*
G01X371473Y133839D02*
X371458Y133840D01*
G01X371488Y133838D02*
X371473Y133839D01*
G01X371503Y133838D02*
X371488D01*
G01X375405Y133839D02*
X375390Y133840D01*
G01X375420Y133838D02*
X375405Y133839D01*
G01X375435Y133838D02*
X375420D01*
G01X379347Y133839D02*
X379332Y133840D01*
G01X379362Y133838D02*
X379347Y133839D01*
G01X379377Y133838D02*
X379362D01*
G01X383279Y133839D02*
X383264Y133840D01*
G01X383294Y133838D02*
X383279Y133839D01*
G01X383309Y133838D02*
X383294D01*
G01X387221Y133839D02*
X387206Y133840D01*
G01X387236Y133838D02*
X387221Y133839D01*
G01X387251Y133838D02*
X387236D01*
G01X391153Y133839D02*
X391138Y133840D01*
G01X391168Y133838D02*
X391153Y133839D01*
G01X391183Y133838D02*
X391168D01*
G01X395095Y133839D02*
X395080Y133840D01*
G01X395110Y133838D02*
X395095Y133839D01*
G01X395125Y133838D02*
X395110D01*
G01X399027Y133839D02*
X399012Y133840D01*
G01X399042Y133838D02*
X399027Y133839D01*
G01X399057Y133838D02*
X399042D01*
G01X402969Y133839D02*
X402954Y133840D01*
G01X402984Y133838D02*
X402969Y133839D01*
G01X402999Y133838D02*
X402984D01*
G01X406901Y133839D02*
X406886Y133840D01*
G01X406916Y133838D02*
X406901Y133839D01*
G01X406931Y133838D02*
X406916D01*
G01X410843Y133839D02*
X410828Y133840D01*
G01X410858Y133838D02*
X410843Y133839D01*
G01X410873Y133838D02*
X410858D01*
G01X414775Y133839D02*
X414760Y133840D01*
G01X414790Y133838D02*
X414775Y133839D01*
G01X414805Y133838D02*
X414790D01*
G01X418717Y133839D02*
X418702Y133840D01*
G01X418732Y133838D02*
X418717Y133839D01*
G01X418747Y133838D02*
X418732D01*
G01X422649Y133839D02*
X422634Y133840D01*
G01X422664Y133838D02*
X422649Y133839D01*
G01X422679Y133838D02*
X422664D01*
G01X426591Y133839D02*
X426576Y133840D01*
G01X426606Y133838D02*
X426591Y133839D01*
G01X426621Y133838D02*
X426606D01*
G01X347851Y134823D02*
X347836Y134824D01*
G01X347866Y134823D02*
X347851D01*
G01X347881Y134822D02*
X347866Y134823D01*
G01X351783D02*
X351768Y134824D01*
G01X351798Y134823D02*
X351783D01*
G01X351813Y134822D02*
X351798Y134823D01*
G01X355725D02*
X355710Y134824D01*
G01X355740Y134823D02*
X355725D01*
G01X355755Y134822D02*
X355740Y134823D01*
G01X359657D02*
X359642Y134824D01*
G01X359672Y134823D02*
X359657D01*
G01X359687Y134822D02*
X359672Y134823D01*
G01X363599D02*
X363584Y134824D01*
G01X363614Y134823D02*
X363599D01*
G01X363629Y134822D02*
X363614Y134823D01*
G01X367531D02*
X367516Y134824D01*
G01X367546Y134823D02*
X367531D01*
G01X367561Y134822D02*
X367546Y134823D01*
G01X371473D02*
X371458Y134824D01*
G01X371488Y134823D02*
X371473D01*
G01X371503Y134822D02*
X371488Y134823D01*
G01X375405D02*
X375390Y134824D01*
G01X375420Y134823D02*
X375405D01*
G01X375435Y134822D02*
X375420Y134823D01*
G01X379347D02*
X379332Y134824D01*
G01X379362Y134823D02*
X379347D01*
G01X379377Y134822D02*
X379362Y134823D01*
G01X383279D02*
X383264Y134824D01*
G01X383294Y134823D02*
X383279D01*
G01X383309Y134822D02*
X383294Y134823D01*
G01X387221D02*
X387206Y134824D01*
G01X387236Y134823D02*
X387221D01*
G01X387251Y134822D02*
X387236Y134823D01*
G01X395095D02*
X395080Y134824D01*
G01X395110Y134823D02*
X395095D01*
G01X395125Y134822D02*
X395110Y134823D01*
G01X402969D02*
X402954Y134824D01*
G01X402984Y134823D02*
X402969D01*
G01X402999Y134822D02*
X402984Y134823D01*
G01X406901D02*
X406886Y134824D01*
G01X406916Y134823D02*
X406901D01*
G01X406931Y134822D02*
X406916Y134823D01*
G01X410843D02*
X410828Y134824D01*
G01X410858Y134823D02*
X410843D01*
G01X410873Y134822D02*
X410858Y134823D01*
G01X414775D02*
X414760Y134824D01*
G01X414790Y134823D02*
X414775D01*
G01X414805Y134822D02*
X414790Y134823D01*
G01X418717D02*
X418702Y134824D01*
G01X418732Y134823D02*
X418717D01*
G01X418747Y134822D02*
X418732Y134823D01*
G01X422649D02*
X422634Y134824D01*
G01X422664Y134823D02*
X422649D01*
G01X422679Y134822D02*
X422664Y134823D01*
G01X426591D02*
X426576Y134824D01*
G01X426606Y134823D02*
X426591D01*
G01X426621Y134822D02*
X426606Y134823D01*
G01X347561Y134622D02*
X347562Y134621D01*
G01X347561Y134624D02*
Y134622D01*
G01X347560Y134627D02*
X347561Y134624D01*
G01X355435Y134622D02*
X355436Y134621D01*
G01X355435Y134624D02*
Y134622D01*
G01X355434Y134627D02*
X355435Y134624D01*
G01X353937Y151756D02*
X353936D01*
G01X353937Y151754D02*
Y151756D01*
G01X353938Y151750D02*
X353937Y151754D01*
G01X363309Y134622D02*
X363310Y134621D01*
G01X363309Y134624D02*
Y134622D01*
G01X363308Y134627D02*
X363309Y134624D01*
G01X361811Y151756D02*
X361810D01*
G01X361811Y151754D02*
Y151756D01*
G01X361812Y151750D02*
X361811Y151754D01*
G01X371183Y134622D02*
X371184Y134621D01*
G01X371183Y134624D02*
Y134622D01*
G01X371182Y134627D02*
X371183Y134624D01*
G01X377559Y150771D02*
X377558Y150772D01*
G01X377559Y150768D02*
Y150771D01*
G01X377560Y150762D02*
X377559Y150768D01*
G01X379057Y135606D02*
X379058Y135605D01*
G01X379057Y135610D02*
Y135606D01*
G01X379056Y135615D02*
X379057Y135610D01*
G01X385433Y150771D02*
X385432Y150772D01*
G01X385433Y150768D02*
Y150771D01*
G01X385434Y150762D02*
X385433Y150768D01*
G01X386931Y135606D02*
X386932Y135605D01*
G01X386931Y135610D02*
Y135606D01*
G01X386930Y135615D02*
X386931Y135610D01*
G01X393296Y136197D02*
X393295Y136570D01*
G01X393299Y135887D02*
X393296Y136197D01*
G01X393302Y135680D02*
X393299Y135887D01*
G01X393306Y135605D02*
X393302Y135680D01*
G01X394816Y150180D02*
X394817Y149807D01*
G01X394813Y150490D02*
X394816Y150180D01*
G01X394810Y150698D02*
X394813Y150490D01*
G01X394806Y150772D02*
X394810Y150698D01*
G01X401170Y136197D02*
X401169Y136570D01*
G01X401173Y135887D02*
X401170Y136197D01*
G01X401176Y135680D02*
X401173Y135887D01*
G01X401180Y135605D02*
X401176Y135680D01*
G01X379325Y133893D02*
X379332Y133840D01*
G01X379319Y134024D02*
X379325Y133893D01*
G01X379314Y134231D02*
X379319Y134024D01*
G01X381232Y152484D02*
X381226Y152538D01*
G01X381238Y152353D02*
X381232Y152484D01*
G01X381244Y152147D02*
X381238Y152353D01*
G01X383258Y133893D02*
X383264Y133840D01*
G01X383252Y134024D02*
X383258Y133893D01*
G01X383246Y134231D02*
X383252Y134024D01*
G01X385165Y152484D02*
X385158Y152538D01*
G01X385171Y152353D02*
X385165Y152484D01*
G01X385176Y152147D02*
X385171Y152353D01*
G01X387199Y133893D02*
X387206Y133840D01*
G01X387193Y134024D02*
X387199Y133893D01*
G01X387188Y134231D02*
X387193Y134024D01*
G01X389106Y152484D02*
X389100Y152538D01*
G01X389112Y152353D02*
X389106Y152484D01*
G01X389118Y152147D02*
X389112Y152353D01*
G01X391132Y133893D02*
X391138Y133840D01*
G01X391126Y134024D02*
X391132Y133893D01*
G01X391120Y134231D02*
X391126Y134024D01*
G01X393039Y152484D02*
X393032Y152538D01*
G01X393045Y152353D02*
X393039Y152484D01*
G01X393050Y152147D02*
X393045Y152353D01*
G01X395074Y133893D02*
X395080Y133840D01*
G01X395067Y134024D02*
X395074Y133893D01*
G01X395062Y134231D02*
X395067Y134024D01*
G01X396980Y152484D02*
X396974Y152538D01*
G01X396986Y152353D02*
X396980Y152484D01*
G01X396992Y152147D02*
X396986Y152353D01*
G01X399006Y133893D02*
X399012Y133840D01*
G01X399000Y134024D02*
X399006Y133893D01*
G01X398994Y134231D02*
X399000Y134024D01*
G01X400913Y152484D02*
X400906Y152538D01*
G01X400919Y152353D02*
X400913Y152484D01*
G01X400924Y152147D02*
X400919Y152353D01*
G01X379327Y134866D02*
X379332Y134824D01*
G01X379323Y134965D02*
X379327Y134866D01*
G01X379318Y135117D02*
X379323Y134965D01*
G01X381231Y151511D02*
X381226Y151553D01*
G01X381235Y151413D02*
X381231Y151511D01*
G01X381239Y151260D02*
X381235Y151413D01*
G01X383259Y134866D02*
X383264Y134824D01*
G01X383255Y134965D02*
X383259Y134866D01*
G01X383251Y135117D02*
X383255Y134965D01*
G01X385163Y151511D02*
X385158Y151553D01*
G01X385167Y151413D02*
X385163Y151511D01*
G01X385172Y151260D02*
X385167Y151413D01*
G01X387201Y134866D02*
X387206Y134824D01*
G01X387197Y134965D02*
X387201Y134866D01*
G01X387192Y135117D02*
X387197Y134965D01*
G01X389105Y151511D02*
X389100Y151553D01*
G01X389109Y151413D02*
X389105Y151511D01*
G01X389113Y151260D02*
X389109Y151413D01*
G01X391133Y134866D02*
X391138Y134824D01*
G01X391129Y134965D02*
X391133Y134866D01*
G01X391125Y135117D02*
X391129Y134965D01*
G01X393037Y151511D02*
X393032Y151553D01*
G01X393041Y151413D02*
X393037Y151511D01*
G01X393046Y151260D02*
X393041Y151413D01*
G01X395075Y134866D02*
X395080Y134824D01*
G01X395071Y134965D02*
X395075Y134866D01*
G01X395066Y135117D02*
X395071Y134965D01*
G01X396979Y151511D02*
X396974Y151553D01*
G01X396983Y151413D02*
X396979Y151511D01*
G01X396987Y151260D02*
X396983Y151413D01*
G01X399007Y134866D02*
X399012Y134824D01*
G01X399003Y134965D02*
X399007Y134866D01*
G01X398999Y135117D02*
X399003Y134965D01*
G01X400911Y151511D02*
X400906Y151553D01*
G01X400915Y151413D02*
X400911Y151511D01*
G01X400920Y151260D02*
X400915Y151413D01*
G01X381488Y135645D02*
X381492Y135615D01*
G01X381484Y135841D02*
X381488Y135645D01*
G01X381481Y136168D02*
X381484Y135841D01*
G01X381480Y136570D02*
X381481Y136168D01*
G01X383003Y150733D02*
X382998Y150762D01*
G01X383007Y150537D02*
X383003Y150733D01*
G01X383009Y150209D02*
X383007Y150537D01*
G01X383010Y149807D02*
X383009Y150209D01*
G01X389362Y135645D02*
X389366Y135615D01*
G01X389358Y135841D02*
X389362Y135645D01*
G01X389355Y136168D02*
X389358Y135841D01*
G01X389354Y136570D02*
X389355Y136168D01*
G01X390877Y150733D02*
X390872Y150762D01*
G01X390881Y150537D02*
X390877Y150733D01*
G01X390883Y150209D02*
X390881Y150537D01*
G01X390884Y149807D02*
X390883Y150209D01*
G01X397236Y135645D02*
X397240Y135615D01*
G01X397232Y135841D02*
X397236Y135645D01*
G01X397229Y136168D02*
X397232Y135841D01*
G01X397228Y136570D02*
X397229Y136168D01*
G01X398751Y150733D02*
X398746Y150762D01*
G01X398755Y150537D02*
X398751Y150733D01*
G01X398757Y150209D02*
X398755Y150537D01*
G01X398758Y149807D02*
X398757Y150209D01*
G01X385424Y134770D02*
X385432Y134621D01*
G01X385417Y135184D02*
X385424Y134770D01*
G01X385412Y135804D02*
X385417Y135184D01*
G01X385410Y136551D02*
X385412Y135804D01*
G01X385428Y135678D02*
X385432Y135605D01*
G01X385425Y135887D02*
X385428Y135678D01*
G01X385422Y136200D02*
X385425Y135887D01*
G01X385421Y136570D02*
X385422Y136200D01*
G01X386936Y150699D02*
X386932Y150772D01*
G01X386939Y150490D02*
X386936Y150699D01*
G01X386942Y150178D02*
X386939Y150490D01*
G01X386943Y149807D02*
X386942Y150178D01*
G01X386940Y151608D02*
X386932Y151756D01*
G01X386947Y151193D02*
X386940Y151608D01*
G01X386952Y150573D02*
X386947Y151193D01*
G01X386954Y149826D02*
X386952Y150573D01*
G01X393298Y134770D02*
X393306Y134621D01*
G01X393291Y135184D02*
X393298Y134770D01*
G01X393286Y135804D02*
X393291Y135184D01*
G01X393284Y136551D02*
X393286Y135804D01*
G01X394814Y151608D02*
X394806Y151756D01*
G01X394821Y151193D02*
X394814Y151608D01*
G01X394826Y150573D02*
X394821Y151193D01*
G01X394828Y149826D02*
X394826Y150573D01*
G01X401172Y134770D02*
X401180Y134621D01*
G01X401165Y135184D02*
X401172Y134770D01*
G01X401160Y135804D02*
X401165Y135184D01*
G01X401158Y136551D02*
X401160Y135804D01*
G01X402688Y151608D02*
X402680Y151756D01*
G01X402695Y151193D02*
X402688Y151608D01*
G01X402700Y150573D02*
X402695Y151193D01*
G01X402702Y149826D02*
X402700Y150573D01*
G01X393302Y150698D02*
X393306Y150772D01*
G01X393299Y150490D02*
X393302Y150698D01*
G01X393296Y150180D02*
X393299Y150490D01*
G01X393295Y149807D02*
X393296Y150180D01*
G01X394810Y135680D02*
X394806Y135605D01*
G01X394813Y135887D02*
X394810Y135680D01*
G01X394816Y136197D02*
X394813Y135887D01*
G01X394817Y136570D02*
X394816Y136197D01*
G01X401176Y150698D02*
X401180Y150772D01*
G01X401173Y150490D02*
X401176Y150698D01*
G01X401170Y150180D02*
X401173Y150490D01*
G01X401169Y149807D02*
X401170Y150180D01*
G01X402684Y135680D02*
X402680Y135605D01*
G01X402688Y135887D02*
X402684Y135680D01*
G01X402690Y136197D02*
X402688Y135887D01*
G01X402691Y136570D02*
X402690Y136197D01*
G01X385412Y150573D02*
X385410Y149826D01*
G01X385417Y151193D02*
X385412Y150573D01*
G01X385424Y151608D02*
X385417Y151193D01*
G01X385432Y151756D02*
X385424Y151608D01*
G01X386952Y135804D02*
X386954Y136551D01*
G01X386947Y135184D02*
X386952Y135804D01*
G01X386940Y134770D02*
X386947Y135184D01*
G01X386932Y134621D02*
X386940Y134770D01*
G01X393286Y150573D02*
X393284Y149826D01*
G01X393291Y151193D02*
X393286Y150573D01*
G01X393298Y151608D02*
X393291Y151193D01*
G01X393306Y151756D02*
X393298Y151608D01*
G01X394826Y135804D02*
X394828Y136551D01*
G01X394821Y135184D02*
X394826Y135804D01*
G01X394814Y134770D02*
X394821Y135184D01*
G01X394806Y134621D02*
X394814Y134770D01*
G01X401160Y150573D02*
X401158Y149826D01*
G01X401165Y151193D02*
X401160Y150573D01*
G01X401172Y151608D02*
X401165Y151193D01*
G01X401180Y151756D02*
X401172Y151608D01*
G01X402700Y135804D02*
X402702Y136551D01*
G01X402695Y135184D02*
X402700Y135804D01*
G01X402688Y134770D02*
X402695Y135184D01*
G01X402680Y134621D02*
X402688Y134770D01*
G01X385422Y150178D02*
X385421Y149807D01*
G01X385425Y150490D02*
X385422Y150178D01*
G01X385428Y150699D02*
X385425Y150490D01*
G01X385432Y150772D02*
X385428Y150699D01*
G01X386942Y136200D02*
X386943Y136570D01*
G01X386939Y135887D02*
X386942Y136200D01*
G01X386936Y135678D02*
X386939Y135887D01*
G01X386932Y135605D02*
X386936Y135678D01*
G01X393307Y135606D02*
X393306Y135605D01*
G01X393307Y135610D02*
Y135606D01*
G01X393308Y135617D02*
X393307Y135610D01*
G01X394805Y150771D02*
X394806Y150772D01*
G01X394805Y150768D02*
Y150771D01*
G01X394804Y150760D02*
X394805Y150768D01*
G01X401181Y135606D02*
X401180Y135605D01*
G01X401181Y135610D02*
Y135606D01*
G01X401182Y135617D02*
X401181Y135610D01*
G01X402679Y150771D02*
X402680Y150772D01*
G01X402679Y150768D02*
Y150771D01*
G01X402678Y150760D02*
X402679Y150768D01*
G01X387197Y151413D02*
X387192Y151260D01*
G01X387201Y151511D02*
X387197Y151413D01*
G01X387206Y151553D02*
X387201Y151511D01*
G01X389100Y134965D02*
X389104Y135117D01*
G01X389095Y134866D02*
X389100Y134965D01*
G01X389091Y134824D02*
X389095Y134866D01*
G01X391138Y151413D02*
X391134Y151260D01*
G01X391143Y151511D02*
X391138Y151413D01*
G01X391147Y151553D02*
X391143Y151511D01*
G01X393041Y134965D02*
X393046Y135117D01*
G01X393037Y134866D02*
X393041Y134965D01*
G01X393032Y134824D02*
X393037Y134866D01*
G01X395071Y151413D02*
X395066Y151260D01*
G01X395075Y151511D02*
X395071Y151413D01*
G01X395080Y151553D02*
X395075Y151511D01*
G01X396974Y134965D02*
X396978Y135117D01*
G01X396969Y134866D02*
X396974Y134965D01*
G01X396965Y134824D02*
X396969Y134866D01*
G01X399012Y151413D02*
X399008Y151260D01*
G01X399017Y151511D02*
X399012Y151413D01*
G01X399021Y151553D02*
X399017Y151511D01*
G01X400915Y134965D02*
X400920Y135117D01*
G01X400911Y134866D02*
X400915Y134965D01*
G01X400906Y134824D02*
X400911Y134866D01*
G01X402945Y151413D02*
X402941Y151260D01*
G01X402949Y151511D02*
X402945Y151413D01*
G01X402954Y151553D02*
X402949Y151511D01*
G01X404848Y134965D02*
X404852Y135117D01*
G01X404843Y134866D02*
X404848Y134965D01*
G01X404839Y134824D02*
X404843Y134866D01*
G01X406886Y151413D02*
X406882Y151260D01*
G01X406891Y151511D02*
X406886Y151413D01*
G01X406895Y151553D02*
X406891Y151511D01*
G01X408789Y134965D02*
X408794Y135117D01*
G01X408785Y134866D02*
X408789Y134965D01*
G01X408780Y134824D02*
X408785Y134866D01*
G01X410819Y151413D02*
X410815Y151260D01*
G01X410823Y151511D02*
X410819Y151413D01*
G01X410828Y151553D02*
X410823Y151511D01*
G01X391135Y152353D02*
X391129Y152147D01*
G01X391141Y152484D02*
X391135Y152353D01*
G01X391147Y152538D02*
X391141Y152484D01*
G01X389103Y134024D02*
X389109Y134231D01*
G01X389097Y133893D02*
X389103Y134024D01*
G01X389091Y133840D02*
X389097Y133893D01*
G01X395067Y152353D02*
X395062Y152147D01*
G01X395074Y152484D02*
X395067Y152353D01*
G01X395080Y152538D02*
X395074Y152484D01*
G01X393045Y134024D02*
X393050Y134231D01*
G01X393039Y133893D02*
X393045Y134024D01*
G01X393032Y133840D02*
X393039Y133893D01*
G01X399009Y152353D02*
X399003Y152147D01*
G01X399015Y152484D02*
X399009Y152353D01*
G01X399021Y152538D02*
X399015Y152484D01*
G01X396977Y134024D02*
X396983Y134231D01*
G01X396971Y133893D02*
X396977Y134024D01*
G01X396965Y133840D02*
X396971Y133893D01*
G01X402941Y152353D02*
X402936Y152147D01*
G01X402948Y152484D02*
X402941Y152353D01*
G01X402954Y152538D02*
X402948Y152484D01*
G01X400919Y134024D02*
X400924Y134231D01*
G01X400913Y133893D02*
X400919Y134024D01*
G01X400906Y133840D02*
X400913Y133893D01*
G01X406883Y152353D02*
X406877Y152147D01*
G01X406889Y152484D02*
X406883Y152353D01*
G01X406895Y152538D02*
X406889Y152484D01*
G01X404851Y134024D02*
X404857Y134231D01*
G01X404845Y133893D02*
X404851Y134024D01*
G01X404839Y133840D02*
X404845Y133893D01*
G01X410816Y152353D02*
X410810Y152147D01*
G01X410822Y152484D02*
X410816Y152353D01*
G01X410828Y152538D02*
X410822Y152484D01*
G01X408793Y134024D02*
X408798Y134231D01*
G01X408787Y133893D02*
X408793Y134024D01*
G01X408780Y133840D02*
X408787Y133893D01*
G01X390874Y136168D02*
X390875Y136570D01*
G01X390871Y135841D02*
X390874Y136168D01*
G01X390867Y135645D02*
X390871Y135841D01*
G01X390863Y135615D02*
X390867Y135645D01*
G01X397238Y150209D02*
X397237Y149807D01*
G01X397241Y150537D02*
X397238Y150209D01*
G01X397245Y150733D02*
X397241Y150537D01*
G01X397250Y150762D02*
X397245Y150733D01*
G01X398748Y136168D02*
X398749Y136570D01*
G01X398745Y135841D02*
X398748Y136168D01*
G01X398741Y135645D02*
X398745Y135841D01*
G01X398737Y135615D02*
X398741Y135645D01*
G01X405112Y150209D02*
X405111Y149807D01*
G01X405115Y150537D02*
X405112Y150209D01*
G01X405119Y150733D02*
X405115Y150537D01*
G01X405124Y150762D02*
X405119Y150733D01*
G01X406622Y136168D02*
X406623Y136570D01*
G01X406619Y135841D02*
X406622Y136168D01*
G01X406615Y135645D02*
X406619Y135841D01*
G01X406611Y135615D02*
X406615Y135645D01*
G01X412986Y150209D02*
X412985Y149807D01*
G01X412989Y150537D02*
X412986Y150209D01*
G01X412993Y150733D02*
X412989Y150537D01*
G01X412998Y150762D02*
X412993Y150733D01*
G01X418427Y150768D02*
X418426Y150762D01*
G01X418427Y150771D02*
Y150768D01*
G01X418428Y150772D02*
X418427Y150771D01*
G01X416929Y135610D02*
X416930Y135615D01*
G01X416929Y135606D02*
Y135610D01*
G01X416928Y135605D02*
X416929Y135606D01*
G01X426301Y150768D02*
X426300Y150762D01*
G01X426301Y150771D02*
Y150768D01*
G01X426302Y150772D02*
X426301Y150771D01*
G01X424803Y135610D02*
X424804Y135615D01*
G01X424803Y135606D02*
Y135610D01*
G01X424802Y135605D02*
X424803Y135606D01*
G01X426606Y151555D02*
X426621D01*
G01X426591Y151554D02*
X426606Y151555D01*
G01X426576Y151553D02*
X426591Y151554D01*
G01X422673Y151555D02*
X422688D01*
G01X422658Y151554D02*
X422673Y151555D01*
G01X422643Y151553D02*
X422658Y151554D01*
G01X418732Y151555D02*
X418747D01*
G01X418717Y151554D02*
X418732Y151555D01*
G01X418702Y151553D02*
X418717Y151554D01*
G01X410858Y151555D02*
X410873D01*
G01X410843Y151554D02*
X410858Y151555D01*
G01X410828Y151553D02*
X410843Y151554D01*
G01X402984Y151555D02*
X402999D01*
G01X402969Y151554D02*
X402984Y151555D01*
G01X402954Y151553D02*
X402969Y151554D01*
G01X399051Y151555D02*
X399066D01*
G01X399036Y151554D02*
X399051Y151555D01*
G01X399021Y151553D02*
X399036Y151554D01*
G01X395110Y151555D02*
X395125D01*
G01X395095Y151554D02*
X395110Y151555D01*
G01X395080Y151553D02*
X395095Y151554D01*
G01X391177Y151555D02*
X391192D01*
G01X391162Y151554D02*
X391177Y151555D01*
G01X391147Y151553D02*
X391162Y151554D01*
G01X387236Y151555D02*
X387251D01*
G01X387221Y151554D02*
X387236Y151555D01*
G01X387206Y151553D02*
X387221Y151554D01*
G01X383303Y151555D02*
X383318D01*
G01X383288Y151554D02*
X383303Y151555D01*
G01X383273Y151553D02*
X383288Y151554D01*
G01X379362Y151555D02*
X379377D01*
G01X379347Y151554D02*
X379362Y151555D01*
G01X379332Y151553D02*
X379347Y151554D01*
G01X371488Y151555D02*
X371503D01*
G01X371473Y151554D02*
X371488Y151555D01*
G01X371458Y151553D02*
X371473Y151554D01*
G01X363614Y151555D02*
X363629D01*
G01X363599Y151554D02*
X363614Y151555D01*
G01X363584Y151553D02*
X363599Y151554D01*
G01X359681Y151555D02*
X359696D01*
G01X359666Y151554D02*
X359681Y151555D01*
G01X359651Y151553D02*
X359666Y151554D01*
G01X355740Y151555D02*
X355755D01*
G01X355725Y151554D02*
X355740Y151555D01*
G01X355710Y151553D02*
X355725Y151554D01*
G01X351807Y151555D02*
X351822D01*
G01X351792Y151554D02*
X351807Y151555D01*
G01X351777Y151553D02*
X351792Y151554D01*
G01X347866Y151555D02*
X347881D01*
G01X347851Y151554D02*
X347866Y151555D01*
G01X347836Y151553D02*
X347851Y151554D01*
G01X426606Y152539D02*
X426621D01*
G01X426591Y152538D02*
X426606Y152539D01*
G01X426576Y152538D02*
X426591D01*
G01X422673Y152539D02*
X422688D01*
G01X422658Y152538D02*
X422673Y152539D01*
G01X422643Y152538D02*
X422658D01*
G01X418732Y152539D02*
X418747D01*
G01X418717Y152538D02*
X418732Y152539D01*
G01X418702Y152538D02*
X418717D01*
G01X414799Y152539D02*
X414814D01*
G01X414784Y152538D02*
X414799Y152539D01*
G01X414769Y152538D02*
X414784D01*
G01X410858Y152539D02*
X410873D01*
G01X410843Y152538D02*
X410858Y152539D01*
G01X410828Y152538D02*
X410843D01*
G01X406925Y152539D02*
X406940D01*
G01X406910Y152538D02*
X406925Y152539D01*
G01X406895Y152538D02*
X406910D01*
G01X391177Y152539D02*
X391192D01*
G01X391162Y152538D02*
X391177Y152539D01*
G01X391147Y152538D02*
X391162D01*
G01X387236Y152539D02*
X387251D01*
G01X387221Y152538D02*
X387236Y152539D01*
G01X387206Y152538D02*
X387221D01*
G01X383303Y152539D02*
X383318D01*
G01X383288Y152538D02*
X383303Y152539D01*
G01X383273Y152538D02*
X383288D01*
G01X379362Y152539D02*
X379377D01*
G01X379347Y152538D02*
X379362Y152539D01*
G01X379332Y152538D02*
X379347D01*
G01X375429Y152539D02*
X375444D01*
G01X375414Y152538D02*
X375429Y152539D01*
G01X375399Y152538D02*
X375414D01*
G01X371488Y152539D02*
X371503D01*
G01X371473Y152538D02*
X371488Y152539D01*
G01X371458Y152538D02*
X371473D01*
G01X367555Y152539D02*
X367570D01*
G01X367540Y152538D02*
X367555Y152539D01*
G01X367525Y152538D02*
X367540D01*
G01X363614Y152539D02*
X363629D01*
G01X363599Y152538D02*
X363614Y152539D01*
G01X363584Y152538D02*
X363599D01*
G01X359681Y152539D02*
X359696D01*
G01X359666Y152538D02*
X359681Y152539D01*
G01X359651Y152538D02*
X359666D01*
G01X355740Y152539D02*
X355755D01*
G01X355725Y152538D02*
X355740Y152539D01*
G01X355710Y152538D02*
X355725D01*
G01X351807Y152539D02*
X351822D01*
G01X351792Y152538D02*
X351807Y152539D01*
G01X351777Y152538D02*
X351792D01*
G01X347866Y152539D02*
X347881D01*
G01X347851Y152538D02*
X347866Y152539D01*
G01X347836Y152538D02*
X347851D01*
G01X349715D02*
X349730D01*
G01X349700Y152539D02*
X349715Y152538D01*
G01X349685Y152539D02*
X349700D01*
G01X353647Y152538D02*
X353662D01*
G01X353632Y152539D02*
X353647Y152538D01*
G01X353617Y152539D02*
X353632D01*
G01X357589Y152538D02*
X357604D01*
G01X357574Y152539D02*
X357589Y152538D01*
G01X357559Y152539D02*
X357574D01*
G01X361521Y152538D02*
X361536D01*
G01X361506Y152539D02*
X361521Y152538D01*
G01X361491Y152539D02*
X361506D01*
G01X365463Y152538D02*
X365478D01*
G01X365448Y152539D02*
X365463Y152538D01*
G01X365433Y152539D02*
X365448D01*
G01X369395Y152538D02*
X369410D01*
G01X369380Y152539D02*
X369395Y152538D01*
G01X369365Y152539D02*
X369380D01*
G01X373337Y152538D02*
X373352D01*
G01X373322Y152539D02*
X373337Y152538D01*
G01X373307Y152539D02*
X373322D01*
G01X377269Y152538D02*
X377284D01*
G01X377254Y152539D02*
X377269Y152538D01*
G01X377239Y152539D02*
X377254D01*
G01X381211Y152538D02*
X381226D01*
G01X381196Y152539D02*
X381211Y152538D01*
G01X381181Y152539D02*
X381196D01*
G01X385143Y152538D02*
X385158D01*
G01X385128Y152539D02*
X385143Y152538D01*
G01X385113Y152539D02*
X385128D01*
G01X389085Y152538D02*
X389100D01*
G01X389070Y152539D02*
X389085Y152538D01*
G01X389055Y152539D02*
X389070D01*
G01X393017Y152538D02*
X393032D01*
G01X393002Y152539D02*
X393017Y152538D01*
G01X392987Y152539D02*
X393002D01*
G01X396959Y152538D02*
X396974D01*
G01X396944Y152539D02*
X396959Y152538D01*
G01X396929Y152539D02*
X396944D01*
G01X400891Y152538D02*
X400906D01*
G01X400876Y152539D02*
X400891Y152538D01*
G01X400861Y152539D02*
X400876D01*
G01X404833Y152538D02*
X404848D01*
G01X404818Y152539D02*
X404833Y152538D01*
G01X404803Y152539D02*
X404818D01*
G01X408765Y152538D02*
X408780D01*
G01X408750Y152539D02*
X408765Y152538D01*
G01X408735Y152539D02*
X408750D01*
G01X412707Y152538D02*
X412722D01*
G01X412692Y152539D02*
X412707Y152538D01*
G01X412677Y152539D02*
X412692D01*
G01X416639Y152538D02*
X416655D01*
G01X416624Y152539D02*
X416639Y152538D01*
G01X416609Y152539D02*
X416624D01*
G01X420581Y152538D02*
X420596D01*
G01X420566Y152539D02*
X420581Y152538D01*
G01X420551Y152539D02*
X420566D01*
G01X424514Y152538D02*
X424529D01*
G01X424499Y152539D02*
X424514Y152538D01*
G01X424483Y152539D02*
X424499D01*
G01X353647Y151554D02*
X353662Y151553D01*
G01X353632Y151555D02*
X353647Y151554D01*
G01X353617Y151555D02*
X353632D01*
G01X361521Y151554D02*
X361536Y151553D01*
G01X361506Y151555D02*
X361521Y151554D01*
G01X361491Y151555D02*
X361506D01*
G01X365463Y151554D02*
X365478Y151553D01*
G01X365448Y151555D02*
X365463Y151554D01*
G01X365433Y151555D02*
X365448D01*
G01X369395Y151554D02*
X369410Y151553D01*
G01X369380Y151555D02*
X369395Y151554D01*
G01X369365Y151555D02*
X369380D01*
G01X373337Y151554D02*
X373352Y151553D01*
G01X373322Y151555D02*
X373337Y151554D01*
G01X373307Y151555D02*
X373322D01*
G01X377269Y151554D02*
X377284Y151553D01*
G01X377254Y151555D02*
X377269Y151554D01*
G01X377239Y151555D02*
X377254D01*
G01X385143Y151554D02*
X385158Y151553D01*
G01X385128Y151555D02*
X385143Y151554D01*
G01X385113Y151555D02*
X385128D01*
G01X389085Y151554D02*
X389100Y151553D01*
G01X389070Y151555D02*
X389085Y151554D01*
G01X389055Y151555D02*
X389070D01*
G01X393017Y151554D02*
X393032Y151553D01*
G01X393002Y151555D02*
X393017Y151554D01*
G01X392987Y151555D02*
X393002D01*
G01X396959Y151554D02*
X396974Y151553D01*
G01X396944Y151555D02*
X396959Y151554D01*
G01X396929Y151555D02*
X396944D01*
G01X400891Y151554D02*
X400906Y151553D01*
G01X400876Y151555D02*
X400891Y151554D01*
G01X400861Y151555D02*
X400876D01*
G01X404833Y151554D02*
X404848Y151553D01*
G01X404818Y151555D02*
X404833Y151554D01*
G01X404803Y151555D02*
X404818D01*
G01X408765Y151554D02*
X408780Y151553D01*
G01X408750Y151555D02*
X408765Y151554D01*
G01X408735Y151555D02*
X408750D01*
G01X412707Y151554D02*
X412722Y151553D01*
G01X412692Y151555D02*
X412707Y151554D01*
G01X412677Y151555D02*
X412692D01*
G01X416639Y151554D02*
X416655Y151553D01*
G01X416624Y151555D02*
X416639Y151554D01*
G01X416609Y151555D02*
X416624D01*
G01X424514Y151554D02*
X424529Y151553D01*
G01X424499Y151555D02*
X424514Y151554D01*
G01X424483Y151555D02*
X424499D01*
G01X391168Y134823D02*
X391183Y134822D01*
G01X391153Y134823D02*
X391168D01*
G01X391138Y134824D02*
X391153Y134823D01*
G01X399042D02*
X399057Y134822D01*
G01X399027Y134823D02*
X399042D01*
G01X399012Y134824D02*
X399027Y134823D01*
G01X349700Y151555D02*
X349685D01*
G01X349715Y151554D02*
X349700Y151555D01*
G01X349730Y151553D02*
X349715Y151554D01*
G01X357574Y151555D02*
X357559D01*
G01X357589Y151554D02*
X357574Y151555D01*
G01X357604Y151553D02*
X357589Y151554D01*
G01X381196Y151555D02*
X381181D01*
G01X381211Y151554D02*
X381196Y151555D01*
G01X381226Y151553D02*
X381211Y151554D01*
G01X420566Y151555D02*
X420551D01*
G01X420581Y151554D02*
X420566Y151555D01*
G01X420596Y151553D02*
X420581Y151554D01*
G01X369685Y151756D02*
X369684D01*
G01X369685Y151754D02*
Y151756D01*
G01X369686Y151750D02*
X369685Y151754D01*
G01X379057Y134622D02*
X379058Y134621D01*
G01X379057Y134624D02*
Y134622D01*
G01X379056Y134627D02*
X379057Y134624D01*
G01X377559Y151756D02*
X377558D01*
G01X377559Y151754D02*
Y151756D01*
G01X377560Y151750D02*
X377559Y151754D01*
G01X386931Y134622D02*
X386932Y134621D01*
G01X386931Y134624D02*
Y134622D01*
G01X386930Y134627D02*
X386931Y134624D01*
G01X385433Y151756D02*
X385432D01*
G01X385433Y151754D02*
Y151756D01*
G01X385434Y151750D02*
X385433Y151754D01*
G01X394805Y134622D02*
X394806Y134621D01*
G01X394805Y134624D02*
Y134622D01*
G01X394804Y134627D02*
X394805Y134624D01*
G01X393307Y151756D02*
X393306D01*
G01X393307Y151754D02*
Y151756D01*
G01X393308Y151750D02*
X393307Y151754D01*
G01X409055Y150771D02*
X409054Y150772D01*
G01X409055Y150768D02*
Y150771D01*
G01X409056Y150762D02*
X409055Y150768D01*
G01X410553Y135606D02*
X410554Y135605D01*
G01X410553Y135610D02*
Y135606D01*
G01X410552Y135615D02*
X410553Y135610D01*
G01X416929Y150771D02*
X416928Y150772D01*
G01X416929Y150768D02*
Y150771D01*
G01X416930Y150762D02*
X416929Y150768D01*
G01X418427Y135606D02*
X418428Y135605D01*
G01X418427Y135610D02*
Y135606D01*
G01X418426Y135615D02*
X418427Y135610D01*
G01X402690Y150180D02*
X402691Y149807D01*
G01X402688Y150490D02*
X402690Y150180D01*
G01X402684Y150698D02*
X402688Y150490D01*
G01X402680Y150772D02*
X402684Y150698D01*
G01X402948Y133893D02*
X402954Y133840D01*
G01X402941Y134024D02*
X402948Y133893D01*
G01X402936Y134231D02*
X402941Y134024D01*
G01X404854Y152484D02*
X404848Y152538D01*
G01X404860Y152353D02*
X404854Y152484D01*
G01X404866Y152147D02*
X404860Y152353D01*
G01X406880Y133893D02*
X406886Y133840D01*
G01X406874Y134024D02*
X406880Y133893D01*
G01X406868Y134231D02*
X406874Y134024D01*
G01X408787Y152484D02*
X408780Y152538D01*
G01X408793Y152353D02*
X408787Y152484D01*
G01X408798Y152147D02*
X408793Y152353D01*
G01X410822Y133893D02*
X410828Y133840D01*
G01X410816Y134024D02*
X410822Y133893D01*
G01X410810Y134231D02*
X410816Y134024D01*
G01X412728Y152484D02*
X412722Y152538D01*
G01X412734Y152353D02*
X412728Y152484D01*
G01X412740Y152147D02*
X412734Y152353D01*
G01X414754Y133893D02*
X414760Y133840D01*
G01X414748Y134024D02*
X414754Y133893D01*
G01X414742Y134231D02*
X414748Y134024D01*
G01X416661Y152484D02*
X416655Y152538D01*
G01X416667Y152353D02*
X416661Y152484D01*
G01X416673Y152147D02*
X416667Y152353D01*
G01X418696Y133893D02*
X418702Y133840D01*
G01X418690Y134024D02*
X418696Y133893D01*
G01X418684Y134231D02*
X418690Y134024D01*
G01X420602Y152484D02*
X420596Y152538D01*
G01X420608Y152353D02*
X420602Y152484D01*
G01X420614Y152147D02*
X420608Y152353D01*
G01X422628Y133893D02*
X422634Y133840D01*
G01X422622Y134024D02*
X422628Y133893D01*
G01X422616Y134231D02*
X422622Y134024D01*
G01X424535Y152484D02*
X424529Y152538D01*
G01X424541Y152353D02*
X424535Y152484D01*
G01X424547Y152147D02*
X424541Y152353D01*
G01X426570Y133893D02*
X426576Y133840D01*
G01X426564Y134024D02*
X426570Y133893D01*
G01X426558Y134231D02*
X426564Y134024D01*
G01X402949Y134866D02*
X402954Y134824D01*
G01X402945Y134965D02*
X402949Y134866D01*
G01X402941Y135117D02*
X402945Y134965D01*
G01X404853Y151511D02*
X404848Y151553D01*
G01X404857Y151413D02*
X404853Y151511D01*
G01X404861Y151260D02*
X404857Y151413D01*
G01X406882Y134866D02*
X406886Y134824D01*
G01X406877Y134965D02*
X406882Y134866D01*
G01X406873Y135117D02*
X406877Y134965D01*
G01X408785Y151511D02*
X408780Y151553D01*
G01X408789Y151413D02*
X408785Y151511D01*
G01X408794Y151260D02*
X408789Y151413D01*
G01X410823Y134866D02*
X410828Y134824D01*
G01X410819Y134965D02*
X410823Y134866D01*
G01X410815Y135117D02*
X410819Y134965D01*
G01X412727Y151511D02*
X412722Y151553D01*
G01X412731Y151413D02*
X412727Y151511D01*
G01X412735Y151260D02*
X412731Y151413D01*
G01X414756Y134866D02*
X414760Y134824D01*
G01X414751Y134965D02*
X414756Y134866D01*
G01X414747Y135117D02*
X414751Y134965D01*
G01X416659Y151511D02*
X416655Y151553D01*
G01X416663Y151413D02*
X416659Y151511D01*
G01X416668Y151260D02*
X416663Y151413D01*
G01X418697Y134866D02*
X418702Y134824D01*
G01X418693Y134965D02*
X418697Y134866D01*
G01X418689Y135117D02*
X418693Y134965D01*
G01X420601Y151511D02*
X420596Y151553D01*
G01X420605Y151413D02*
X420601Y151511D01*
G01X420609Y151260D02*
X420605Y151413D01*
G01X422630Y134866D02*
X422634Y134824D01*
G01X422625Y134965D02*
X422630Y134866D01*
G01X422621Y135117D02*
X422625Y134965D01*
G01X424533Y151511D02*
X424529Y151553D01*
G01X424537Y151413D02*
X424533Y151511D01*
G01X424542Y151260D02*
X424537Y151413D01*
G01X426571Y134866D02*
X426576Y134824D01*
G01X426567Y134965D02*
X426571Y134866D01*
G01X426563Y135117D02*
X426567Y134965D01*
G01X405110Y135645D02*
X405114Y135615D01*
G01X405106Y135841D02*
X405110Y135645D01*
G01X405103Y136168D02*
X405106Y135841D01*
G01X405102Y136570D02*
X405103Y136168D01*
G01X406625Y150733D02*
X406620Y150762D01*
G01X406629Y150537D02*
X406625Y150733D01*
G01X406631Y150209D02*
X406629Y150537D01*
G01X406632Y149807D02*
X406631Y150209D01*
G01X412984Y135645D02*
X412988Y135615D01*
G01X412980Y135841D02*
X412984Y135645D01*
G01X412977Y136168D02*
X412980Y135841D01*
G01X412976Y136570D02*
X412977Y136168D01*
G01X414499Y150733D02*
X414494Y150762D01*
G01X414503Y150537D02*
X414499Y150733D01*
G01X414505Y150209D02*
X414503Y150537D01*
G01X414507Y149807D02*
X414505Y150209D01*
G01X420858Y135645D02*
X420862Y135615D01*
G01X420854Y135841D02*
X420858Y135645D01*
G01X420851Y136168D02*
X420854Y135841D01*
G01X420850Y136570D02*
X420851Y136168D01*
G01X422373Y150733D02*
X422368Y150762D01*
G01X422377Y150537D02*
X422373Y150733D01*
G01X422379Y150209D02*
X422377Y150537D01*
G01X422381Y149807D02*
X422379Y150209D01*
G01X409046Y134770D02*
X409054Y134621D01*
G01X409039Y135184D02*
X409046Y134770D01*
G01X409034Y135804D02*
X409039Y135184D01*
G01X409032Y136551D02*
X409034Y135804D01*
G01X409050Y135678D02*
X409054Y135605D01*
G01X409047Y135887D02*
X409050Y135678D01*
G01X409044Y136200D02*
X409047Y135887D01*
G01X409043Y136570D02*
X409044Y136200D01*
G01X410558Y150699D02*
X410554Y150772D01*
G01X410562Y150490D02*
X410558Y150699D01*
G01X410564Y150178D02*
X410562Y150490D01*
G01X410565Y149807D02*
X410564Y150178D01*
G01X410562Y151608D02*
X410554Y151756D01*
G01X410569Y151193D02*
X410562Y151608D01*
G01X410574Y150573D02*
X410569Y151193D01*
G01X410576Y149826D02*
X410574Y150573D01*
G01X416920Y134770D02*
X416928Y134621D01*
G01X416913Y135184D02*
X416920Y134770D01*
G01X416908Y135804D02*
X416913Y135184D01*
G01X416906Y136551D02*
X416908Y135804D01*
G01X416924Y135678D02*
X416928Y135605D01*
G01X416921Y135887D02*
X416924Y135678D01*
G01X416918Y136200D02*
X416921Y135887D01*
G01X416917Y136570D02*
X416918Y136200D01*
G01X418432Y150699D02*
X418428Y150772D01*
G01X418436Y150490D02*
X418432Y150699D01*
G01X418438Y150178D02*
X418436Y150490D01*
G01X418439Y149807D02*
X418438Y150178D01*
G01X418436Y151608D02*
X418428Y151756D01*
G01X418443Y151193D02*
X418436Y151608D01*
G01X418448Y150573D02*
X418443Y151193D01*
G01X418450Y149826D02*
X418448Y150573D01*
G01X424794Y134770D02*
X424802Y134621D01*
G01X424787Y135184D02*
X424794Y134770D01*
G01X424782Y135804D02*
X424787Y135184D01*
G01X424780Y136551D02*
X424782Y135804D01*
G01X424798Y135678D02*
X424802Y135605D01*
G01X424795Y135887D02*
X424798Y135678D01*
G01X424792Y136200D02*
X424795Y135887D01*
G01X424791Y136570D02*
X424792Y136200D01*
G01X426306Y150699D02*
X426302Y150772D01*
G01X426310Y150490D02*
X426306Y150699D01*
G01X426312Y150178D02*
X426310Y150490D01*
G01X426313Y149807D02*
X426312Y150178D01*
G01X426310Y151608D02*
X426302Y151756D01*
G01X426317Y151193D02*
X426310Y151608D01*
G01X426322Y150573D02*
X426317Y151193D01*
G01X426324Y149826D02*
X426322Y150573D01*
G01X409034D02*
X409032Y149826D01*
G01X409039Y151193D02*
X409034Y150573D01*
G01X409046Y151608D02*
X409039Y151193D01*
G01X409054Y151756D02*
X409046Y151608D01*
G01X410574Y135804D02*
X410576Y136551D01*
G01X410569Y135184D02*
X410574Y135804D01*
G01X410562Y134770D02*
X410569Y135184D01*
G01X410554Y134621D02*
X410562Y134770D01*
G01X416908Y150573D02*
X416906Y149826D01*
G01X416913Y151193D02*
X416908Y150573D01*
G01X416920Y151608D02*
X416913Y151193D01*
G01X416928Y151756D02*
X416920Y151608D01*
G01X418448Y135804D02*
X418450Y136551D01*
G01X418443Y135184D02*
X418448Y135804D01*
G01X418436Y134770D02*
X418443Y135184D01*
G01X418428Y134621D02*
X418436Y134770D01*
G01X424782Y150573D02*
X424780Y149826D01*
G01X424787Y151193D02*
X424782Y150573D01*
G01X424794Y151608D02*
X424787Y151193D01*
G01X424802Y151756D02*
X424794Y151608D01*
G01X426322Y135804D02*
X426324Y136551D01*
G01X426317Y135184D02*
X426322Y135804D01*
G01X426310Y134770D02*
X426317Y135184D01*
G01X426302Y134621D02*
X426310Y134770D01*
G01X409044Y150178D02*
X409043Y149807D01*
G01X409047Y150490D02*
X409044Y150178D01*
G01X409050Y150699D02*
X409047Y150490D01*
G01X409054Y150772D02*
X409050Y150699D01*
G01X410564Y136200D02*
X410565Y136570D01*
G01X410562Y135887D02*
X410564Y136200D01*
G01X410558Y135678D02*
X410562Y135887D01*
G01X410554Y135605D02*
X410558Y135678D01*
G01X416918Y150178D02*
X416917Y149807D01*
G01X416921Y150490D02*
X416918Y150178D01*
G01X416924Y150699D02*
X416921Y150490D01*
G01X416928Y150772D02*
X416924Y150699D01*
G01X418438Y136200D02*
X418439Y136570D01*
G01X418436Y135887D02*
X418438Y136200D01*
G01X418432Y135678D02*
X418436Y135887D01*
G01X418428Y135605D02*
X418432Y135678D01*
G01X424792Y150178D02*
X424791Y149807D01*
G01X424795Y150490D02*
X424792Y150178D01*
G01X424798Y150699D02*
X424795Y150490D01*
G01X424802Y150772D02*
X424798Y150699D01*
G01X426312Y136200D02*
X426313Y136570D01*
G01X426310Y135887D02*
X426312Y136200D01*
G01X426306Y135678D02*
X426310Y135887D01*
G01X426302Y135605D02*
X426306Y135678D01*
G01X412722Y134965D02*
X412726Y135117D01*
G01X412717Y134866D02*
X412722Y134965D01*
G01X412713Y134824D02*
X412717Y134866D01*
G01X414760Y151413D02*
X414756Y151260D01*
G01X414765Y151511D02*
X414760Y151413D01*
G01X414769Y151553D02*
X414765Y151511D01*
G01X416663Y134965D02*
X416668Y135117D01*
G01X416659Y134866D02*
X416663Y134965D01*
G01X416655Y134824D02*
X416659Y134866D01*
G01X418693Y151413D02*
X418689Y151260D01*
G01X418697Y151511D02*
X418693Y151413D01*
G01X418702Y151553D02*
X418697Y151511D01*
G01X420596Y134965D02*
X420600Y135117D01*
G01X420591Y134866D02*
X420596Y134965D01*
G01X420587Y134824D02*
X420591Y134866D01*
G01X422634Y151413D02*
X422630Y151260D01*
G01X422639Y151511D02*
X422634Y151413D01*
G01X422643Y151553D02*
X422639Y151511D01*
G01X424537Y134965D02*
X424542Y135117D01*
G01X424533Y134866D02*
X424537Y134965D01*
G01X424529Y134824D02*
X424533Y134866D01*
G01X426567Y151413D02*
X426563Y151260D01*
G01X426571Y151511D02*
X426567Y151413D01*
G01X426576Y151553D02*
X426571Y151511D01*
G01X414757Y152353D02*
X414751Y152147D01*
G01X414763Y152484D02*
X414757Y152353D01*
G01X414769Y152538D02*
X414763Y152484D01*
G01X412725Y134024D02*
X412731Y134231D01*
G01X412719Y133893D02*
X412725Y134024D01*
G01X412713Y133840D02*
X412719Y133893D01*
G01X418690Y152353D02*
X418684Y152147D01*
G01X418696Y152484D02*
X418690Y152353D01*
G01X418702Y152538D02*
X418696Y152484D01*
G01X416667Y134024D02*
X416673Y134231D01*
G01X416661Y133893D02*
X416667Y134024D01*
G01X416655Y133840D02*
X416661Y133893D01*
G01X422631Y152353D02*
X422625Y152147D01*
G01X422637Y152484D02*
X422631Y152353D01*
G01X422643Y152538D02*
X422637Y152484D01*
G01X420599Y134024D02*
X420605Y134231D01*
G01X420593Y133893D02*
X420599Y134024D01*
G01X420587Y133840D02*
X420593Y133893D01*
G01X426564Y152353D02*
X426558Y152147D01*
G01X426570Y152484D02*
X426564Y152353D01*
G01X426576Y152538D02*
X426570Y152484D01*
G01X424541Y134024D02*
X424547Y134231D01*
G01X424535Y133893D02*
X424541Y134024D01*
G01X424529Y133840D02*
X424535Y133893D01*
G01X414496Y136168D02*
X414497Y136570D01*
G01X414493Y135841D02*
X414496Y136168D01*
G01X414489Y135645D02*
X414493Y135841D01*
G01X414485Y135615D02*
X414489Y135645D01*
G01X420860Y150209D02*
X420859Y149807D01*
G01X420863Y150537D02*
X420860Y150209D01*
G01X420867Y150733D02*
X420863Y150537D01*
G01X420872Y150762D02*
X420867Y150733D01*
G01X422370Y136168D02*
X422371Y136570D01*
G01X422367Y135841D02*
X422370Y136168D01*
G01X422363Y135645D02*
X422367Y135841D01*
G01X422359Y135615D02*
X422363Y135645D01*
G01X394805Y135610D02*
X394804Y135617D01*
G01X394805Y135606D02*
Y135610D01*
G01X394806Y135605D02*
X394805Y135606D01*
G01X393307Y150768D02*
X393308Y150760D01*
G01X393307Y150771D02*
Y150768D01*
G01X393306Y150772D02*
X393307Y150771D01*
G01X402679Y135610D02*
X402678Y135617D01*
G01X402679Y135606D02*
Y135610D01*
G01X402680Y135605D02*
X402679Y135606D01*
G01X401181Y150768D02*
X401182Y150760D01*
G01X401181Y150771D02*
Y150768D01*
G01X401180Y150772D02*
X401181Y150771D01*
G01X402679Y134622D02*
X402680Y134621D01*
G01X402679Y134624D02*
Y134622D01*
G01X402678Y134627D02*
X402679Y134624D01*
G01X401181Y151756D02*
X401180D01*
G01X401181Y151754D02*
Y151756D01*
G01X401182Y151750D02*
X401181Y151754D01*
G01X410553Y134622D02*
X410554Y134621D01*
G01X410553Y134624D02*
Y134622D01*
G01X410552Y134627D02*
X410553Y134624D01*
G01X409055Y151756D02*
X409054D01*
G01X409056Y151754D02*
X409055Y151756D01*
G01X409056Y151750D02*
Y151754D01*
G01X418427Y134622D02*
X418428Y134621D01*
G01X418427Y134624D02*
Y134622D01*
G01X418426Y134627D02*
X418427Y134624D01*
G01X416929Y151756D02*
X416928D01*
G01X416930Y151754D02*
X416929Y151756D01*
G01X416930Y151750D02*
Y151754D01*
G01X424803Y150771D02*
X424802Y150772D01*
G01X424803Y150768D02*
Y150771D01*
G01X424804Y150762D02*
X424803Y150768D01*
G01X426301Y135606D02*
X426302Y135605D01*
G01X426301Y135610D02*
Y135606D01*
G01X426300Y135615D02*
X426301Y135610D01*
G01Y134622D02*
X426302Y134621D01*
G01X426301Y134624D02*
Y134622D01*
G01X426300Y134627D02*
X426301Y134624D01*
G01X424803Y151756D02*
X424802D01*
G01X424804Y151754D02*
X424803Y151756D01*
G01X424804Y151750D02*
Y151754D01*
G01X347481Y129943D02*
X347639Y129981D01*
G01X347481Y130965D02*
X347639Y131039D01*
G01X347548Y134640D02*
X347560Y134627D01*
G01X347639Y156396D02*
X347481Y156434D01*
G01X347639Y155338D02*
X347481Y155412D01*
G01X347560Y151750D02*
X347548Y151737D01*
G01X351481Y134640D02*
X351492Y134627D01*
G01X349996D02*
X350008Y134640D01*
G01X351576Y138680D02*
X351418Y138717D01*
G01X350080D02*
X349922Y138680D01*
G01X351576Y137621D02*
X351418Y137696D01*
G01X350080D02*
X349922Y137621D01*
G01Y147698D02*
X350080Y147660D01*
G01X351418D02*
X351576Y147698D01*
G01X349922Y148756D02*
X350080Y148681D01*
G01X351418D02*
X351576Y148756D01*
G01X350017Y151737D02*
X350006Y151750D01*
G01X351502D02*
X351490Y151737D01*
G01X353859Y129981D02*
X354017Y129943D01*
G01X355355D02*
X355513Y129981D01*
G01X353859Y131039D02*
X354017Y130965D01*
G01X355355D02*
X355513Y131039D01*
G01X353938Y134627D02*
X353950Y134640D01*
G01X355423D02*
X355434Y134627D01*
G01X355513Y156396D02*
X355355Y156434D01*
G01X354017D02*
X353859Y156396D01*
G01X355513Y155338D02*
X355355Y155412D01*
G01X354017D02*
X353859Y155338D01*
G01X353950Y151737D02*
X353938Y151750D01*
G01X355434D02*
X355423Y151737D01*
G01X359355Y134640D02*
X359366Y134627D01*
G01X357870D02*
X357882Y134640D01*
G01X359450Y138680D02*
X359292Y138717D01*
G01X357954D02*
X357796Y138680D01*
G01X359450Y137621D02*
X359292Y137696D01*
G01X357954D02*
X357796Y137621D01*
G01Y147698D02*
X357954Y147660D01*
G01X359292D02*
X359450Y147698D01*
G01X357796Y148756D02*
X357954Y148681D01*
G01X359292D02*
X359450Y148756D01*
G01X357891Y151737D02*
X357880Y151750D01*
G01X359376D02*
X359364Y151737D01*
G01X361733Y129981D02*
X361891Y129943D01*
G01X363229D02*
X363387Y129981D01*
G01X361733Y131039D02*
X361891Y130965D01*
G01X363229D02*
X363387Y131039D01*
G01X361812Y134627D02*
X361824Y134640D01*
G01X363297D02*
X363308Y134627D01*
G01X363387Y156396D02*
X363229Y156434D01*
G01X361891D02*
X361733Y156396D01*
G01X363387Y155338D02*
X363229Y155412D01*
G01X361891D02*
X361733Y155338D01*
G01X361824Y151737D02*
X361812Y151750D01*
G01X363308D02*
X363297Y151737D01*
G01X367229Y134640D02*
X367240Y134627D01*
G01X365744D02*
X365756Y134640D01*
G01X367324Y138680D02*
X367166Y138717D01*
G01X365828D02*
X365670Y138680D01*
G01X367324Y137621D02*
X367166Y137696D01*
G01X365828D02*
X365670Y137621D01*
G01Y147698D02*
X365828Y147660D01*
G01X365670Y148756D02*
X365828Y148681D01*
G01X367166D02*
X367324Y148756D01*
G01X367166Y147660D02*
X367324Y147698D01*
G01X367570Y151555D02*
X367525Y151553D01*
G01X365765Y151737D02*
X365754Y151750D01*
G01X367250D02*
X367238Y151737D01*
G01X369607Y129981D02*
X369765Y129943D01*
G01X371103D02*
X371261Y129981D01*
G01X369607Y131039D02*
X369765Y130965D01*
G01X371103D02*
X371261Y131039D01*
G01X369686Y134627D02*
X369698Y134640D01*
G01X371171D02*
X371182Y134627D01*
G01X371261Y156396D02*
X371103Y156434D01*
G01X369765D02*
X369607Y156396D01*
G01X371261Y155338D02*
X371103Y155412D01*
G01X369765D02*
X369607Y155338D01*
G01X369698Y151737D02*
X369686Y151750D01*
G01X371182D02*
X371171Y151737D01*
G01X375103Y134640D02*
X375114Y134627D01*
G01X373618D02*
X373630Y134640D01*
G01X375198Y138680D02*
X375040Y138717D01*
G01X373702D02*
X373544Y138680D01*
G01X375198Y137621D02*
X375040Y137696D01*
G01X373702D02*
X373544Y137621D01*
G01Y147698D02*
X373702Y147660D01*
G01X373544Y148756D02*
X373702Y148681D01*
G01X375040D02*
X375198Y148756D01*
G01X375040Y147660D02*
X375198Y147698D01*
G01X375444Y151555D02*
X375399Y151553D01*
G01X373639Y151737D02*
X373628Y151750D01*
G01X375124D02*
X375112Y151737D01*
G01X377481Y129981D02*
X377639Y129943D01*
G01X378977D02*
X379135Y129981D01*
G01X377481Y131039D02*
X377639Y130965D01*
G01X378977D02*
X379135Y131039D01*
G01X377560Y134627D02*
X377572Y134640D01*
G01X379045D02*
X379056Y134627D01*
G01X379135Y156396D02*
X378977Y156434D01*
G01X377639D02*
X377481Y156396D01*
G01X379135Y155338D02*
X378977Y155412D01*
G01X377639D02*
X377481Y155338D01*
G01X377572Y151737D02*
X377560Y151750D01*
G01X379056D02*
X379045Y151737D01*
G01X382977Y134640D02*
X382988Y134627D01*
G01X381492D02*
X381504Y134640D01*
G01X383072Y138680D02*
X382914Y138717D01*
G01X381576D02*
X381418Y138680D01*
G01X383072Y137621D02*
X382914Y137696D01*
G01X381576D02*
X381418Y137621D01*
G01Y147698D02*
X381576Y147660D01*
G01X382914D02*
X383072Y147698D01*
G01X381418Y148756D02*
X381576Y148681D01*
G01X382914D02*
X383072Y148756D01*
G01X381513Y151737D02*
X381502Y151750D01*
G01X382998D02*
X382986Y151737D01*
G01X385355Y129981D02*
X385513Y129943D01*
G01X386851D02*
X387009Y129981D01*
G01X385355Y131039D02*
X385513Y130965D01*
G01X386851D02*
X387009Y131039D01*
G01X385434Y134627D02*
X385446Y134640D01*
G01X386919D02*
X386930Y134627D01*
G01X387009Y156396D02*
X386851Y156434D01*
G01X385513D02*
X385355Y156396D01*
G01X387009Y155338D02*
X386851Y155412D01*
G01X385513D02*
X385355Y155338D01*
G01X385446Y151737D02*
X385434Y151750D01*
G01X386930D02*
X386919Y151737D01*
G01X390851Y134640D02*
X390862Y134627D01*
G01X389366D02*
X389378Y134640D01*
G01X389046Y134822D02*
X389091Y134824D01*
G01X389450Y138717D02*
X389292Y138680D01*
G01X390946D02*
X390788Y138717D01*
G01X389450Y137696D02*
X389292Y137621D01*
G01X390946D02*
X390788Y137696D01*
G01X389387Y151737D02*
X389376Y151750D01*
G01X390872D02*
X390860Y151737D01*
G01X390788Y147660D02*
X390946Y147698D01*
G01X389292D02*
X389450Y147660D01*
G01X390788Y148681D02*
X390946Y148756D01*
G01X389292D02*
X389450Y148681D01*
G01X394725Y129943D02*
X394883Y129981D01*
G01X393229D02*
X393387Y129943D01*
G01X394725Y130965D02*
X394883Y131039D01*
G01X393229D02*
X393387Y130965D01*
G01X392987Y133838D02*
X393032Y133840D01*
G01X393308Y134627D02*
X393320Y134640D01*
G01X394793D02*
X394804Y134627D01*
G01X393387Y156434D02*
X393229Y156396D01*
G01X394883D02*
X394725Y156434D01*
G01X393387Y155412D02*
X393229Y155338D01*
G01X394883D02*
X394725Y155412D01*
G01X393320Y151737D02*
X393308Y151750D01*
G01X394804D02*
X394793Y151737D01*
G01X395125Y152539D02*
X395080Y152538D01*
G01X398820Y138680D02*
X398662Y138717D01*
G01X397324D02*
X397166Y138680D01*
G01X397324Y137696D02*
X397166Y137621D01*
G01X398820D02*
X398662Y137696D01*
G01X398725Y134640D02*
X398736Y134627D01*
G01X397240D02*
X397252Y134640D01*
G01X396920Y134822D02*
X396965Y134824D01*
G01X397166Y147698D02*
X397324Y147660D01*
G01X398662Y148681D02*
X398820Y148756D01*
G01X397166D02*
X397324Y148681D01*
G01X398662Y147660D02*
X398820Y147698D01*
G01X397261Y151737D02*
X397250Y151750D01*
G01X398746D02*
X398734Y151737D01*
G01X399066Y152539D02*
X399021Y152538D01*
G01X402599Y129943D02*
X402757Y129981D01*
G01X401103D02*
X401261Y129943D01*
G01X402599Y130965D02*
X402757Y131039D01*
G01X401103D02*
X401261Y130965D01*
G01X400861Y133838D02*
X400906Y133840D01*
G01X401182Y134627D02*
X401194Y134640D01*
G01X402667D02*
X402678Y134627D01*
G01X401261Y156434D02*
X401103Y156396D01*
G01X402757D02*
X402599Y156434D01*
G01X401261Y155412D02*
X401103Y155338D01*
G01X402757D02*
X402599Y155412D01*
G01X401194Y151737D02*
X401182Y151750D01*
G01X402678D02*
X402667Y151737D01*
G01X402999Y152539D02*
X402954Y152538D01*
G01X406599Y134640D02*
X406610Y134627D01*
G01X405114D02*
X405126Y134640D01*
G01X406694Y138680D02*
X406536Y138717D01*
G01X405198D02*
X405040Y138680D01*
G01X406694Y137621D02*
X406536Y137696D01*
G01X405198D02*
X405040Y137621D01*
G01Y147698D02*
X405198Y147660D01*
G01X405040Y148756D02*
X405198Y148681D01*
G01X406536D02*
X406694Y148756D01*
G01X406536Y147660D02*
X406694Y147698D01*
G01X406940Y151555D02*
X406895Y151553D01*
G01X405135Y151737D02*
X405124Y151750D01*
G01X406620D02*
X406608Y151737D01*
G01X410631Y156396D02*
X410473Y156434D01*
G01X409135D02*
X408977Y156396D01*
G01X410631Y155338D02*
X410473Y155412D01*
G01X409135D02*
X408977Y155338D01*
G01X410552Y151750D02*
X410541Y151737D01*
G01X409068D02*
X409056Y151750D01*
G01X408977Y129981D02*
X409135Y129943D01*
G01X410473D02*
X410631Y129981D01*
G01X408977Y131039D02*
X409135Y130965D01*
G01X410473D02*
X410631Y131039D01*
G01X410541Y134640D02*
X410552Y134627D01*
G01X409056D02*
X409068Y134640D01*
G01X414473D02*
X414484Y134627D01*
G01X412988D02*
X413000Y134640D01*
G01X414568Y138680D02*
X414410Y138717D01*
G01X413072D02*
X412914Y138680D01*
G01X414568Y137621D02*
X414410Y137696D01*
G01X413072D02*
X412914Y137621D01*
G01Y147698D02*
X413072Y147660D01*
G01X412914Y148756D02*
X413072Y148681D01*
G01X414410D02*
X414568Y148756D01*
G01X414410Y147660D02*
X414568Y147698D01*
G01X414814Y151555D02*
X414769Y151553D01*
G01X413009Y151737D02*
X412998Y151750D01*
G01X414494D02*
X414482Y151737D01*
G01X416851Y129981D02*
X417009Y129943D01*
G01X418347D02*
X418505Y129981D01*
G01X416851Y131039D02*
X417009Y130965D01*
G01X418347D02*
X418505Y131039D01*
G01X416930Y134627D02*
X416942Y134640D01*
G01X418415D02*
X418426Y134627D01*
G01X418505Y156396D02*
X418347Y156434D01*
G01X417009D02*
X416851Y156396D01*
G01X418505Y155338D02*
X418347Y155412D01*
G01X417009D02*
X416851Y155338D01*
G01X416942Y151737D02*
X416930Y151750D01*
G01X418426D02*
X418415Y151737D01*
G01X422347Y134640D02*
X422359Y134627D01*
G01X420862D02*
X420874Y134640D01*
G01X422442Y138680D02*
X422284Y138717D01*
G01X420946D02*
X420788Y138680D01*
G01X422442Y137621D02*
X422284Y137696D01*
G01X420946D02*
X420788Y137621D01*
G01Y147698D02*
X420946Y147660D01*
G01X422284D02*
X422442Y147698D01*
G01X420788Y148756D02*
X420946Y148681D01*
G01X422284D02*
X422442Y148756D01*
G01X420883Y151737D02*
X420872Y151750D01*
G01X422368D02*
X422356Y151737D01*
G01X424725Y129981D02*
X424883Y129943D01*
G01X426221D02*
X426379Y129981D01*
G01X424725Y131039D02*
X424883Y130965D01*
G01X426221D02*
X426379Y131039D01*
G01X424804Y134627D02*
X424816Y134640D01*
G01X426289D02*
X426300Y134627D01*
G01X426379Y156396D02*
X426221Y156434D01*
G01X424883D02*
X424725Y156396D01*
G01X426379Y155338D02*
X426221Y155412D01*
G01X424883D02*
X424725Y155338D01*
G01X424816Y151737D02*
X424804Y151750D01*
G01X426300D02*
X426289Y151737D01*
G01X425024Y150441D02*
X425033Y150393D01*
G01X426080Y135937D02*
X426071Y135984D01*
G01X421092Y150441D02*
X421101Y150393D01*
G01X422139Y135937D02*
X422129Y135984D01*
G01X424816Y151737D02*
X425069Y151368D01*
G01X425024Y150441D02*
X424803Y150762D01*
G01X420883Y151737D02*
X421137Y151368D01*
G01X421092Y150441D02*
X420870Y150762D01*
G01X416942Y151737D02*
X417195Y151368D01*
G01X417150Y150441D02*
X416928Y150762D01*
G01X426080Y135937D02*
X426302Y135615D01*
G01X426289Y134640D02*
X426035Y135009D01*
G01X413009Y151737D02*
X413263Y151368D01*
G01X413217Y150441D02*
X412996Y150762D01*
G01X422139Y135937D02*
X422360Y135615D01*
G01X422347Y134640D02*
X422093Y135009D01*
G01X409068Y151737D02*
X409321Y151368D01*
G01X409276Y150441D02*
X409054Y150762D01*
G01X418206Y135937D02*
X418428Y135615D01*
G01X418415Y134640D02*
X418161Y135009D01*
G01X405135Y151737D02*
X405389Y151368D01*
G01X405343Y150441D02*
X405122Y150762D01*
G01X426400Y146012D02*
X426350Y146999D01*
G01X426347Y146037D02*
X426398Y145050D01*
G01X417150Y150441D02*
X417159Y150393D01*
G01X418206Y135937D02*
X418197Y135984D01*
G01X413217Y150441D02*
X413227Y150393D01*
G01X414265Y135937D02*
X414255Y135984D01*
G01X409276Y150441D02*
X409285Y150393D01*
G01X410332Y135937D02*
X410323Y135984D01*
G01X405343Y150441D02*
X405353Y150393D01*
G01X406391Y135937D02*
X406381Y135984D01*
G01X401411Y150393D02*
X401402Y150441D01*
G01X402449Y135984D02*
X402458Y135937D01*
G01X397469Y150441D02*
X397479Y150393D01*
G01X398517Y135937D02*
X398507Y135984D01*
G01X393537Y150393D02*
X393528Y150441D01*
G01X414265Y135937D02*
X414486Y135615D01*
G01X414473Y134640D02*
X414219Y135009D01*
G01X401447Y151368D02*
X401194Y151737D01*
G01X401182Y150760D02*
X401402Y150441D01*
G01X410332Y135937D02*
X410554Y135615D01*
G01X410541Y134640D02*
X410287Y135009D01*
G01X397515Y151368D02*
X397261Y151737D01*
G01X397469Y150441D02*
X397248Y150762D01*
G01X406391Y135937D02*
X406612Y135615D01*
G01X406599Y134640D02*
X406345Y135009D01*
G01X393573Y151368D02*
X393320Y151737D01*
G01X393308Y150760D02*
X393528Y150441D01*
G01X402678Y135617D02*
X402458Y135937D01*
G01X402413Y135009D02*
X402667Y134640D01*
G01X389641Y151368D02*
X389387Y151737D01*
G01X389595Y150441D02*
X389374Y150762D01*
G01X398517Y135937D02*
X398738Y135615D01*
G01X398471Y135009D02*
X398725Y134640D01*
G01X385446Y151737D02*
X385699Y151368D01*
G01X385654Y150441D02*
X385432Y150762D01*
G01X394804Y135617D02*
X394584Y135937D01*
G01X394539Y135009D02*
X394793Y134640D01*
G01X381513Y151737D02*
X381767Y151368D01*
G01X381721Y150441D02*
X381500Y150762D01*
G01X390643Y135937D02*
X390864Y135615D01*
G01X390597Y135009D02*
X390851Y134640D01*
G01X377572Y151737D02*
X377825Y151368D01*
G01X377780Y150441D02*
X377558Y150762D01*
G01X386710Y135937D02*
X386932Y135615D01*
G01X386919Y134640D02*
X386665Y135009D01*
G01X425033Y135984D02*
X425024Y135937D01*
G01X426071Y150393D02*
X426080Y150441D01*
G01X421092Y135984D02*
X421082Y135937D01*
G01X422139Y150393D02*
X422148Y150441D01*
G01X417159Y135984D02*
X417150Y135937D01*
G01X426350Y139379D02*
X426400Y140365D01*
G01X426398Y141327D02*
X426347Y140340D01*
G01X424706Y145050D02*
X424757Y146037D01*
G01X424755Y146999D02*
X424704Y146012D01*
G01X422408Y139379D02*
X422459Y140365D01*
G01X422456Y141327D02*
X422406Y140340D01*
G01X420774Y145050D02*
X420825Y146037D01*
G01X420822Y146999D02*
X420772Y146012D01*
G01X418476Y139379D02*
X418526Y140365D01*
G01X418524Y141327D02*
X418473Y140340D01*
G01X416832Y145050D02*
X416883Y146037D01*
G01X416881Y146999D02*
X416830Y146012D01*
G01X414534Y139379D02*
X414585Y140365D01*
G01X414582Y141327D02*
X414532Y140340D01*
G01X412900Y145050D02*
X412951Y146037D01*
G01X412948Y146999D02*
X412898Y146012D01*
G01X410602Y139379D02*
X410652Y140365D01*
G01X410650Y141327D02*
X410599Y140340D01*
G01X408958Y145050D02*
X409009Y146037D01*
G01X409007Y146999D02*
X408956Y146012D01*
G01X426426Y145353D02*
X426563Y151260D01*
G01X426558Y152147D02*
X426422Y146239D01*
G01X424547Y134231D02*
X424683Y140138D01*
G01X424678Y141024D02*
X424542Y135117D01*
G01X422494Y145353D02*
X422630Y151260D01*
G01X422625Y152147D02*
X422489Y146239D01*
G01X420605Y134231D02*
X420741Y140138D01*
G01X420736Y141024D02*
X420600Y135117D01*
G01X418552Y145353D02*
X418689Y151260D01*
G01X418684Y152147D02*
X418548Y146239D01*
G01X416673Y134231D02*
X416809Y140138D01*
G01X416804Y141024D02*
X416668Y135117D01*
G01X414620Y145353D02*
X414756Y151260D01*
G01X414751Y152147D02*
X414615Y146239D01*
G01X412731Y134231D02*
X412867Y140138D01*
G01X412862Y141024D02*
X412726Y135117D01*
G01X410678Y145353D02*
X410815Y151260D01*
G01X410810Y152147D02*
X410674Y146239D01*
G01X408798Y134231D02*
X408935Y140138D01*
G01X408930Y141024D02*
X408794Y135117D01*
G01X406746Y145353D02*
X406882Y151260D01*
G01X406877Y152147D02*
X406741Y146239D01*
G01X426048Y135984D02*
X426035Y135009D01*
G01X425056Y150393D02*
X425069Y151368D01*
G01X422106Y135984D02*
X422093Y135009D01*
G01X421124Y150393D02*
X421137Y151368D01*
G01X418174Y135984D02*
X418161Y135009D01*
G01X417182Y150393D02*
X417195Y151368D01*
G01X414232Y135984D02*
X414219Y135009D01*
G01X413250Y150393D02*
X413263Y151368D01*
G01X410300Y135984D02*
X410287Y135009D01*
G01X409308Y150393D02*
X409321Y151368D01*
G01X406358Y135984D02*
X406345Y135009D01*
G01X405376Y150393D02*
X405389Y151368D01*
G01X426969Y149862D02*
Y154035D01*
G01Y132342D02*
Y136515D01*
G01X426935Y134822D02*
Y133838D01*
G01X426930Y134822D02*
Y133838D01*
G01Y152539D02*
Y151555D01*
G01X426733Y135984D02*
Y129901D01*
G01Y156476D02*
Y150393D01*
G01X426655Y133838D02*
Y152539D01*
G01X426576Y134824D02*
Y133840D01*
G01Y152538D02*
Y151553D01*
G01X426379Y151555D02*
Y156396D01*
G01Y129981D02*
Y134822D01*
G01X426300Y150760D02*
Y151750D01*
G01Y134627D02*
Y135617D01*
G01X426221Y130965D02*
Y129901D01*
G01Y156476D02*
Y155412D01*
G01X425946Y130885D02*
Y129901D01*
G01Y156476D02*
Y155492D01*
G01X425158D02*
Y156476D01*
G01Y130885D02*
Y129901D01*
G01X424883Y130965D02*
Y129901D01*
G01Y156476D02*
Y155412D01*
G01X424804Y135617D02*
Y134627D01*
G01Y151750D02*
Y150760D01*
G01X424725Y151555D02*
Y156396D01*
G01Y129981D02*
Y134822D01*
G01X424529Y133840D02*
Y134824D01*
G01Y151553D02*
Y152538D01*
G01X424450Y152539D02*
Y133838D01*
G01X424371Y135984D02*
Y129901D01*
G01Y156476D02*
Y150393D01*
G01X424174Y134822D02*
Y133838D01*
G01Y152539D02*
Y151555D01*
G01X424170Y152539D02*
Y151555D01*
G01X424135Y136515D02*
Y132342D01*
G01Y154035D02*
Y149862D01*
G01X423032D02*
Y154035D01*
G01Y132342D02*
Y136515D01*
G01X422998Y152539D02*
Y151555D01*
G01X422993Y134822D02*
Y133838D01*
G01X422988Y134822D02*
Y133838D01*
G01X422796Y135984D02*
Y129901D01*
G01Y156476D02*
Y150393D01*
G01X422717Y133838D02*
Y152539D01*
G01X422643Y152538D02*
Y151553D01*
G01X422634Y134824D02*
Y133840D01*
G01X422442Y147698D02*
Y152539D01*
G01Y133838D02*
Y138680D01*
G01X422368Y150760D02*
Y151750D01*
G01X422359Y134627D02*
Y135617D01*
G01X422284Y138760D02*
Y137696D01*
G01Y148681D02*
Y147618D01*
G01X422009Y138760D02*
Y137775D01*
G01Y148602D02*
Y147618D01*
G01X421221Y138760D02*
Y137775D01*
G01Y148602D02*
Y147618D01*
G01X420946Y138760D02*
Y137696D01*
G01Y148681D02*
Y147618D01*
G01X420872Y151750D02*
Y150760D01*
G01X420862Y135617D02*
Y134627D01*
G01X420828Y128523D02*
Y123011D01*
G01X420788Y147698D02*
Y152539D01*
G01Y133838D02*
Y138680D01*
G01X420596Y151553D02*
Y152538D01*
G01X420587Y133840D02*
Y134824D01*
G01X420513Y152539D02*
Y133838D01*
G01X420434Y135984D02*
Y129901D01*
G01Y156476D02*
Y150393D01*
G01X420242Y152539D02*
Y151555D01*
G01X420237Y152539D02*
Y151555D01*
G01X420233Y134822D02*
Y133838D01*
G01X420198Y136515D02*
Y132342D01*
G01Y154035D02*
Y149862D01*
G01X419095D02*
Y154035D01*
G01Y132342D02*
Y136515D01*
G01X419061Y134822D02*
Y133838D01*
G01X419056Y134822D02*
Y133838D01*
G01Y152539D02*
Y151555D01*
G01X418859Y135984D02*
Y129901D01*
G01Y156476D02*
Y150393D01*
G01X418780Y133838D02*
Y152539D01*
G01X418702Y134824D02*
Y133840D01*
G01Y152538D02*
Y151553D01*
G01X418505Y151555D02*
Y156396D01*
G01Y129981D02*
Y134822D01*
G01X418426Y150760D02*
Y151750D01*
G01Y134627D02*
Y135617D01*
G01X418347Y130965D02*
Y129901D01*
G01Y156476D02*
Y155412D01*
G01X418072Y130885D02*
Y129901D01*
G01Y156476D02*
Y155492D01*
G01X417678Y128523D02*
Y123011D01*
G01X417284Y155492D02*
Y156476D01*
G01Y130885D02*
Y129901D01*
G01X417009Y130965D02*
Y129901D01*
G01Y156476D02*
Y155412D01*
G01X416930Y135617D02*
Y134627D01*
G01Y151750D02*
Y150760D01*
G01X416851Y151555D02*
Y156396D01*
G01Y129981D02*
Y134822D01*
G01X416655Y151553D02*
Y152538D01*
G01Y133840D02*
Y134824D01*
G01X416576Y152539D02*
Y133838D01*
G01X416497Y135984D02*
Y129901D01*
G01Y156476D02*
Y150393D01*
G01X416300Y134822D02*
Y133838D01*
G01Y152539D02*
Y151555D01*
G01X416295Y152539D02*
Y151555D01*
G01X416261Y136515D02*
Y132342D01*
G01Y154035D02*
Y149862D01*
G01X415158D02*
Y154035D01*
G01Y132342D02*
Y136515D01*
G01X415124Y152539D02*
Y151555D01*
G01X415119Y134822D02*
Y133838D01*
G01X415114Y134822D02*
Y133838D01*
G01X414922Y135984D02*
Y129901D01*
G01Y156476D02*
Y150393D01*
G01X414843Y133838D02*
Y152539D01*
G01X414769Y152538D02*
Y151553D01*
G01X414760Y134824D02*
Y133840D01*
G01X414568Y147698D02*
Y152539D01*
G01Y133838D02*
Y138680D01*
G01X414494Y150760D02*
Y151750D01*
G01X414484Y134627D02*
Y135617D01*
G01X414410Y138760D02*
Y137696D01*
G01Y148681D02*
Y147618D01*
G01X414135D02*
Y148602D01*
G01Y138760D02*
Y137775D01*
G01X413741Y128523D02*
Y123011D01*
G01X413347Y147618D02*
Y148602D01*
G01Y137775D02*
Y138760D01*
G01X413072D02*
Y137696D01*
G01Y148681D02*
Y147618D01*
G01X412998Y151750D02*
Y150760D01*
G01X412988Y135617D02*
Y134627D01*
G01X412914Y147698D02*
Y152539D01*
G01Y133838D02*
Y138680D01*
G01X412722Y151553D02*
Y152538D01*
G01X412713Y133840D02*
Y134824D01*
G01X412639Y152539D02*
Y133838D01*
G01X412560Y135984D02*
Y129901D01*
G01Y156476D02*
Y150393D01*
G01X412368Y152539D02*
Y151555D01*
G01X412363Y152539D02*
Y151555D01*
G01X412359Y134822D02*
Y133838D01*
G01X412324Y136515D02*
Y132342D01*
G01Y154035D02*
Y149862D01*
G01X411221D02*
Y154035D01*
G01Y132342D02*
Y136515D01*
G01X411187Y134822D02*
Y133838D01*
G01X411182Y134822D02*
Y133838D01*
G01Y152539D02*
Y151555D01*
G01X410985Y135984D02*
Y129901D01*
G01Y156476D02*
Y150393D01*
G01X410906Y133838D02*
Y152539D01*
G01X410828Y134824D02*
Y133840D01*
G01Y152538D02*
Y151553D01*
G01X410631Y151555D02*
Y156396D01*
G01Y129981D02*
Y134822D01*
G01X410592Y128523D02*
Y123011D01*
G01X410552Y150760D02*
Y151750D01*
G01Y134627D02*
Y135617D01*
G01X410473Y130965D02*
Y129901D01*
G01Y156476D02*
Y155412D01*
G01X410198Y130885D02*
Y129901D01*
G01Y156476D02*
Y155492D01*
G01X409410D02*
Y156476D01*
G01Y130885D02*
Y129901D01*
G01X409135Y130965D02*
Y129901D01*
G01Y156476D02*
Y155412D01*
G01X409056Y135617D02*
Y134627D01*
G01Y151750D02*
Y150760D01*
G01X408977Y151555D02*
Y156396D01*
G01Y129981D02*
Y134822D01*
G01X408780Y151553D02*
Y152538D01*
G01Y133840D02*
Y134824D01*
G01X408702Y152539D02*
Y133838D01*
G01X408623Y135984D02*
Y129901D01*
G01Y156476D02*
Y150393D01*
G01X408426Y134822D02*
Y133838D01*
G01Y152539D02*
Y151555D01*
G01X408421Y152539D02*
Y151555D01*
G01X408387Y136515D02*
Y132342D01*
G01Y154035D02*
Y149862D01*
G01X407284D02*
Y154035D01*
G01Y132342D02*
Y136515D01*
G01X407250Y152539D02*
Y151555D01*
G01X407245Y134822D02*
Y133838D01*
G01X407240Y134822D02*
Y133838D01*
G01X407048Y135984D02*
Y129901D01*
G01Y156476D02*
Y150393D01*
G01X406969Y133838D02*
Y152539D01*
G01X406895Y152538D02*
Y151553D01*
G01X406886Y134824D02*
Y133840D01*
G01X406694Y147698D02*
Y152539D01*
G01Y133838D02*
Y138680D01*
G01X406620Y150760D02*
Y151750D01*
G01X406610Y134627D02*
Y135617D01*
G01X406536Y138760D02*
Y137696D01*
G01Y148681D02*
Y147618D01*
G01X406261D02*
Y148602D01*
G01Y138760D02*
Y137775D01*
G01X405473Y147618D02*
Y148602D01*
G01Y137775D02*
Y138760D01*
G01X405198D02*
Y137696D01*
G01Y148681D02*
Y147618D01*
G01X405124Y151750D02*
Y150760D01*
G01X405114Y135617D02*
Y134627D01*
G01X405040Y147698D02*
Y152539D01*
G01Y133838D02*
Y138680D01*
G01X404848Y151553D02*
Y152538D01*
G01X404839Y133840D02*
Y134824D01*
G01X404765Y152539D02*
Y133838D01*
G01X404686Y135984D02*
Y129901D01*
G01Y156476D02*
Y150393D01*
G01X404494Y152539D02*
Y151555D01*
G01X404489Y152539D02*
Y151555D01*
G01X404484Y134822D02*
Y133838D01*
G01X404450Y136515D02*
Y132342D01*
G01Y154035D02*
Y149862D01*
G01X426035Y151368D02*
X426048Y150393D01*
G01X425069Y135009D02*
X425056Y135984D01*
G01X422102Y151368D02*
X422116Y150393D01*
G01X421128Y135009D02*
X421115Y135984D01*
G01X418161Y151368D02*
X418174Y150393D01*
G01X417195Y135009D02*
X417182Y135984D01*
G01X414228Y151368D02*
X414242Y150393D01*
G01X413254Y135009D02*
X413241Y135984D01*
G01X410287Y151368D02*
X410300Y150393D01*
G01X409321Y135009D02*
X409308Y135984D01*
G01X406354Y151368D02*
X406368Y150393D01*
G01X405380Y135009D02*
X405367Y135984D01*
G01X426563Y135117D02*
X426426Y141024D01*
G01X426422Y140138D02*
X426558Y134231D01*
G01X424683Y146239D02*
X424547Y152147D01*
G01X424542Y151260D02*
X424678Y145353D01*
G01X422621Y135117D02*
X422485Y141024D01*
G01X422480Y140138D02*
X422616Y134231D01*
G01X420750Y146239D02*
X420614Y152147D01*
G01X420609Y151260D02*
X420746Y145353D01*
G01X418689Y135117D02*
X418552Y141024D01*
G01X418548Y140138D02*
X418684Y134231D01*
G01X416809Y146239D02*
X416673Y152147D01*
G01X416668Y151260D02*
X416804Y145353D01*
G01X414747Y135117D02*
X414611Y141024D01*
G01X414606Y140138D02*
X414742Y134231D01*
G01X412876Y146239D02*
X412740Y152147D01*
G01X412735Y151260D02*
X412872Y145353D01*
G01X410815Y135117D02*
X410678Y141024D01*
G01X410674Y140138D02*
X410810Y134231D01*
G01X408935Y146239D02*
X408798Y152147D01*
G01X408794Y151260D02*
X408930Y145353D01*
G01X406873Y135117D02*
X406737Y141024D01*
G01X406732Y140138D02*
X406868Y134231D01*
G01X405002Y146239D02*
X404866Y152147D01*
G01X404861Y151260D02*
X404998Y145353D01*
G01X424757Y140340D02*
X424706Y141327D01*
G01X424704Y140365D02*
X424755Y139379D01*
G01X422468Y146012D02*
X422417Y146999D01*
G01X422415Y146037D02*
X422466Y145050D01*
G01X420815Y140340D02*
X420765Y141327D01*
G01X420762Y140365D02*
X420813Y139379D01*
G01X418526Y146012D02*
X418476Y146999D01*
G01X418473Y146037D02*
X418524Y145050D01*
G01X416883Y140340D02*
X416832Y141327D01*
G01X416830Y140365D02*
X416881Y139379D01*
G01X414594Y146012D02*
X414543Y146999D01*
G01X414541Y146037D02*
X414592Y145050D01*
G01X412941Y140340D02*
X412891Y141327D01*
G01X412888Y140365D02*
X412939Y139379D01*
G01X410652Y146012D02*
X410602Y146999D01*
G01X410599Y146037D02*
X410650Y145050D01*
G01X409009Y140340D02*
X408958Y141327D01*
G01X408956Y140365D02*
X409007Y139379D01*
G01X406720Y146012D02*
X406669Y146999D01*
G01X406667Y146037D02*
X406718Y145050D01*
G01X405067Y140340D02*
X405017Y141327D01*
G01X405014Y140365D02*
X405065Y139379D01*
G01X402778Y146012D02*
X402728Y146999D01*
G01X402725Y146037D02*
X402776Y145050D01*
G01X394575Y135984D02*
X394584Y135937D01*
G01X389595Y150441D02*
X389605Y150393D01*
G01X390643Y135937D02*
X390633Y135984D01*
G01X385654Y150441D02*
X385663Y150393D01*
G01X386710Y135937D02*
X386701Y135984D01*
G01X381721Y150441D02*
X381731Y150393D01*
G01X382769Y135937D02*
X382759Y135984D01*
G01X377780Y150441D02*
X377789Y150393D01*
G01X378836Y135937D02*
X378827Y135984D01*
G01X373847Y150441D02*
X373857Y150393D01*
G01X374895Y135937D02*
X374885Y135984D01*
G01X369906Y150441D02*
X369915Y150393D01*
G01X370962Y135937D02*
X370953Y135984D01*
G01X373639Y151737D02*
X373893Y151368D01*
G01X373847Y150441D02*
X373626Y150762D01*
G01X382769Y135937D02*
X382990Y135615D01*
G01X382977Y134640D02*
X382723Y135009D01*
G01X369698Y151737D02*
X369951Y151368D01*
G01X369906Y150441D02*
X369684Y150762D01*
G01X378836Y135937D02*
X379058Y135615D01*
G01X379045Y134640D02*
X378791Y135009D01*
G01X365765Y151737D02*
X366019Y151368D01*
G01X365973Y150441D02*
X365752Y150762D01*
G01X374895Y135937D02*
X375116Y135615D01*
G01X375103Y134640D02*
X374849Y135009D01*
G01X361824Y151737D02*
X362077Y151368D01*
G01X362032Y150441D02*
X361810Y150762D01*
G01X370962Y135937D02*
X371184Y135615D01*
G01X371171Y134640D02*
X370917Y135009D01*
G01X357891Y151737D02*
X358145Y151368D01*
G01X358099Y150441D02*
X357878Y150762D01*
G01X367021Y135937D02*
X367242Y135615D01*
G01X367229Y134640D02*
X366975Y135009D01*
G01X353950Y151737D02*
X354203Y151368D01*
G01X354158Y150441D02*
X353936Y150762D01*
G01X363088Y135937D02*
X363310Y135615D01*
G01X363297Y134640D02*
X363043Y135009D01*
G01X350017Y151737D02*
X350271Y151368D01*
G01X350225Y150441D02*
X350004Y150762D01*
G01X359147Y135937D02*
X359368Y135615D01*
G01X359355Y134640D02*
X359101Y135009D01*
G01X351930Y156476D02*
X349568D01*
G01X355867D02*
X353505D01*
G01X359804D02*
X357442D01*
G01X363741D02*
X361379D01*
G01X367678D02*
X365316D01*
G01X371615D02*
X369253D01*
G01X375552D02*
X373190D01*
G01X379489D02*
X377127D01*
G01X383426D02*
X381064D01*
G01X387363D02*
X385001D01*
G01X391300D02*
X388938D01*
G01X395237D02*
X392875D01*
G01X399174D02*
X396812D01*
G01X403111D02*
X400749D01*
G01X407048D02*
X404686D01*
G01X410985D02*
X408623D01*
G01X414922D02*
X412560D01*
G01X418859D02*
X416497D01*
G01X422796D02*
X420434D01*
G01X426733D02*
X424371D01*
G01X355355Y155492D02*
X354017D01*
G01X363229D02*
X361891D01*
G01X371103D02*
X369765D01*
G01X378977D02*
X377639D01*
G01X386851D02*
X385513D01*
G01X394725D02*
X393387D01*
G01X402599D02*
X401261D01*
G01X410473D02*
X409135D01*
G01X418347D02*
X417009D01*
G01X426221D02*
X424883D01*
G01X424725Y155393D02*
X426379D01*
G01X416851D02*
X418505D01*
G01X408977D02*
X410631D01*
G01X401103D02*
X402757D01*
G01X393229D02*
X394883D01*
G01X385355D02*
X387009D01*
G01X377481D02*
X379135D01*
G01X369607D02*
X371261D01*
G01X361733D02*
X363387D01*
G01X353859D02*
X355513D01*
G01X351930Y155295D02*
X349568D01*
G01X355867D02*
X353505D01*
G01X359804D02*
X357442D01*
G01X363741D02*
X361379D01*
G01X367678D02*
X365316D01*
G01X371615D02*
X369253D01*
G01X375552D02*
X373190D01*
G01X379489D02*
X377127D01*
G01X383426D02*
X381064D01*
G01X387363D02*
X385001D01*
G01X391300D02*
X388938D01*
G01X395237D02*
X392875D01*
G01X399174D02*
X396812D01*
G01X403111D02*
X400749D01*
G01X407048D02*
X404686D01*
G01X410985D02*
X408623D01*
G01X414922D02*
X412560D01*
G01X418859D02*
X416497D01*
G01X422796D02*
X420434D01*
G01X426733D02*
X424371D01*
G01X355513Y154901D02*
X353859D01*
G01X363387D02*
X361733D01*
G01X371261D02*
X369607D01*
G01X379135D02*
X377481D01*
G01X387009D02*
X385355D01*
G01X394883D02*
X393229D01*
G01X402757D02*
X401103D01*
G01X410631D02*
X408977D01*
G01X418505D02*
X416851D01*
G01X426379D02*
X424725D01*
G01X352166Y154035D02*
X349332D01*
G01X356103D02*
X353269D01*
G01X360040D02*
X357206D01*
G01X363977D02*
X361143D01*
G01X367914D02*
X365080D01*
G01X371851D02*
X369017D01*
G01X375788D02*
X372954D01*
G01X379725D02*
X376891D01*
G01X383662D02*
X380828D01*
G01X387599D02*
X384765D01*
G01X391536D02*
X388702D01*
G01X395473D02*
X392639D01*
G01X399410D02*
X396576D01*
G01X403347D02*
X400513D01*
G01X407284D02*
X404450D01*
G01X411221D02*
X408387D01*
G01X415158D02*
X412324D01*
G01X419095D02*
X416261D01*
G01X423032D02*
X420198D01*
G01X426969D02*
X424135D01*
G01X355513Y153130D02*
X353859D01*
G01X363387D02*
X361733D01*
G01X371261D02*
X369607D01*
G01X379135D02*
X377481D01*
G01X387009D02*
X385355D01*
G01X394883D02*
X393229D01*
G01X402757D02*
X401103D01*
G01X410631D02*
X408977D01*
G01X418505D02*
X416851D01*
G01X426379D02*
X424725D01*
G01Y152637D02*
X426379D01*
G01X416851D02*
X418505D01*
G01X408977D02*
X410631D01*
G01X401103D02*
X402757D01*
G01X393229D02*
X394883D01*
G01X385355D02*
X387009D01*
G01X377481D02*
X379135D01*
G01X369607D02*
X371261D01*
G01X361733D02*
X363387D01*
G01X353859D02*
X355513D01*
G01X352166Y152539D02*
X349332D01*
G01X356103D02*
X353269D01*
G01X360040D02*
X357206D01*
G01X363977D02*
X361143D01*
G01X367914D02*
X365080D01*
G01X371851D02*
X369017D01*
G01X375788D02*
X372954D01*
G01X379725D02*
X376891D01*
G01X383662D02*
X380828D01*
G01X387599D02*
X384765D01*
G01X391536D02*
X388702D01*
G01X395473D02*
X392639D01*
G01X399410D02*
X396576D01*
G01X403347D02*
X400513D01*
G01X407284D02*
X404450D01*
G01X411221D02*
X408387D01*
G01X415158D02*
X412324D01*
G01X419095D02*
X416261D01*
G01X423032D02*
X420198D01*
G01X426969D02*
X424135D01*
G01X426379Y152382D02*
X426969D01*
G01X424135D02*
X424725D01*
G01X422442D02*
X423032D01*
G01X420198D02*
X420788D01*
G01X418505D02*
X419095D01*
G01X416261D02*
X416851D01*
G01X414568D02*
X415158D01*
G01X412324D02*
X412914D01*
G01X410631D02*
X411221D01*
G01X408387D02*
X408977D01*
G01X406694D02*
X407284D01*
G01X404450D02*
X405040D01*
G01X402757D02*
X403347D01*
G01X400513D02*
X401103D01*
G01X398820D02*
X399410D01*
G01X396576D02*
X397166D01*
G01X394883D02*
X395473D01*
G01X392639D02*
X393229D01*
G01X390946D02*
X391536D01*
G01X388702D02*
X389292D01*
G01X387009D02*
X387599D01*
G01X384765D02*
X385355D01*
G01X383072D02*
X383662D01*
G01X380828D02*
X381418D01*
G01X379135D02*
X379725D01*
G01X376891D02*
X377481D01*
G01X375198D02*
X375788D01*
G01X372954D02*
X373544D01*
G01X371261D02*
X371851D01*
G01X369017D02*
X369607D01*
G01X367324D02*
X367914D01*
G01X365080D02*
X365670D01*
G01X363387D02*
X363977D01*
G01X361143D02*
X361733D01*
G01X359450D02*
X360040D01*
G01X357206D02*
X357796D01*
G01X355513D02*
X356103D01*
G01X353269D02*
X353859D01*
G01X351576D02*
X352166D01*
G01X349332D02*
X349922D01*
G01X347639D02*
X348229D01*
G01X424547Y152147D02*
X426558D01*
G01X420614D02*
X422625D01*
G01X416673D02*
X418684D01*
G01X412740D02*
X414751D01*
G01X408798D02*
X410810D01*
G01X404866D02*
X406877D01*
G01X400924D02*
X402936D01*
G01X396992D02*
X399003D01*
G01X393050D02*
X395062D01*
G01X389118D02*
X391129D01*
G01X385176D02*
X387188D01*
G01X381244D02*
X383255D01*
G01X377302D02*
X379314D01*
G01X373370D02*
X375381D01*
G01X369428D02*
X371440D01*
G01X365496D02*
X367507D01*
G01X361554D02*
X363566D01*
G01X357622D02*
X359633D01*
G01X353680D02*
X355692D01*
G01X349748D02*
X351759D01*
G01X351503Y151756D02*
X350004D01*
G01X355436D02*
X353936D01*
G01X359377D02*
X357878D01*
G01X363310D02*
X361810D01*
G01X367251D02*
X365752D01*
G01X371184D02*
X369684D01*
G01X375125D02*
X373626D01*
G01X379058D02*
X377558D01*
G01X382999D02*
X381500D01*
G01X386932D02*
X385432D01*
G01X390873D02*
X389374D01*
G01X394806D02*
X393306D01*
G01X398747D02*
X397248D01*
G01X402680D02*
X401180D01*
G01X406621D02*
X405122D01*
G01X410554D02*
X409054D01*
G01X414496D02*
X412996D01*
G01X418428D02*
X416928D01*
G01X422370D02*
X420870D01*
G01X426302D02*
X424802D01*
G01X424816Y151737D02*
X426289D01*
G01X420883D02*
X422356D01*
G01X416942D02*
X418415D01*
G01X413009D02*
X414482D01*
G01X409068D02*
X410541D01*
G01X405135D02*
X406608D01*
G01X401194D02*
X402667D01*
G01X397261D02*
X398734D01*
G01X393320D02*
X394793D01*
G01X389387D02*
X390860D01*
G01X385446D02*
X386919D01*
G01X381513D02*
X382986D01*
G01X377572D02*
X379045D01*
G01X373639D02*
X375112D01*
G01X369698D02*
X371171D01*
G01X365765D02*
X367238D01*
G01X361824D02*
X363297D01*
G01X357891D02*
X359364D01*
G01X353950D02*
X355423D01*
G01X350017D02*
X351490D01*
G01X348229Y151712D02*
X347639D01*
G01X349922D02*
X349332D01*
G01X352166D02*
X351576D01*
G01X353859D02*
X353269D01*
G01X356103D02*
X355513D01*
G01X357796D02*
X357206D01*
G01X360040D02*
X359450D01*
G01X361733D02*
X361143D01*
G01X363977D02*
X363387D01*
G01X365670D02*
X365080D01*
G01X367914D02*
X367324D01*
G01X369607D02*
X369017D01*
G01X371851D02*
X371261D01*
G01X373544D02*
X372954D01*
G01X375788D02*
X375198D01*
G01X377481D02*
X376891D01*
G01X379725D02*
X379135D01*
G01X381418D02*
X380828D01*
G01X383662D02*
X383072D01*
G01X385355D02*
X384765D01*
G01X387599D02*
X387009D01*
G01X389292D02*
X388702D01*
G01X391536D02*
X390946D01*
G01X393229D02*
X392639D01*
G01X395473D02*
X394883D01*
G01X397166D02*
X396576D01*
G01X399410D02*
X398820D01*
G01X401103D02*
X400513D01*
G01X403347D02*
X402757D01*
G01X405040D02*
X404450D01*
G01X407284D02*
X406694D01*
G01X408977D02*
X408387D01*
G01X411221D02*
X410631D01*
G01X412914D02*
X412324D01*
G01X415158D02*
X414568D01*
G01X416851D02*
X416261D01*
G01X419095D02*
X418505D01*
G01X420788D02*
X420198D01*
G01X423032D02*
X422442D01*
G01X424725D02*
X424135D01*
G01X426969D02*
X426379D01*
G01X424135Y151555D02*
X426969D01*
G01X420198D02*
X423032D01*
G01X416261D02*
X419095D01*
G01X412324D02*
X415158D01*
G01X408387D02*
X411221D01*
G01X404450D02*
X407284D01*
G01X400513D02*
X403347D01*
G01X396576D02*
X399410D01*
G01X392639D02*
X395473D01*
G01X388702D02*
X391536D01*
G01X384765D02*
X387599D01*
G01X376891D02*
X379725D01*
G01X372954D02*
X375788D01*
G01X369017D02*
X371851D01*
G01X365080D02*
X367914D01*
G01X361143D02*
X363977D01*
G01X357206D02*
X360040D01*
G01X353269D02*
X356103D01*
G01X352166D02*
X349332D01*
G01X383662D02*
X380828D01*
G01X351576Y151456D02*
X349922D01*
G01X359450D02*
X357796D01*
G01X367324D02*
X365670D01*
G01X375198D02*
X373544D01*
G01X383072D02*
X381418D01*
G01X390946D02*
X389292D01*
G01X398820D02*
X397166D01*
G01X406694D02*
X405040D01*
G01X414568D02*
X412914D01*
G01X422442D02*
X420788D01*
G01X351236Y151368D02*
X350271D01*
G01X355169D02*
X354203D01*
G01X359110D02*
X358145D01*
G01X363043D02*
X362077D01*
G01X366984D02*
X366019D01*
G01X370917D02*
X369951D01*
G01X374858D02*
X373893D01*
G01X378791D02*
X377825D01*
G01X382732D02*
X381767D01*
G01X386665D02*
X385699D01*
G01X390606D02*
X389641D01*
G01X394539D02*
X393573D01*
G01X398480D02*
X397515D01*
G01X402413D02*
X401447D01*
G01X406354D02*
X405389D01*
G01X410287D02*
X409321D01*
G01X414228D02*
X413263D01*
G01X418161D02*
X417195D01*
G01X422102D02*
X421137D01*
G01X426035D02*
X425069D01*
G01X424135Y151358D02*
X424450D01*
G01X420198D02*
X420513D01*
G01X416261D02*
X416576D01*
G01X412324D02*
X412639D01*
G01X408387D02*
X408702D01*
G01X404450D02*
X404765D01*
G01X396576D02*
X396891D01*
G01X388702D02*
X389017D01*
G01X384765D02*
X385080D01*
G01X380828D02*
X381143D01*
G01X376891D02*
X377206D01*
G01X372954D02*
X373269D01*
G01X369017D02*
X369332D01*
G01X365080D02*
X365395D01*
G01X361143D02*
X361458D01*
G01X357206D02*
X357521D01*
G01X353269D02*
X353584D01*
G01X349332D02*
X349647D01*
G01X348229D02*
X347914D01*
G01X352166D02*
X351851D01*
G01X356103D02*
X355788D01*
G01X360040D02*
X359725D01*
G01X363977D02*
X363662D01*
G01X367914D02*
X367599D01*
G01X371851D02*
X371536D01*
G01X375788D02*
X375473D01*
G01X379725D02*
X379410D01*
G01X383662D02*
X383347D01*
G01X387599D02*
X387284D01*
G01X391536D02*
X391221D01*
G01X392954D02*
X392639D01*
G01X395473D02*
X395158D01*
G01X399410D02*
X399095D01*
G01X400828D02*
X400513D01*
G01X403347D02*
X403032D01*
G01X407284D02*
X406969D01*
G01X411221D02*
X410906D01*
G01X415158D02*
X414843D01*
G01X419095D02*
X418780D01*
G01X423032D02*
X422717D01*
G01X426969D02*
X426655D01*
G01X351764Y151260D02*
X349743D01*
G01X355696D02*
X353676D01*
G01X359638D02*
X357617D01*
G01X363570D02*
X361550D01*
G01X367512D02*
X365491D01*
G01X371444D02*
X369424D01*
G01X375386D02*
X373365D01*
G01X379318D02*
X377298D01*
G01X383260D02*
X381239D01*
G01X387192D02*
X385172D01*
G01X391134D02*
X389113D01*
G01X395066D02*
X393046D01*
G01X399008D02*
X396987D01*
G01X402941D02*
X400920D01*
G01X406882D02*
X404861D01*
G01X410815D02*
X408794D01*
G01X414756D02*
X412735D01*
G01X418689D02*
X416668D01*
G01X422630D02*
X420609D01*
G01X426563D02*
X424542D01*
G01X420788Y150964D02*
X422442D01*
G01X412914D02*
X414568D01*
G01X405040D02*
X406694D01*
G01X397166D02*
X398820D01*
G01X389292D02*
X390946D01*
G01X381418D02*
X383072D01*
G01X373544D02*
X375198D01*
G01X365670D02*
X367324D01*
G01X357796D02*
X359450D01*
G01X349922D02*
X351576D01*
G01X351503Y150772D02*
X350004D01*
G01X355436D02*
X353936D01*
G01X359377D02*
X357878D01*
G01X363310D02*
X361810D01*
G01X367251D02*
X365752D01*
G01X371184D02*
X369684D01*
G01X375125D02*
X373626D01*
G01X379058D02*
X377558D01*
G01X382999D02*
X381500D01*
G01X386932D02*
X385432D01*
G01X390873D02*
X389374D01*
G01X394806D02*
X393306D01*
G01X398747D02*
X397248D01*
G01X402680D02*
X401180D01*
G01X406621D02*
X405122D01*
G01X410554D02*
X409054D01*
G01X414496D02*
X412996D01*
G01X418428D02*
X416928D01*
G01X422370D02*
X420870D01*
G01X426302D02*
X424802D01*
G01X351502Y150762D02*
X350005D01*
G01X355434D02*
X353938D01*
G01X359376D02*
X357879D01*
G01X363308D02*
X361812D01*
G01X367250D02*
X365753D01*
G01X371182D02*
X369686D01*
G01X375124D02*
X373627D01*
G01X379056D02*
X377560D01*
G01X382998D02*
X381502D01*
G01X386930D02*
X385434D01*
G01X390872D02*
X389376D01*
G01X394804D02*
X393308D01*
G01X398746D02*
X397250D01*
G01X402678D02*
X401182D01*
G01X406620D02*
X405124D01*
G01X410552D02*
X409056D01*
G01X414494D02*
X412998D01*
G01X418426D02*
X416930D01*
G01X422368D02*
X420872D01*
G01X426300D02*
X424804D01*
G01X425024Y150441D02*
X426080D01*
G01X421092D02*
X422148D01*
G01X417150D02*
X418206D01*
G01X413217D02*
X414274D01*
G01X409276D02*
X410332D01*
G01X405343D02*
X406400D01*
G01X401402D02*
X402458D01*
G01X397469D02*
X398526D01*
G01X393528D02*
X394584D01*
G01X389595D02*
X390652D01*
G01X385654D02*
X386710D01*
G01X381721D02*
X382778D01*
G01X377780D02*
X378836D01*
G01X373847D02*
X374904D01*
G01X369906D02*
X370962D01*
G01X365973D02*
X367030D01*
G01X362032D02*
X363088D01*
G01X358099D02*
X359156D01*
G01X354158D02*
X355214D01*
G01X350225D02*
X351282D01*
G01X400749Y150393D02*
X403111D01*
G01X396812D02*
X399174D01*
G01X392875D02*
X395237D01*
G01X351930D02*
X349568D01*
G01X355867D02*
X353505D01*
G01X359804D02*
X357442D01*
G01X363741D02*
X361379D01*
G01X367678D02*
X365316D01*
G01X371615D02*
X369253D01*
G01X375552D02*
X373190D01*
G01X379489D02*
X377127D01*
G01X383426D02*
X381064D01*
G01X387363D02*
X385001D01*
G01X391300D02*
X388938D01*
G01X407048D02*
X404686D01*
G01X410985D02*
X408623D01*
G01X414922D02*
X412560D01*
G01X418859D02*
X416497D01*
G01X422796D02*
X420434D01*
G01X426733D02*
X424371D01*
G01X426655Y149862D02*
X426969D01*
G01X424135D02*
X424450D01*
G01X422717D02*
X423032D01*
G01X420198D02*
X420513D01*
G01X418780D02*
X419095D01*
G01X416261D02*
X416576D01*
G01X414843D02*
X415158D01*
G01X412324D02*
X412639D01*
G01X410906D02*
X411221D01*
G01X408387D02*
X408702D01*
G01X406969D02*
X407284D01*
G01X403032D02*
X403347D01*
G01X404450D02*
X404765D01*
G01X400513D02*
X400828D01*
G01X399095D02*
X399410D01*
G01X396576D02*
X396891D01*
G01X395158D02*
X395473D01*
G01X392639D02*
X392954D01*
G01X391221D02*
X391536D01*
G01X388702D02*
X389017D01*
G01X387284D02*
X387599D01*
G01X384765D02*
X385080D01*
G01X383347D02*
X383662D01*
G01X380828D02*
X381143D01*
G01X379410D02*
X379725D01*
G01X376891D02*
X377206D01*
G01X375473D02*
X375788D01*
G01X372954D02*
X373269D01*
G01X371536D02*
X371851D01*
G01X369017D02*
X369332D01*
G01X367599D02*
X367914D01*
G01X365080D02*
X365395D01*
G01X363662D02*
X363977D01*
G01X361143D02*
X361458D01*
G01X359725D02*
X360040D01*
G01X357206D02*
X357521D01*
G01X355788D02*
X356103D01*
G01X353269D02*
X353584D01*
G01X351851D02*
X352166D01*
G01X349332D02*
X349647D01*
G01X347914D02*
X348229D01*
G01X424780Y149826D02*
X426324D01*
G01X420848D02*
X422391D01*
G01X416906D02*
X418450D01*
G01X412974D02*
X414517D01*
G01X409032D02*
X410576D01*
G01X405100D02*
X406643D01*
G01X401158D02*
X402702D01*
G01X397226D02*
X398769D01*
G01X393284D02*
X394828D01*
G01X389352D02*
X390895D01*
G01X385410D02*
X386954D01*
G01X381478D02*
X383021D01*
G01X377536D02*
X379080D01*
G01X373604D02*
X375147D01*
G01X369662D02*
X371206D01*
G01X365730D02*
X367273D01*
G01X361788D02*
X363332D01*
G01X357856D02*
X359399D01*
G01X353914D02*
X355458D01*
G01X349982D02*
X351525D01*
G01X424791Y149807D02*
X426313D01*
G01X420859D02*
X422381D01*
G01X416917D02*
X418439D01*
G01X412985D02*
X414507D01*
G01X409043D02*
X410565D01*
G01X405111D02*
X406632D01*
G01X401169D02*
X402691D01*
G01X397237D02*
X398758D01*
G01X393295D02*
X394817D01*
G01X389363D02*
X390884D01*
G01X385421D02*
X386943D01*
G01X381489D02*
X383010D01*
G01X377547D02*
X379069D01*
G01X373615D02*
X375136D01*
G01X369673D02*
X371195D01*
G01X365741D02*
X367262D01*
G01X361799D02*
X363321D01*
G01X357867D02*
X359388D01*
G01X353925D02*
X355447D01*
G01X349993D02*
X351514D01*
G01X420788Y149193D02*
X422442D01*
G01X412914D02*
X414568D01*
G01X405040D02*
X406694D01*
G01X397166D02*
X398820D01*
G01X389292D02*
X390946D01*
G01X381418D02*
X383072D01*
G01X373544D02*
X375198D01*
G01X365670D02*
X367324D01*
G01X357796D02*
X359450D01*
G01X349922D02*
X351576D01*
G01Y148700D02*
X349922D01*
G01X359450D02*
X357796D01*
G01X367324D02*
X365670D01*
G01X375198D02*
X373544D01*
G01X383072D02*
X381418D01*
G01X390946D02*
X389292D01*
G01X398820D02*
X397166D01*
G01X406694D02*
X405040D01*
G01X414568D02*
X412914D01*
G01X422442D02*
X420788D01*
G01X351418Y148602D02*
X350080D01*
G01X359292D02*
X357954D01*
G01X367166D02*
X365828D01*
G01X375040D02*
X373702D01*
G01X382914D02*
X381576D01*
G01X390788D02*
X389450D01*
G01X398662D02*
X397324D01*
G01X406536D02*
X405198D01*
G01X414410D02*
X413072D01*
G01X422284D02*
X420946D01*
G01Y147618D02*
X422284D01*
G01X413072D02*
X414410D01*
G01X405198D02*
X406536D01*
G01X397324D02*
X398662D01*
G01X389450D02*
X390788D01*
G01X381576D02*
X382914D01*
G01X373702D02*
X375040D01*
G01X365828D02*
X367166D01*
G01X357954D02*
X359292D01*
G01X350080D02*
X351418D01*
G01X351551Y146999D02*
X349956D01*
G01X355484D02*
X353888D01*
G01X359425D02*
X357830D01*
G01X363358D02*
X361762D01*
G01X367299D02*
X365704D01*
G01X371232D02*
X369636D01*
G01X375173D02*
X373578D01*
G01X379106D02*
X377510D01*
G01X383047D02*
X381452D01*
G01X386980D02*
X385384D01*
G01X390921D02*
X389326D01*
G01X394854D02*
X393258D01*
G01X398795D02*
X397200D01*
G01X402728D02*
X401133D01*
G01X406669D02*
X405074D01*
G01X410602D02*
X409007D01*
G01X414543D02*
X412948D01*
G01X418476D02*
X416881D01*
G01X422417D02*
X420822D01*
G01X426350D02*
X424755D01*
G01X351851Y146889D02*
X349647D01*
G01X355788D02*
X353584D01*
G01X359725D02*
X357521D01*
G01X363662D02*
X361458D01*
G01X367599D02*
X365395D01*
G01X371536D02*
X369332D01*
G01X375473D02*
X373269D01*
G01X379410D02*
X377206D01*
G01X383347D02*
X381143D01*
G01X387284D02*
X385080D01*
G01X391221D02*
X389017D01*
G01X395158D02*
X392954D01*
G01X399095D02*
X396891D01*
G01X403032D02*
X400828D01*
G01X406969D02*
X404765D01*
G01X410906D02*
X408702D01*
G01X414843D02*
X412639D01*
G01X418780D02*
X416576D01*
G01X422717D02*
X420513D01*
G01X426655D02*
X424450D01*
G01X351623Y146239D02*
X349884D01*
G01X355555D02*
X353817D01*
G01X359497D02*
X357758D01*
G01X363429D02*
X361691D01*
G01X367371D02*
X365632D01*
G01X371303D02*
X369565D01*
G01X375245D02*
X373506D01*
G01X379177D02*
X377439D01*
G01X383119D02*
X381380D01*
G01X387051D02*
X385313D01*
G01X390993D02*
X389254D01*
G01X394925D02*
X393187D01*
G01X398867D02*
X397128D01*
G01X402799D02*
X401061D01*
G01X406741D02*
X405002D01*
G01X410674D02*
X408935D01*
G01X414615D02*
X412876D01*
G01X418548D02*
X416809D01*
G01X422489D02*
X420750D01*
G01X426422D02*
X424683D01*
G01X424757Y146037D02*
X426347D01*
G01X420825D02*
X422415D01*
G01X416883D02*
X418473D01*
G01X412951D02*
X414541D01*
G01X409009D02*
X410599D01*
G01X405077D02*
X406667D01*
G01X401135D02*
X402725D01*
G01X397203D02*
X398793D01*
G01X393261D02*
X394851D01*
G01X389328D02*
X390919D01*
G01X385387D02*
X386977D01*
G01X381454D02*
X383045D01*
G01X377513D02*
X379103D01*
G01X373580D02*
X375171D01*
G01X369639D02*
X371229D01*
G01X365706D02*
X367297D01*
G01X361765D02*
X363355D01*
G01X357832D02*
X359423D01*
G01X353891D02*
X355481D01*
G01X349958D02*
X351549D01*
G01X424704Y146012D02*
X426400D01*
G01X420772D02*
X422468D01*
G01X416830D02*
X418526D01*
G01X412898D02*
X414594D01*
G01X408956D02*
X410652D01*
G01X405024D02*
X406720D01*
G01X401082D02*
X402778D01*
G01X397150D02*
X398846D01*
G01X393208D02*
X394904D01*
G01X389276D02*
X390972D01*
G01X385334D02*
X387030D01*
G01X381402D02*
X383098D01*
G01X377460D02*
X379156D01*
G01X373528D02*
X375224D01*
G01X369586D02*
X371282D01*
G01X365654D02*
X367350D01*
G01X361712D02*
X363408D01*
G01X357780D02*
X359476D01*
G01X353838D02*
X355534D01*
G01X349906D02*
X351602D01*
G01X351609Y145945D02*
X349899D01*
G01X355541D02*
X353831D01*
G01X359483D02*
X357773D01*
G01X363415D02*
X361705D01*
G01X367357D02*
X365647D01*
G01X371289D02*
X369579D01*
G01X375231D02*
X373521D01*
G01X379163D02*
X377453D01*
G01X383105D02*
X381395D01*
G01X387037D02*
X385327D01*
G01X390979D02*
X389269D01*
G01X394911D02*
X393201D01*
G01X398853D02*
X397143D01*
G01X402785D02*
X401075D01*
G01X406727D02*
X405017D01*
G01X410659D02*
X408949D01*
G01X414601D02*
X412891D01*
G01X418533D02*
X416823D01*
G01X422475D02*
X420765D01*
G01X426407D02*
X424697D01*
G01X424678Y145353D02*
X426426D01*
G01X420746D02*
X422494D01*
G01X416804D02*
X418552D01*
G01X412872D02*
X414620D01*
G01X408930D02*
X410678D01*
G01X404998D02*
X406746D01*
G01X401056D02*
X402804D01*
G01X397124D02*
X398872D01*
G01X393182D02*
X394930D01*
G01X389250D02*
X390998D01*
G01X385308D02*
X387056D01*
G01X381376D02*
X383124D01*
G01X377434D02*
X379182D01*
G01X373502D02*
X375250D01*
G01X369560D02*
X371308D01*
G01X365628D02*
X367376D01*
G01X361686D02*
X363434D01*
G01X357753D02*
X359502D01*
G01X353812D02*
X355560D01*
G01X349879D02*
X351628D01*
G01X351599Y145050D02*
X349908D01*
G01X355532D02*
X353840D01*
G01X359473D02*
X357782D01*
G01X363406D02*
X361714D01*
G01X367347D02*
X365656D01*
G01X371280D02*
X369588D01*
G01X375221D02*
X373530D01*
G01X379154D02*
X377462D01*
G01X383095D02*
X381404D01*
G01X387028D02*
X385336D01*
G01X390969D02*
X389278D01*
G01X394902D02*
X393210D01*
G01X398843D02*
X397152D01*
G01X402776D02*
X401084D01*
G01X406718D02*
X405026D01*
G01X410650D02*
X408958D01*
G01X414592D02*
X412900D01*
G01X418524D02*
X416832D01*
G01X422466D02*
X420774D01*
G01X426398D02*
X424706D01*
G01X351609Y144960D02*
X349899D01*
G01X355541D02*
X353831D01*
G01X359483D02*
X357773D01*
G01X363415D02*
X361705D01*
G01X367357D02*
X365647D01*
G01X371289D02*
X369579D01*
G01X375231D02*
X373521D01*
G01X379163D02*
X377453D01*
G01X383105D02*
X381395D01*
G01X387037D02*
X385327D01*
G01X390979D02*
X389269D01*
G01X394911D02*
X393201D01*
G01X398853D02*
X397143D01*
G01X402785D02*
X401075D01*
G01X406727D02*
X405017D01*
G01X410659D02*
X408949D01*
G01X414601D02*
X412891D01*
G01X418533D02*
X416823D01*
G01X422475D02*
X420765D01*
G01X426407D02*
X424697D01*
G01X424450Y144634D02*
X426655D01*
G01X420513D02*
X422717D01*
G01X416576D02*
X418780D01*
G01X412639D02*
X414843D01*
G01X408702D02*
X410906D01*
G01X404765D02*
X406969D01*
G01X400828D02*
X403032D01*
G01X396891D02*
X399095D01*
G01X392954D02*
X395158D01*
G01X389017D02*
X391221D01*
G01X385080D02*
X387284D01*
G01X381143D02*
X383347D01*
G01X377206D02*
X379410D01*
G01X373269D02*
X375473D01*
G01X369332D02*
X371536D01*
G01X365395D02*
X367599D01*
G01X361458D02*
X363662D01*
G01X357521D02*
X359725D01*
G01X353584D02*
X355788D01*
G01X349647D02*
X351851D01*
G01X424450Y144467D02*
X426655D01*
G01X420513D02*
X422717D01*
G01X416576D02*
X418780D01*
G01X412639D02*
X414843D01*
G01X408702D02*
X410906D01*
G01X404765D02*
X406969D01*
G01X400828D02*
X403032D01*
G01X396891D02*
X399095D01*
G01X392954D02*
X395158D01*
G01X389017D02*
X391221D01*
G01X385080D02*
X387284D01*
G01X381143D02*
X383347D01*
G01X377206D02*
X379410D01*
G01X373269D02*
X375473D01*
G01X369332D02*
X371536D01*
G01X365395D02*
X367599D01*
G01X361458D02*
X363662D01*
G01X357521D02*
X359725D01*
G01X353584D02*
X355788D01*
G01X349647D02*
X351851D01*
G01Y141910D02*
X349647D01*
G01X355788D02*
X353584D01*
G01X359725D02*
X357521D01*
G01X363662D02*
X361458D01*
G01X367599D02*
X365395D01*
G01X371536D02*
X369332D01*
G01X375473D02*
X373269D01*
G01X379410D02*
X377206D01*
G01X383347D02*
X381143D01*
G01X387284D02*
X385080D01*
G01X391221D02*
X389017D01*
G01X395158D02*
X392954D01*
G01X399095D02*
X396891D01*
G01X403032D02*
X400828D01*
G01X406969D02*
X404765D01*
G01X410906D02*
X408702D01*
G01X414843D02*
X412639D01*
G01X418780D02*
X416576D01*
G01X422717D02*
X420513D01*
G01X426655D02*
X424450D01*
G01X351851Y141743D02*
X349647D01*
G01X355788D02*
X353584D01*
G01X359725D02*
X357521D01*
G01X363662D02*
X361458D01*
G01X367599D02*
X365395D01*
G01X371536D02*
X369332D01*
G01X375473D02*
X373269D01*
G01X379410D02*
X377206D01*
G01X383347D02*
X381143D01*
G01X387284D02*
X385080D01*
G01X391221D02*
X389017D01*
G01X395158D02*
X392954D01*
G01X399095D02*
X396891D01*
G01X403032D02*
X400828D01*
G01X406969D02*
X404765D01*
G01X410906D02*
X408702D01*
G01X414843D02*
X412639D01*
G01X418780D02*
X416576D01*
G01X422717D02*
X420513D01*
G01X426655D02*
X424450D01*
G01X424697Y141417D02*
X426407D01*
G01X420755D02*
X422466D01*
G01X416823D02*
X418533D01*
G01X412881D02*
X414592D01*
G01X408949D02*
X410659D01*
G01X405007D02*
X406718D01*
G01X401075D02*
X402785D01*
G01X397133D02*
X398843D01*
G01X393201D02*
X394911D01*
G01X389259D02*
X390969D01*
G01X385327D02*
X387037D01*
G01X381385D02*
X383095D01*
G01X377453D02*
X379163D01*
G01X373511D02*
X375221D01*
G01X369579D02*
X371289D01*
G01X365637D02*
X367347D01*
G01X361705D02*
X363415D01*
G01X357763D02*
X359473D01*
G01X353831D02*
X355541D01*
G01X349889D02*
X351599D01*
G01X424706Y141327D02*
X426398D01*
G01X420765D02*
X422456D01*
G01X416832D02*
X418524D01*
G01X412891D02*
X414582D01*
G01X408958D02*
X410650D01*
G01X405017D02*
X406708D01*
G01X401084D02*
X402776D01*
G01X397143D02*
X398834D01*
G01X393210D02*
X394902D01*
G01X389269D02*
X390960D01*
G01X385336D02*
X387028D01*
G01X381395D02*
X383086D01*
G01X377462D02*
X379154D01*
G01X373521D02*
X375212D01*
G01X369588D02*
X371280D01*
G01X365647D02*
X367338D01*
G01X361714D02*
X363406D01*
G01X357773D02*
X359464D01*
G01X353840D02*
X355532D01*
G01X349899D02*
X351590D01*
G01X351619Y141024D02*
X349870D01*
G01X355560D02*
X353812D01*
G01X359493D02*
X357744D01*
G01X363434D02*
X361686D01*
G01X367367D02*
X365618D01*
G01X371308D02*
X369560D01*
G01X375241D02*
X373492D01*
G01X379182D02*
X377434D01*
G01X383115D02*
X381366D01*
G01X387056D02*
X385308D01*
G01X390989D02*
X389240D01*
G01X394930D02*
X393182D01*
G01X398863D02*
X397114D01*
G01X402804D02*
X401056D01*
G01X406737D02*
X404988D01*
G01X410678D02*
X408930D01*
G01X414611D02*
X412862D01*
G01X418552D02*
X416804D01*
G01X422485D02*
X420736D01*
G01X426426D02*
X424678D01*
G01X424697Y140433D02*
X426407D01*
G01X420755D02*
X422466D01*
G01X416823D02*
X418533D01*
G01X412881D02*
X414592D01*
G01X408949D02*
X410659D01*
G01X405007D02*
X406718D01*
G01X401075D02*
X402785D01*
G01X397133D02*
X398843D01*
G01X393201D02*
X394911D01*
G01X389259D02*
X390969D01*
G01X385327D02*
X387037D01*
G01X381385D02*
X383095D01*
G01X377453D02*
X379163D01*
G01X373511D02*
X375221D01*
G01X369579D02*
X371289D01*
G01X365637D02*
X367347D01*
G01X361705D02*
X363415D01*
G01X357763D02*
X359473D01*
G01X353831D02*
X355541D01*
G01X349889D02*
X351599D01*
G01X351592Y140365D02*
X349896D01*
G01X355534D02*
X353838D01*
G01X359466D02*
X357770D01*
G01X363408D02*
X361712D01*
G01X367340D02*
X365644D01*
G01X371282D02*
X369586D01*
G01X375214D02*
X373518D01*
G01X379156D02*
X377460D01*
G01X383088D02*
X381392D01*
G01X387030D02*
X385334D01*
G01X390962D02*
X389266D01*
G01X394904D02*
X393208D01*
G01X398836D02*
X397140D01*
G01X402778D02*
X401082D01*
G01X406711D02*
X405014D01*
G01X410652D02*
X408956D01*
G01X414585D02*
X412888D01*
G01X418526D02*
X416830D01*
G01X422459D02*
X420762D01*
G01X426400D02*
X424704D01*
G01X351540Y140340D02*
X349949D01*
G01X355481D02*
X353891D01*
G01X359414D02*
X357823D01*
G01X363355D02*
X361765D01*
G01X367288D02*
X365697D01*
G01X371229D02*
X369639D01*
G01X375162D02*
X373571D01*
G01X379103D02*
X377513D01*
G01X383036D02*
X381445D01*
G01X386977D02*
X385387D01*
G01X390910D02*
X389319D01*
G01X394851D02*
X393261D01*
G01X398784D02*
X397193D01*
G01X402725D02*
X401135D01*
G01X406658D02*
X405067D01*
G01X410599D02*
X409009D01*
G01X414532D02*
X412941D01*
G01X418473D02*
X416883D01*
G01X422406D02*
X420815D01*
G01X426347D02*
X424757D01*
G01X424683Y140138D02*
X426422D01*
G01X420741D02*
X422480D01*
G01X416809D02*
X418548D01*
G01X412867D02*
X414606D01*
G01X408935D02*
X410674D01*
G01X404993D02*
X406732D01*
G01X401061D02*
X402799D01*
G01X397119D02*
X398858D01*
G01X393187D02*
X394925D01*
G01X389245D02*
X390984D01*
G01X385313D02*
X387051D01*
G01X381371D02*
X383110D01*
G01X377439D02*
X379177D01*
G01X373497D02*
X375236D01*
G01X369565D02*
X371303D01*
G01X365623D02*
X367362D01*
G01X361691D02*
X363429D01*
G01X357749D02*
X359488D01*
G01X353817D02*
X355555D01*
G01X349875D02*
X351614D01*
G01X424450Y139488D02*
X426655D01*
G01X420513D02*
X422717D01*
G01X416576D02*
X418780D01*
G01X412639D02*
X414843D01*
G01X408702D02*
X410906D01*
G01X404765D02*
X406969D01*
G01X400828D02*
X403032D01*
G01X396891D02*
X399095D01*
G01X392954D02*
X395158D01*
G01X389017D02*
X391221D01*
G01X385080D02*
X387284D01*
G01X381143D02*
X383347D01*
G01X377206D02*
X379410D01*
G01X373269D02*
X375473D01*
G01X369332D02*
X371536D01*
G01X365395D02*
X367599D01*
G01X361458D02*
X363662D01*
G01X357521D02*
X359725D01*
G01X353584D02*
X355788D01*
G01X349647D02*
X351851D01*
G01X424755Y139379D02*
X426350D01*
G01X420813D02*
X422408D01*
G01X416881D02*
X418476D01*
G01X412939D02*
X414534D01*
G01X409007D02*
X410602D01*
G01X405065D02*
X406660D01*
G01X401133D02*
X402728D01*
G01X397191D02*
X398786D01*
G01X393258D02*
X394854D01*
G01X389317D02*
X390912D01*
G01X385384D02*
X386980D01*
G01X381443D02*
X383038D01*
G01X377510D02*
X379106D01*
G01X373569D02*
X375164D01*
G01X369636D02*
X371232D01*
G01X365695D02*
X367290D01*
G01X361762D02*
X363358D01*
G01X357821D02*
X359416D01*
G01X353888D02*
X355484D01*
G01X349947D02*
X351542D01*
G01X351418Y138760D02*
X350080D01*
G01X359292D02*
X357954D01*
G01X367166D02*
X365828D01*
G01X375040D02*
X373702D01*
G01X382914D02*
X381576D01*
G01X390788D02*
X389450D01*
G01X398662D02*
X397324D01*
G01X406536D02*
X405198D01*
G01X414410D02*
X413072D01*
G01X422284D02*
X420946D01*
G01X351418Y137775D02*
X350080D01*
G01X359292D02*
X357954D01*
G01X367166D02*
X365828D01*
G01X375040D02*
X373702D01*
G01X382914D02*
X381576D01*
G01X390788D02*
X389450D01*
G01X398662D02*
X397324D01*
G01X406536D02*
X405198D01*
G01X414410D02*
X413072D01*
G01X422284D02*
X420946D01*
G01X420788Y137677D02*
X422442D01*
G01X412914D02*
X414568D01*
G01X405040D02*
X406694D01*
G01X397166D02*
X398820D01*
G01X389292D02*
X390946D01*
G01X381418D02*
X383072D01*
G01X373544D02*
X375198D01*
G01X365670D02*
X367324D01*
G01X357796D02*
X359450D01*
G01X349922D02*
X351576D01*
G01Y137185D02*
X349922D01*
G01X359450D02*
X357796D01*
G01X367324D02*
X365670D01*
G01X375198D02*
X373544D01*
G01X383072D02*
X381418D01*
G01X390946D02*
X389292D01*
G01X398820D02*
X397166D01*
G01X406694D02*
X405040D01*
G01X414568D02*
X412914D01*
G01X422442D02*
X420788D01*
G01X418197Y150393D02*
X418206Y150441D01*
G01X413218Y135984D02*
X413208Y135937D01*
G01X414264Y150393D02*
X414274Y150441D01*
G01X409285Y135984D02*
X409276Y135937D01*
G01X410323Y150393D02*
X410332Y150441D01*
G01X405344Y135984D02*
X405334Y135937D01*
G01X406390Y150393D02*
X406400Y150441D01*
G01X401402Y135937D02*
X401411Y135984D01*
G01X402458Y150441D02*
X402449Y150393D01*
G01X397470Y135984D02*
X397460Y135937D01*
G01X398516Y150393D02*
X398526Y150441D01*
G01X393528Y135937D02*
X393537Y135984D01*
G01X394584Y150441D02*
X394575Y150393D01*
G01X406660Y139379D02*
X406711Y140365D01*
G01X406708Y141327D02*
X406658Y140340D01*
G01X405026Y145050D02*
X405077Y146037D01*
G01X405074Y146999D02*
X405024Y146012D01*
G01X402728Y139379D02*
X402778Y140365D01*
G01X402776Y141327D02*
X402725Y140340D01*
G01X401084Y145050D02*
X401135Y146037D01*
G01X401133Y146999D02*
X401082Y146012D01*
G01X398786Y139379D02*
X398836Y140365D01*
G01X398834Y141327D02*
X398784Y140340D01*
G01X397152Y145050D02*
X397203Y146037D01*
G01X397200Y146999D02*
X397150Y146012D01*
G01X394854Y139379D02*
X394904Y140365D01*
G01X394902Y141327D02*
X394851Y140340D01*
G01X393210Y145050D02*
X393261Y146037D01*
G01X393258Y146999D02*
X393208Y146012D01*
G01X390912Y139379D02*
X390962Y140365D01*
G01X390960Y141327D02*
X390910Y140340D01*
G01X389278Y145050D02*
X389328Y146037D01*
G01X389326Y146999D02*
X389276Y146012D01*
G01X386980Y139379D02*
X387030Y140365D01*
G01X387028Y141327D02*
X386977Y140340D01*
G01X385336Y145050D02*
X385387Y146037D01*
G01X385384Y146999D02*
X385334Y146012D01*
G01X383038Y139379D02*
X383088Y140365D01*
G01X383086Y141327D02*
X383036Y140340D01*
G01X404857Y134231D02*
X404993Y140138D01*
G01X404988Y141024D02*
X404852Y135117D01*
G01X402804Y145353D02*
X402941Y151260D01*
G01X402936Y152147D02*
X402799Y146239D01*
G01X400924Y134231D02*
X401061Y140138D01*
G01X401056Y141024D02*
X400920Y135117D01*
G01X398872Y145353D02*
X399008Y151260D01*
G01X399003Y152147D02*
X398867Y146239D01*
G01X396983Y134231D02*
X397119Y140138D01*
G01X397114Y141024D02*
X396978Y135117D01*
G01X394930Y145353D02*
X395066Y151260D01*
G01X395062Y152147D02*
X394925Y146239D01*
G01X393050Y134231D02*
X393187Y140138D01*
G01X393182Y141024D02*
X393046Y135117D01*
G01X390998Y145353D02*
X391134Y151260D01*
G01X391129Y152147D02*
X390993Y146239D01*
G01X389109Y134231D02*
X389245Y140138D01*
G01X389240Y141024D02*
X389104Y135117D01*
G01X387056Y145353D02*
X387192Y151260D01*
G01X387188Y152147D02*
X387051Y146239D01*
G01X385176Y134231D02*
X385313Y140138D01*
G01X385308Y141024D02*
X385172Y135117D01*
G01X383124Y145353D02*
X383260Y151260D01*
G01X383255Y152147D02*
X383119Y146239D01*
G01X381235Y134231D02*
X381371Y140138D01*
G01X381366Y141024D02*
X381230Y135117D01*
G01X402426Y135984D02*
X402413Y135009D01*
G01X401434Y150393D02*
X401447Y151368D01*
G01X398484Y135984D02*
X398471Y135009D01*
G01X397502Y150393D02*
X397515Y151368D01*
G01X394552Y135984D02*
X394539Y135009D01*
G01X393560Y150393D02*
X393573Y151368D01*
G01X390610Y135984D02*
X390597Y135009D01*
G01X389628Y150393D02*
X389641Y151368D01*
G01X386678Y135984D02*
X386665Y135009D01*
G01X385686Y150393D02*
X385699Y151368D01*
G01X382736Y135984D02*
X382723Y135009D01*
G01X381754Y150393D02*
X381767Y151368D01*
G01X403347Y149862D02*
Y154035D01*
G01Y132342D02*
Y136515D01*
G01X403313Y134822D02*
Y133838D01*
G01X403308Y134822D02*
Y133838D01*
G01Y152539D02*
Y151555D01*
G01X403111Y135984D02*
Y129901D01*
G01Y156476D02*
Y150393D01*
G01X403032Y133838D02*
Y152539D01*
G01X402954Y134824D02*
Y133840D01*
G01Y152538D02*
Y151553D01*
G01X402757Y151555D02*
Y156396D01*
G01Y129981D02*
Y134822D01*
G01X402678Y150760D02*
Y151750D01*
G01Y134627D02*
Y135617D01*
G01X402599Y130965D02*
Y129901D01*
G01Y156476D02*
Y155412D01*
G01X402324Y129901D02*
Y130885D01*
G01Y156476D02*
Y155492D01*
G01X401536Y130885D02*
Y129901D01*
G01Y156476D02*
Y155492D01*
G01X401261Y130965D02*
Y129901D01*
G01Y156476D02*
Y155412D01*
G01X401182Y135617D02*
Y134627D01*
G01Y151750D02*
Y150760D01*
G01X401103Y151555D02*
Y156396D01*
G01Y129981D02*
Y134822D01*
G01X400906Y133840D02*
Y134824D01*
G01Y151553D02*
Y152538D01*
G01X400828Y152539D02*
Y133838D01*
G01X400749Y135984D02*
Y129901D01*
G01Y156476D02*
Y150393D01*
G01X400552Y134822D02*
Y133838D01*
G01Y152539D02*
Y151555D01*
G01X400547Y152539D02*
Y151555D01*
G01X400513Y136515D02*
Y132342D01*
G01Y154035D02*
Y149862D01*
G01X399410D02*
Y154035D01*
G01Y132342D02*
Y136515D01*
G01X399376Y152539D02*
Y151555D01*
G01X399371Y134822D02*
Y133838D01*
G01X399366Y134822D02*
Y133838D01*
G01X399174Y135984D02*
Y129901D01*
G01Y156476D02*
Y150393D01*
G01X399095Y133838D02*
Y152539D01*
G01X399021Y152538D02*
Y151553D01*
G01X399012Y134824D02*
Y133840D01*
G01X398820Y147698D02*
Y152539D01*
G01Y133838D02*
Y138680D01*
G01X398746Y150760D02*
Y151750D01*
G01X398736Y134627D02*
Y135617D01*
G01X398662Y138760D02*
Y137696D01*
G01Y148681D02*
Y147618D01*
G01X398387D02*
Y148602D01*
G01Y138760D02*
Y137775D01*
G01X397599Y147618D02*
Y148602D01*
G01Y138760D02*
Y137775D01*
G01X397324Y138760D02*
Y137696D01*
G01Y148681D02*
Y147618D01*
G01X397250Y151750D02*
Y150760D01*
G01X397240Y135617D02*
Y134627D01*
G01X397206Y128523D02*
Y123011D01*
G01X397166Y147698D02*
Y152539D01*
G01Y133838D02*
Y138680D01*
G01X396974Y151553D02*
Y152538D01*
G01X396965Y133840D02*
Y134824D01*
G01X396891Y152539D02*
Y133838D01*
G01X396812Y135984D02*
Y129901D01*
G01Y156476D02*
Y150393D01*
G01X396620Y152539D02*
Y151555D01*
G01X396615Y152539D02*
Y151555D01*
G01X396610Y134822D02*
Y133838D01*
G01X396576Y136515D02*
Y132342D01*
G01Y154035D02*
Y149862D01*
G01X395473D02*
Y154035D01*
G01Y132342D02*
Y136515D01*
G01X395439Y134822D02*
Y133838D01*
G01X395434Y134822D02*
Y133838D01*
G01Y152539D02*
Y151555D01*
G01X395237Y135984D02*
Y129901D01*
G01Y156476D02*
Y150393D01*
G01X395158Y133838D02*
Y152539D01*
G01X395080Y134824D02*
Y133840D01*
G01Y152538D02*
Y151553D01*
G01X394883Y151555D02*
Y156396D01*
G01Y129981D02*
Y134822D01*
G01X394804Y150760D02*
Y151750D01*
G01Y134627D02*
Y135617D01*
G01X394725Y130965D02*
Y129901D01*
G01Y156476D02*
Y155412D01*
G01X394450Y129901D02*
Y130885D01*
G01Y156476D02*
Y155492D01*
G01X394056Y128523D02*
Y123011D01*
G01X393662Y130885D02*
Y129901D01*
G01Y156476D02*
Y155492D01*
G01X393387Y130965D02*
Y129901D01*
G01Y156476D02*
Y155412D01*
G01X393308Y135617D02*
Y134627D01*
G01Y151750D02*
Y150760D01*
G01X393229Y151555D02*
Y156396D01*
G01Y129981D02*
Y134822D01*
G01X393032Y133840D02*
Y134824D01*
G01Y151553D02*
Y152538D01*
G01X392954Y152539D02*
Y133838D01*
G01X392875Y135984D02*
Y129901D01*
G01Y156476D02*
Y150393D01*
G01X392678Y134822D02*
Y133838D01*
G01Y152539D02*
Y151555D01*
G01X392673Y152539D02*
Y151555D01*
G01X392639Y136515D02*
Y132342D01*
G01Y154035D02*
Y149862D01*
G01X391536D02*
Y154035D01*
G01Y132342D02*
Y136515D01*
G01X391502Y152539D02*
Y151555D01*
G01X391497Y134822D02*
Y133838D01*
G01X391492Y134822D02*
Y133838D01*
G01X391300Y135984D02*
Y129901D01*
G01Y156476D02*
Y150393D01*
G01X391221Y133838D02*
Y152539D01*
G01X391147Y152538D02*
Y151553D01*
G01X391138Y134824D02*
Y133840D01*
G01X390946Y147698D02*
Y152539D01*
G01Y133838D02*
Y138680D01*
G01X390872Y150760D02*
Y151750D01*
G01X390862Y134627D02*
Y135617D01*
G01X390788Y138760D02*
Y137696D01*
G01Y148681D02*
Y147618D01*
G01X390513D02*
Y148602D01*
G01Y138760D02*
Y137775D01*
G01X390119Y128523D02*
Y123011D01*
G01X389725Y147618D02*
Y148602D01*
G01Y138760D02*
Y137775D01*
G01X389450Y138760D02*
Y137696D01*
G01Y148681D02*
Y147618D01*
G01X389376Y151750D02*
Y150760D01*
G01X389366Y135617D02*
Y134627D01*
G01X389292Y147698D02*
Y152539D01*
G01Y133838D02*
Y138680D01*
G01X389100Y151553D02*
Y152538D01*
G01X389091Y133840D02*
Y134824D01*
G01X389017Y152539D02*
Y133838D01*
G01X388938Y135984D02*
Y129901D01*
G01Y156476D02*
Y150393D01*
G01X388746Y152539D02*
Y151555D01*
G01X388741Y152539D02*
Y151555D01*
G01X388736Y134822D02*
Y133838D01*
G01X388702Y136515D02*
Y132342D01*
G01Y154035D02*
Y149862D01*
G01X387599D02*
Y154035D01*
G01Y132342D02*
Y136515D01*
G01X387565Y134822D02*
Y133838D01*
G01X387560Y134822D02*
Y133838D01*
G01Y152539D02*
Y151555D01*
G01X387363Y135984D02*
Y129901D01*
G01Y156476D02*
Y150393D01*
G01X387284Y133838D02*
Y152539D01*
G01X387206Y134824D02*
Y133840D01*
G01Y152538D02*
Y151553D01*
G01X387009Y151555D02*
Y156396D01*
G01Y129981D02*
Y134822D01*
G01X386969Y128523D02*
Y123011D01*
G01X386930Y150760D02*
Y151750D01*
G01Y134627D02*
Y135617D01*
G01X386851Y130965D02*
Y129901D01*
G01Y156476D02*
Y155412D01*
G01X386576Y130885D02*
Y129901D01*
G01Y156476D02*
Y155492D01*
G01X385788D02*
Y156476D01*
G01Y130885D02*
Y129901D01*
G01X385513Y130965D02*
Y129901D01*
G01Y156476D02*
Y155412D01*
G01X385434Y135617D02*
Y134627D01*
G01Y151750D02*
Y150760D01*
G01X385355Y151555D02*
Y156396D01*
G01Y129981D02*
Y134822D01*
G01X385158Y151553D02*
Y152538D01*
G01Y133840D02*
Y134824D01*
G01X385080Y152539D02*
Y133838D01*
G01X385001Y135984D02*
Y129901D01*
G01Y156476D02*
Y150393D01*
G01X384804Y134822D02*
Y133838D01*
G01Y152539D02*
Y151555D01*
G01X384799Y152539D02*
Y151555D01*
G01X384765Y136515D02*
Y132342D01*
G01Y154035D02*
Y149862D01*
G01X383662D02*
Y154035D01*
G01Y132342D02*
Y136515D01*
G01X383628Y152539D02*
Y151555D01*
G01X383623Y134822D02*
Y133838D01*
G01X383618Y134822D02*
Y133838D01*
G01X383426Y135984D02*
Y129901D01*
G01Y156476D02*
Y150393D01*
G01X383347Y133838D02*
Y152539D01*
G01X383273Y152538D02*
Y151553D01*
G01X383264Y134824D02*
Y133840D01*
G01X383072Y147698D02*
Y152539D01*
G01Y133838D02*
Y138680D01*
G01X382998Y150760D02*
Y151750D01*
G01X382988Y134627D02*
Y135617D01*
G01X382914Y138760D02*
Y137696D01*
G01Y148681D02*
Y147618D01*
G01X382639Y138760D02*
Y137775D01*
G01Y148602D02*
Y147618D01*
G01X381851Y138760D02*
Y137775D01*
G01Y148602D02*
Y147618D01*
G01X381576Y138760D02*
Y137696D01*
G01Y148681D02*
Y147618D01*
G01X381502Y151750D02*
Y150760D01*
G01X381492Y135617D02*
Y134627D01*
G01X381418Y147698D02*
Y152539D01*
G01Y133838D02*
Y138680D01*
G01X381226Y151553D02*
Y152538D01*
G01X381217Y133840D02*
Y134824D01*
G01X381143Y152539D02*
Y133838D01*
G01X381064Y135984D02*
Y129901D01*
G01Y156476D02*
Y150393D01*
G01X380872Y152539D02*
Y151555D01*
G01X380867Y152539D02*
Y151555D01*
G01X380862Y134822D02*
Y133838D01*
G01X380828Y136515D02*
Y132342D01*
G01Y154035D02*
Y149862D01*
G01X379725D02*
Y154035D01*
G01Y132342D02*
Y136515D01*
G01X379691Y134822D02*
Y133838D01*
G01X379686Y134822D02*
Y133838D01*
G01Y152539D02*
Y151555D01*
G01X402413Y151368D02*
X402426Y150393D01*
G01X401447Y135009D02*
X401434Y135984D01*
G01X398480Y151368D02*
X398494Y150393D01*
G01X397506Y135009D02*
X397493Y135984D01*
G01X394539Y151368D02*
X394552Y150393D01*
G01X393573Y135009D02*
X393560Y135984D01*
G01X390606Y151368D02*
X390620Y150393D01*
G01X389632Y135009D02*
X389619Y135984D01*
G01X386665Y151368D02*
X386678Y150393D01*
G01X385699Y135009D02*
X385686Y135984D01*
G01X382732Y151368D02*
X382746Y150393D01*
G01X381758Y135009D02*
X381745Y135984D01*
G01X378791Y151368D02*
X378804Y150393D01*
G01X402941Y135117D02*
X402804Y141024D01*
G01X402799Y140138D02*
X402936Y134231D01*
G01X401061Y146239D02*
X400924Y152147D01*
G01X400920Y151260D02*
X401056Y145353D01*
G01X398999Y135117D02*
X398863Y141024D01*
G01X398858Y140138D02*
X398994Y134231D01*
G01X397128Y146239D02*
X396992Y152147D01*
G01X396987Y151260D02*
X397124Y145353D01*
G01X395066Y135117D02*
X394930Y141024D01*
G01X394925Y140138D02*
X395062Y134231D01*
G01X393187Y146239D02*
X393050Y152147D01*
G01X393046Y151260D02*
X393182Y145353D01*
G01X391125Y135117D02*
X390989Y141024D01*
G01X390984Y140138D02*
X391120Y134231D01*
G01X389254Y146239D02*
X389118Y152147D01*
G01X389113Y151260D02*
X389250Y145353D01*
G01X387192Y135117D02*
X387056Y141024D01*
G01X387051Y140138D02*
X387188Y134231D01*
G01X385313Y146239D02*
X385176Y152147D01*
G01X385172Y151260D02*
X385308Y145353D01*
G01X383251Y135117D02*
X383115Y141024D01*
G01X383110Y140138D02*
X383246Y134231D01*
G01X381380Y146239D02*
X381244Y152147D01*
G01X381239Y151260D02*
X381376Y145353D01*
G01X379318Y135117D02*
X379182Y141024D01*
G01X379177Y140138D02*
X379314Y134231D01*
G01X401135Y140340D02*
X401084Y141327D01*
G01X401082Y140365D02*
X401133Y139379D01*
G01X398846Y146012D02*
X398795Y146999D01*
G01X398793Y146037D02*
X398843Y145050D01*
G01X397193Y140340D02*
X397143Y141327D01*
G01X397140Y140365D02*
X397191Y139379D01*
G01X394904Y146012D02*
X394854Y146999D01*
G01X394851Y146037D02*
X394902Y145050D01*
G01X393261Y140340D02*
X393210Y141327D01*
G01X393208Y140365D02*
X393258Y139379D01*
G01X390972Y146012D02*
X390921Y146999D01*
G01X390919Y146037D02*
X390969Y145050D01*
G01X389319Y140340D02*
X389269Y141327D01*
G01X389266Y140365D02*
X389317Y139379D01*
G01X387030Y146012D02*
X386980Y146999D01*
G01X386977Y146037D02*
X387028Y145050D01*
G01X385387Y140340D02*
X385336Y141327D01*
G01X385334Y140365D02*
X385384Y139379D01*
G01X383098Y146012D02*
X383047Y146999D01*
G01X383045Y146037D02*
X383095Y145050D01*
G01X381445Y140340D02*
X381395Y141327D01*
G01X381392Y140365D02*
X381443Y139379D01*
G01X379156Y146012D02*
X379106Y146999D01*
G01X379103Y146037D02*
X379154Y145050D01*
G01X377513Y140340D02*
X377462Y141327D01*
G01X377460Y140365D02*
X377510Y139379D01*
G01X365973Y150441D02*
X365983Y150393D01*
G01X367021Y135937D02*
X367011Y135984D01*
G01X362032Y150441D02*
X362041Y150393D01*
G01X363088Y135937D02*
X363079Y135984D01*
G01X358099Y150441D02*
X358109Y150393D01*
G01X359147Y135937D02*
X359137Y135984D01*
G01X354158Y150441D02*
X354167Y150393D01*
G01X355214Y135937D02*
X355205Y135984D01*
G01X350225Y150441D02*
X350235Y150393D01*
G01X351273Y135937D02*
X351263Y135984D01*
G01X347340Y135937D02*
X347331Y135984D01*
G01X355214Y135937D02*
X355436Y135615D01*
G01X355423Y134640D02*
X355169Y135009D01*
G01X351273Y135937D02*
X351494Y135615D01*
G01X351481Y134640D02*
X351227Y135009D01*
G01X347340Y135937D02*
X347562Y135615D01*
G01X347548Y134640D02*
X347295Y135009D01*
G01X351505Y136570D02*
X349984D01*
G01X355447D02*
X353925D01*
G01X359379D02*
X357858D01*
G01X363321D02*
X361799D01*
G01X367253D02*
X365732D01*
G01X371195D02*
X369673D01*
G01X375127D02*
X373606D01*
G01X379069D02*
X377547D01*
G01X383001D02*
X381480D01*
G01X386943D02*
X385421D01*
G01X390875D02*
X389354D01*
G01X394817D02*
X393295D01*
G01X398749D02*
X397228D01*
G01X402691D02*
X401169D01*
G01X406623D02*
X405102D01*
G01X410565D02*
X409043D01*
G01X414497D02*
X412976D01*
G01X418439D02*
X416917D01*
G01X422371D02*
X420850D01*
G01X426313D02*
X424791D01*
G01X351516Y136551D02*
X349973D01*
G01X355458D02*
X353914D01*
G01X359390D02*
X357847D01*
G01X363332D02*
X361788D01*
G01X367264D02*
X365721D01*
G01X371206D02*
X369662D01*
G01X375138D02*
X373595D01*
G01X379080D02*
X377536D01*
G01X383012D02*
X381469D01*
G01X386954D02*
X385410D01*
G01X390886D02*
X389343D01*
G01X394828D02*
X393284D01*
G01X398760D02*
X397217D01*
G01X402702D02*
X401158D01*
G01X406634D02*
X405091D01*
G01X410576D02*
X409032D01*
G01X414508D02*
X412965D01*
G01X418450D02*
X416906D01*
G01X422382D02*
X420839D01*
G01X426324D02*
X424780D01*
G01X348229Y136515D02*
X347914D01*
G01X349647D02*
X349332D01*
G01X353584D02*
X353269D01*
G01X352166D02*
X351851D01*
G01X356103D02*
X355788D01*
G01X357521D02*
X357206D01*
G01X360040D02*
X359725D01*
G01X361458D02*
X361143D01*
G01X363977D02*
X363662D01*
G01X365395D02*
X365080D01*
G01X367914D02*
X367599D01*
G01X369332D02*
X369017D01*
G01X371851D02*
X371536D01*
G01X373269D02*
X372954D01*
G01X375788D02*
X375473D01*
G01X377206D02*
X376891D01*
G01X379725D02*
X379410D01*
G01X381143D02*
X380828D01*
G01X385080D02*
X384765D01*
G01X383662D02*
X383347D01*
G01X387599D02*
X387284D01*
G01X389017D02*
X388702D01*
G01X391536D02*
X391221D01*
G01X392954D02*
X392639D01*
G01X395473D02*
X395158D01*
G01X396891D02*
X396576D01*
G01X399410D02*
X399095D01*
G01X400828D02*
X400513D01*
G01X403347D02*
X403032D01*
G01X404765D02*
X404450D01*
G01X407284D02*
X406969D01*
G01X408702D02*
X408387D01*
G01X411221D02*
X410906D01*
G01X412639D02*
X412324D01*
G01X415158D02*
X414843D01*
G01X416576D02*
X416261D01*
G01X419095D02*
X418780D01*
G01X420513D02*
X420198D01*
G01X423032D02*
X422717D01*
G01X424450D02*
X424135D01*
G01X426969D02*
X426655D01*
G01X351930Y135984D02*
X349568D01*
G01X355867D02*
X353505D01*
G01X359804D02*
X357442D01*
G01X363741D02*
X361379D01*
G01X367678D02*
X365316D01*
G01X371615D02*
X369253D01*
G01X375552D02*
X373190D01*
G01X379489D02*
X377127D01*
G01X383426D02*
X381064D01*
G01X387363D02*
X385001D01*
G01X391300D02*
X388938D01*
G01X395237D02*
X392875D01*
G01X399174D02*
X396812D01*
G01X403111D02*
X400749D01*
G01X407048D02*
X404686D01*
G01X410985D02*
X408623D01*
G01X414922D02*
X412560D01*
G01X418859D02*
X416497D01*
G01X422796D02*
X420434D01*
G01X426733D02*
X424371D01*
G01X351273Y135937D02*
X350216D01*
G01X355214D02*
X354158D01*
G01X359147D02*
X358090D01*
G01X363088D02*
X362032D01*
G01X367021D02*
X365964D01*
G01X370962D02*
X369906D01*
G01X374895D02*
X373838D01*
G01X378836D02*
X377780D01*
G01X382769D02*
X381712D01*
G01X386710D02*
X385654D01*
G01X390643D02*
X389586D01*
G01X394584D02*
X393528D01*
G01X398517D02*
X397460D01*
G01X402458D02*
X401402D01*
G01X406391D02*
X405334D01*
G01X410332D02*
X409276D01*
G01X414265D02*
X413208D01*
G01X418206D02*
X417150D01*
G01X422139D02*
X421082D01*
G01X426080D02*
X425024D01*
G01X424804Y135615D02*
X426300D01*
G01X420862D02*
X422359D01*
G01X416930D02*
X418426D01*
G01X412988D02*
X414485D01*
G01X409056D02*
X410552D01*
G01X405114D02*
X406611D01*
G01X401182D02*
X402678D01*
G01X397240D02*
X398737D01*
G01X393308D02*
X394804D01*
G01X389366D02*
X390863D01*
G01X385434D02*
X386930D01*
G01X381492D02*
X382989D01*
G01X377560D02*
X379056D01*
G01X373618D02*
X375115D01*
G01X369686D02*
X371182D01*
G01X365744D02*
X367241D01*
G01X361812D02*
X363308D01*
G01X357870D02*
X359367D01*
G01X353938D02*
X355434D01*
G01X349996D02*
X351493D01*
G01X424802Y135605D02*
X426302D01*
G01X420861D02*
X422360D01*
G01X416928D02*
X418428D01*
G01X412987D02*
X414486D01*
G01X409054D02*
X410554D01*
G01X405113D02*
X406612D01*
G01X401180D02*
X402680D01*
G01X397239D02*
X398738D01*
G01X393306D02*
X394806D01*
G01X389365D02*
X390864D01*
G01X385432D02*
X386932D01*
G01X381491D02*
X382990D01*
G01X377558D02*
X379058D01*
G01X373617D02*
X375116D01*
G01X369684D02*
X371184D01*
G01X365743D02*
X367242D01*
G01X361810D02*
X363310D01*
G01X357869D02*
X359368D01*
G01X353936D02*
X355436D01*
G01X349995D02*
X351494D01*
G01X351576Y135413D02*
X349922D01*
G01X359450D02*
X357796D01*
G01X367324D02*
X365670D01*
G01X375198D02*
X373544D01*
G01X383072D02*
X381418D01*
G01X390946D02*
X389292D01*
G01X398820D02*
X397166D01*
G01X406694D02*
X405040D01*
G01X414568D02*
X412914D01*
G01X422442D02*
X420788D01*
G01X424542Y135117D02*
X426563D01*
G01X420600D02*
X422621D01*
G01X416668D02*
X418689D01*
G01X412726D02*
X414747D01*
G01X408794D02*
X410815D01*
G01X404852D02*
X406873D01*
G01X400920D02*
X402941D01*
G01X396978D02*
X398999D01*
G01X393046D02*
X395066D01*
G01X389104D02*
X391125D01*
G01X385172D02*
X387192D01*
G01X381230D02*
X383251D01*
G01X377298D02*
X379318D01*
G01X373356D02*
X375377D01*
G01X369424D02*
X371444D01*
G01X365482D02*
X367503D01*
G01X361550D02*
X363570D01*
G01X357608D02*
X359629D01*
G01X353676D02*
X355696D01*
G01X349734D02*
X351755D01*
G01X426655Y135019D02*
X426969D01*
G01X422717D02*
X423032D01*
G01X418780D02*
X419095D01*
G01X414843D02*
X415158D01*
G01X410906D02*
X411221D01*
G01X406969D02*
X407284D01*
G01X399095D02*
X399410D01*
G01X391221D02*
X391536D01*
G01X387284D02*
X387599D01*
G01X383347D02*
X383662D01*
G01X379410D02*
X379725D01*
G01X375473D02*
X375788D01*
G01X371536D02*
X371851D01*
G01X367599D02*
X367914D01*
G01X363662D02*
X363977D01*
G01X359725D02*
X360040D01*
G01X355788D02*
X356103D01*
G01X351851D02*
X352166D01*
G01X347914D02*
X348229D01*
G01X349647D02*
X349332D01*
G01X353584D02*
X353269D01*
G01X357521D02*
X357206D01*
G01X361458D02*
X361143D01*
G01X365395D02*
X365080D01*
G01X369332D02*
X369017D01*
G01X373269D02*
X372954D01*
G01X377206D02*
X376891D01*
G01X381143D02*
X380828D01*
G01X385080D02*
X384765D01*
G01X389017D02*
X388702D01*
G01X392954D02*
X392639D01*
G01X395473D02*
X395158D01*
G01X396891D02*
X396576D01*
G01X400828D02*
X400513D01*
G01X403347D02*
X403032D01*
G01X404765D02*
X404450D01*
G01X408702D02*
X408387D01*
G01X412639D02*
X412324D01*
G01X416576D02*
X416261D01*
G01X420513D02*
X420198D01*
G01X424450D02*
X424135D01*
G01X425069Y135009D02*
X426035D01*
G01X421128D02*
X422093D01*
G01X417195D02*
X418161D01*
G01X413254D02*
X414219D01*
G01X409321D02*
X410287D01*
G01X405380D02*
X406345D01*
G01X401447D02*
X402413D01*
G01X397506D02*
X398471D01*
G01X393573D02*
X394539D01*
G01X389632D02*
X390597D01*
G01X385699D02*
X386665D01*
G01X381758D02*
X382723D01*
G01X377825D02*
X378791D01*
G01X373884D02*
X374849D01*
G01X369951D02*
X370917D01*
G01X366010D02*
X366975D01*
G01X362077D02*
X363043D01*
G01X358136D02*
X359101D01*
G01X354203D02*
X355169D01*
G01X350262D02*
X351227D01*
G01X420788Y134921D02*
X422442D01*
G01X412914D02*
X414568D01*
G01X405040D02*
X406694D01*
G01X397166D02*
X398820D01*
G01X389292D02*
X390946D01*
G01X381418D02*
X383072D01*
G01X373544D02*
X375198D01*
G01X365670D02*
X367324D01*
G01X357796D02*
X359450D01*
G01X349922D02*
X351576D01*
G01X424135Y134822D02*
X426969D01*
G01X420198D02*
X423032D01*
G01X416261D02*
X419095D01*
G01X412324D02*
X415158D01*
G01X408387D02*
X411221D01*
G01X404450D02*
X407284D01*
G01X400513D02*
X403347D01*
G01X396576D02*
X399410D01*
G01X392639D02*
X395473D01*
G01X388702D02*
X391536D01*
G01X384765D02*
X387599D01*
G01X380828D02*
X383662D01*
G01X376891D02*
X379725D01*
G01X372954D02*
X375788D01*
G01X369017D02*
X371851D01*
G01X365080D02*
X367914D01*
G01X361143D02*
X363977D01*
G01X357206D02*
X360040D01*
G01X353269D02*
X356103D01*
G01X349332D02*
X352166D01*
G01X426379Y134665D02*
X426969D01*
G01X424135D02*
X424725D01*
G01X422442D02*
X423032D01*
G01X420198D02*
X420788D01*
G01X418505D02*
X419095D01*
G01X416261D02*
X416851D01*
G01X414568D02*
X415158D01*
G01X412324D02*
X412914D01*
G01X410631D02*
X411221D01*
G01X408387D02*
X408977D01*
G01X406694D02*
X407284D01*
G01X404450D02*
X405040D01*
G01X402757D02*
X403347D01*
G01X400513D02*
X401103D01*
G01X398820D02*
X399410D01*
G01X396576D02*
X397166D01*
G01X394883D02*
X395473D01*
G01X392639D02*
X393229D01*
G01X390946D02*
X391536D01*
G01X388702D02*
X389292D01*
G01X387009D02*
X387599D01*
G01X384765D02*
X385355D01*
G01X383072D02*
X383662D01*
G01X380828D02*
X381418D01*
G01X379135D02*
X379725D01*
G01X376891D02*
X377481D01*
G01X375198D02*
X375788D01*
G01X372954D02*
X373544D01*
G01X371261D02*
X371851D01*
G01X369017D02*
X369607D01*
G01X367324D02*
X367914D01*
G01X365080D02*
X365670D01*
G01X363387D02*
X363977D01*
G01X361143D02*
X361733D01*
G01X359450D02*
X360040D01*
G01X357206D02*
X357796D01*
G01X355513D02*
X356103D01*
G01X353269D02*
X353859D01*
G01X351576D02*
X352166D01*
G01X349332D02*
X349922D01*
G01X347639D02*
X348229D01*
G01X351481Y134640D02*
X350008D01*
G01X355423D02*
X353950D01*
G01X359355D02*
X357882D01*
G01X363297D02*
X361824D01*
G01X367229D02*
X365756D01*
G01X371171D02*
X369698D01*
G01X375103D02*
X373630D01*
G01X379045D02*
X377572D01*
G01X382977D02*
X381504D01*
G01X386919D02*
X385446D01*
G01X390851D02*
X389378D01*
G01X394793D02*
X393320D01*
G01X398725D02*
X397252D01*
G01X402667D02*
X401194D01*
G01X406599D02*
X405126D01*
G01X410541D02*
X409068D01*
G01X414473D02*
X413000D01*
G01X418415D02*
X416942D01*
G01X422347D02*
X420874D01*
G01X426289D02*
X424816D01*
G01X424802Y134621D02*
X426302D01*
G01X420861D02*
X422360D01*
G01X416928D02*
X418428D01*
G01X412987D02*
X414486D01*
G01X409054D02*
X410554D01*
G01X405113D02*
X406612D01*
G01X401180D02*
X402680D01*
G01X397239D02*
X398738D01*
G01X393306D02*
X394806D01*
G01X389365D02*
X390864D01*
G01X385432D02*
X386932D01*
G01X381491D02*
X382990D01*
G01X377558D02*
X379058D01*
G01X373617D02*
X375116D01*
G01X369684D02*
X371184D01*
G01X365743D02*
X367242D01*
G01X361810D02*
X363310D01*
G01X357869D02*
X359368D01*
G01X353936D02*
X355436D01*
G01X349995D02*
X351494D01*
G01X351750Y134231D02*
X349739D01*
G01X355692D02*
X353680D01*
G01X359624D02*
X357613D01*
G01X363566D02*
X361554D01*
G01X367498D02*
X365487D01*
G01X371440D02*
X369428D01*
G01X375372D02*
X373361D01*
G01X379314D02*
X377302D01*
G01X383246D02*
X381235D01*
G01X387188D02*
X385176D01*
G01X391120D02*
X389109D01*
G01X395062D02*
X393050D01*
G01X398994D02*
X396983D01*
G01X402936D02*
X400924D01*
G01X406868D02*
X404857D01*
G01X410810D02*
X408798D01*
G01X414742D02*
X412731D01*
G01X418684D02*
X416673D01*
G01X422616D02*
X420605D01*
G01X426558D02*
X424547D01*
G01X348229Y133996D02*
X347639D01*
G01X349922D02*
X349332D01*
G01X352166D02*
X351576D01*
G01X353859D02*
X353269D01*
G01X356103D02*
X355513D01*
G01X357796D02*
X357206D01*
G01X360040D02*
X359450D01*
G01X361733D02*
X361143D01*
G01X363977D02*
X363387D01*
G01X365670D02*
X365080D01*
G01X367914D02*
X367324D01*
G01X369607D02*
X369017D01*
G01X371851D02*
X371261D01*
G01X373544D02*
X372954D01*
G01X375788D02*
X375198D01*
G01X377481D02*
X376891D01*
G01X379725D02*
X379135D01*
G01X381418D02*
X380828D01*
G01X383662D02*
X383072D01*
G01X385355D02*
X384765D01*
G01X387599D02*
X387009D01*
G01X389292D02*
X388702D01*
G01X391536D02*
X390946D01*
G01X393229D02*
X392639D01*
G01X395473D02*
X394883D01*
G01X397166D02*
X396576D01*
G01X399410D02*
X398820D01*
G01X401103D02*
X400513D01*
G01X403347D02*
X402757D01*
G01X405040D02*
X404450D01*
G01X407284D02*
X406694D01*
G01X408977D02*
X408387D01*
G01X411221D02*
X410631D01*
G01X412914D02*
X412324D01*
G01X415158D02*
X414568D01*
G01X416851D02*
X416261D01*
G01X419095D02*
X418505D01*
G01X420788D02*
X420198D01*
G01X423032D02*
X422442D01*
G01X424725D02*
X424135D01*
G01X426969D02*
X426379D01*
G01X352166Y133838D02*
X349332D01*
G01X356103D02*
X353269D01*
G01X360040D02*
X357206D01*
G01X363977D02*
X361143D01*
G01X367914D02*
X365080D01*
G01X371851D02*
X369017D01*
G01X375788D02*
X372954D01*
G01X379725D02*
X376891D01*
G01X383662D02*
X380828D01*
G01X387599D02*
X384765D01*
G01X391536D02*
X388702D01*
G01X395473D02*
X392639D01*
G01X399410D02*
X396576D01*
G01X403347D02*
X400513D01*
G01X407284D02*
X404450D01*
G01X411221D02*
X408387D01*
G01X415158D02*
X412324D01*
G01X419095D02*
X416261D01*
G01X423032D02*
X420198D01*
G01X426969D02*
X424135D01*
G01X355513Y133740D02*
X353859D01*
G01X363387D02*
X361733D01*
G01X371261D02*
X369607D01*
G01X379135D02*
X377481D01*
G01X387009D02*
X385355D01*
G01X394883D02*
X393229D01*
G01X402757D02*
X401103D01*
G01X410631D02*
X408977D01*
G01X418505D02*
X416851D01*
G01X426379D02*
X424725D01*
G01Y133248D02*
X426379D01*
G01X416851D02*
X418505D01*
G01X408977D02*
X410631D01*
G01X401103D02*
X402757D01*
G01X393229D02*
X394883D01*
G01X385355D02*
X387009D01*
G01X377481D02*
X379135D01*
G01X369607D02*
X371261D01*
G01X361733D02*
X363387D01*
G01X353859D02*
X355513D01*
G01X424135Y132342D02*
X426969D01*
G01X420198D02*
X423032D01*
G01X416261D02*
X419095D01*
G01X412324D02*
X415158D01*
G01X408387D02*
X411221D01*
G01X404450D02*
X407284D01*
G01X400513D02*
X403347D01*
G01X396576D02*
X399410D01*
G01X392639D02*
X395473D01*
G01X388702D02*
X391536D01*
G01X384765D02*
X387599D01*
G01X380828D02*
X383662D01*
G01X376891D02*
X379725D01*
G01X372954D02*
X375788D01*
G01X369017D02*
X371851D01*
G01X365080D02*
X367914D01*
G01X361143D02*
X363977D01*
G01X357206D02*
X360040D01*
G01X353269D02*
X356103D01*
G01X349332D02*
X352166D01*
G01X424725Y131476D02*
X426379D01*
G01X416851D02*
X418505D01*
G01X408977D02*
X410631D01*
G01X401103D02*
X402757D01*
G01X393229D02*
X394883D01*
G01X385355D02*
X387009D01*
G01X377481D02*
X379135D01*
G01X369607D02*
X371261D01*
G01X361733D02*
X363387D01*
G01X353859D02*
X355513D01*
G01X400749Y131082D02*
X403111D01*
G01X396812D02*
X399174D01*
G01X392875D02*
X395237D01*
G01X388938D02*
X391300D01*
G01X351930D02*
X349568D01*
G01X355867D02*
X353505D01*
G01X359804D02*
X357442D01*
G01X363741D02*
X361379D01*
G01X367678D02*
X365316D01*
G01X371615D02*
X369253D01*
G01X375552D02*
X373190D01*
G01X379489D02*
X377127D01*
G01X383426D02*
X381064D01*
G01X387363D02*
X385001D01*
G01X407048D02*
X404686D01*
G01X410985D02*
X408623D01*
G01X414922D02*
X412560D01*
G01X418859D02*
X416497D01*
G01X422796D02*
X420434D01*
G01X426733D02*
X424371D01*
G01X355513Y130984D02*
X353859D01*
G01X363387D02*
X361733D01*
G01X371261D02*
X369607D01*
G01X379135D02*
X377481D01*
G01X387009D02*
X385355D01*
G01X394883D02*
X393229D01*
G01X402757D02*
X401103D01*
G01X410631D02*
X408977D01*
G01X418505D02*
X416851D01*
G01X426379D02*
X424725D01*
G01X355355Y130885D02*
X354017D01*
G01X363229D02*
X361891D01*
G01X371103D02*
X369765D01*
G01X378977D02*
X377639D01*
G01X386851D02*
X385513D01*
G01X394725D02*
X393387D01*
G01X402599D02*
X401261D01*
G01X410473D02*
X409135D01*
G01X418347D02*
X417009D01*
G01X426221D02*
X424883D01*
G01X424371Y129901D02*
X426733D01*
G01X420434D02*
X422796D01*
G01X416497D02*
X418859D01*
G01X412560D02*
X414922D01*
G01X408623D02*
X410985D01*
G01X404686D02*
X407048D01*
G01X400749D02*
X403111D01*
G01X396812D02*
X399174D01*
G01X392875D02*
X395237D01*
G01X388938D02*
X391300D01*
G01X385001D02*
X387363D01*
G01X381064D02*
X383426D01*
G01X377127D02*
X379489D01*
G01X373190D02*
X375552D01*
G01X369253D02*
X371615D01*
G01X365316D02*
X367678D01*
G01X361379D02*
X363741D01*
G01X357442D02*
X359804D01*
G01X353505D02*
X355867D01*
G01X349568D02*
X351930D01*
G01X417678Y123011D02*
X437363D01*
G01X394056D02*
X413741D01*
G01X370434D02*
X390119D01*
G01X424816Y134640D02*
X425069Y135009D01*
G01X424803Y135615D02*
X425024Y135937D01*
G01X420874Y134640D02*
X421128Y135009D01*
G01X420861Y135615D02*
X421082Y135937D01*
G01X416942Y134640D02*
X417195Y135009D01*
G01X416928Y135615D02*
X417150Y135937D01*
G01X426302Y150762D02*
X426080Y150441D01*
G01X426289Y151737D02*
X426035Y151368D01*
G01X413000Y134640D02*
X413254Y135009D01*
G01X412987Y135615D02*
X413208Y135937D01*
G01X422369Y150762D02*
X422148Y150441D01*
G01X422356Y151737D02*
X422102Y151368D01*
G01X409068Y134640D02*
X409321Y135009D01*
G01X409054Y135615D02*
X409276Y135937D01*
G01X418428Y150762D02*
X418206Y150441D01*
G01X418415Y151737D02*
X418161Y151368D01*
G01X405126Y134640D02*
X405380Y135009D01*
G01X405113Y135615D02*
X405334Y135937D01*
G01X414495Y150762D02*
X414274Y150441D01*
G01X414482Y151737D02*
X414228Y151368D01*
G01X401194Y134640D02*
X401447Y135009D01*
G01X401402Y135937D02*
X401182Y135617D01*
G01X410554Y150762D02*
X410332Y150441D01*
G01X410541Y151737D02*
X410287Y151368D01*
G01X397252Y134640D02*
X397506Y135009D01*
G01X397239Y135615D02*
X397460Y135937D01*
G01X406621Y150762D02*
X406400Y150441D01*
G01X389596Y135984D02*
X389586Y135937D01*
G01X390642Y150393D02*
X390652Y150441D01*
G01X385663Y135984D02*
X385654Y135937D01*
G01X386701Y150393D02*
X386710Y150441D01*
G01X381722Y135984D02*
X381712Y135937D01*
G01X382768Y150393D02*
X382778Y150441D01*
G01X377789Y135984D02*
X377780Y135937D01*
G01X378827Y150393D02*
X378836Y150441D01*
G01X373848Y135984D02*
X373838Y135937D01*
G01X374894Y150393D02*
X374904Y150441D01*
G01X369915Y135984D02*
X369906Y135937D01*
G01X370953Y150393D02*
X370962Y150441D01*
G01X381404Y145050D02*
X381454Y146037D01*
G01X381452Y146999D02*
X381402Y146012D01*
G01X379106Y139379D02*
X379156Y140365D01*
G01X379154Y141327D02*
X379103Y140340D01*
G01X377462Y145050D02*
X377513Y146037D01*
G01X377510Y146999D02*
X377460Y146012D01*
G01X375164Y139379D02*
X375214Y140365D01*
G01X375212Y141327D02*
X375162Y140340D01*
G01X373530Y145050D02*
X373580Y146037D01*
G01X373578Y146999D02*
X373528Y146012D01*
G01X371232Y139379D02*
X371282Y140365D01*
G01X371280Y141327D02*
X371229Y140340D01*
G01X369588Y145050D02*
X369639Y146037D01*
G01X369636Y146999D02*
X369586Y146012D01*
G01X367290Y139379D02*
X367340Y140365D01*
G01X367338Y141327D02*
X367288Y140340D01*
G01X365656Y145050D02*
X365706Y146037D01*
G01X365704Y146999D02*
X365654Y146012D01*
G01X363358Y139379D02*
X363408Y140365D01*
G01X363406Y141327D02*
X363355Y140340D01*
G01X361714Y145050D02*
X361765Y146037D01*
G01X361762Y146999D02*
X361712Y146012D01*
G01X359416Y139379D02*
X359466Y140365D01*
G01X359464Y141327D02*
X359414Y140340D01*
G01X379182Y145353D02*
X379318Y151260D01*
G01X379314Y152147D02*
X379177Y146239D01*
G01X377302Y134231D02*
X377439Y140138D01*
G01X377434Y141024D02*
X377298Y135117D01*
G01X375250Y145353D02*
X375386Y151260D01*
G01X375381Y152147D02*
X375245Y146239D01*
G01X373361Y134231D02*
X373497Y140138D01*
G01X373492Y141024D02*
X373356Y135117D01*
G01X371308Y145353D02*
X371444Y151260D01*
G01X371440Y152147D02*
X371303Y146239D01*
G01X369428Y134231D02*
X369565Y140138D01*
G01X369560Y141024D02*
X369424Y135117D01*
G01X367376Y145353D02*
X367512Y151260D01*
G01X367507Y152147D02*
X367371Y146239D01*
G01X365487Y134231D02*
X365623Y140138D01*
G01X365618Y141024D02*
X365482Y135117D01*
G01X363434Y145353D02*
X363570Y151260D01*
G01X363566Y152147D02*
X363429Y146239D01*
G01X361554Y134231D02*
X361691Y140138D01*
G01X361686Y141024D02*
X361550Y135117D01*
G01X359502Y145353D02*
X359638Y151260D01*
G01X359633Y152147D02*
X359497Y146239D01*
G01X357613Y134231D02*
X357749Y140138D01*
G01X357744Y141024D02*
X357608Y135117D01*
G01X378804Y135984D02*
X378791Y135009D01*
G01X377812Y150393D02*
X377825Y151368D01*
G01X374862Y135984D02*
X374849Y135009D01*
G01X373880Y150393D02*
X373893Y151368D01*
G01X370930Y135984D02*
X370917Y135009D01*
G01X369938Y150393D02*
X369951Y151368D01*
G01X366988Y135984D02*
X366975Y135009D01*
G01X366006Y150393D02*
X366019Y151368D01*
G01X363056Y135984D02*
X363043Y135009D01*
G01X362064Y150393D02*
X362077Y151368D01*
G01X359114Y135984D02*
X359101Y135009D01*
G01X358132Y150393D02*
X358145Y151368D01*
G01X379489Y135984D02*
Y129901D01*
G01Y156476D02*
Y150393D01*
G01X379410Y133838D02*
Y152539D01*
G01X379332Y134824D02*
Y133840D01*
G01Y152538D02*
Y151553D01*
G01X379135Y151555D02*
Y156396D01*
G01Y129981D02*
Y134822D01*
G01X379056Y150760D02*
Y151750D01*
G01Y134627D02*
Y135617D01*
G01X378977Y130965D02*
Y129901D01*
G01Y156476D02*
Y155412D01*
G01X378702Y130885D02*
Y129901D01*
G01Y156476D02*
Y155492D01*
G01X377914D02*
Y156476D01*
G01Y130885D02*
Y129901D01*
G01X377639Y130965D02*
Y129901D01*
G01Y156476D02*
Y155412D01*
G01X377560Y135617D02*
Y134627D01*
G01Y151750D02*
Y150760D01*
G01X377481Y151555D02*
Y156396D01*
G01Y129981D02*
Y134822D01*
G01X377284Y151553D02*
Y152538D01*
G01Y133840D02*
Y134824D01*
G01X377206Y152539D02*
Y133838D01*
G01X377127Y135984D02*
Y129901D01*
G01Y156476D02*
Y150393D01*
G01X376930Y134822D02*
Y133838D01*
G01Y152539D02*
Y151555D01*
G01X376925Y152539D02*
Y151555D01*
G01X376891Y136515D02*
Y132342D01*
G01Y154035D02*
Y149862D01*
G01X375788D02*
Y154035D01*
G01Y132342D02*
Y136515D01*
G01X375754Y152539D02*
Y151555D01*
G01X375749Y134822D02*
Y133838D01*
G01X375744Y134822D02*
Y133838D01*
G01X375552Y135984D02*
Y129901D01*
G01Y156476D02*
Y150393D01*
G01X375473Y133838D02*
Y152539D01*
G01X375399Y152538D02*
Y151553D01*
G01X375390Y134824D02*
Y133840D01*
G01X375198Y147698D02*
Y152539D01*
G01Y133838D02*
Y138680D01*
G01X375124Y150760D02*
Y151750D01*
G01X375114Y134627D02*
Y135617D01*
G01X375040Y138760D02*
Y137696D01*
G01Y148681D02*
Y147618D01*
G01X374765D02*
Y148602D01*
G01Y138760D02*
Y137775D01*
G01X373977Y147618D02*
Y148602D01*
G01Y137775D02*
Y138760D01*
G01X373702D02*
Y137696D01*
G01Y148681D02*
Y147618D01*
G01X373628Y151750D02*
Y150760D01*
G01X373618Y135617D02*
Y134627D01*
G01X373584Y128523D02*
Y123011D01*
G01X373544Y147698D02*
Y152539D01*
G01Y133838D02*
Y138680D01*
G01X373352Y151553D02*
Y152538D01*
G01X373343Y133840D02*
Y134824D01*
G01X373269Y152539D02*
Y133838D01*
G01X373190Y135984D02*
Y129901D01*
G01Y156476D02*
Y150393D01*
G01X372998Y152539D02*
Y151555D01*
G01X372993Y152539D02*
Y151555D01*
G01X372988Y134822D02*
Y133838D01*
G01X372954Y136515D02*
Y132342D01*
G01Y154035D02*
Y149862D01*
G01X371851D02*
Y154035D01*
G01Y132342D02*
Y136515D01*
G01X371817Y134822D02*
Y133838D01*
G01X371812Y134822D02*
Y133838D01*
G01Y152539D02*
Y151555D01*
G01X371615Y135984D02*
Y129901D01*
G01Y156476D02*
Y150393D01*
G01X371536Y133838D02*
Y152539D01*
G01X371458Y134824D02*
Y133840D01*
G01Y152538D02*
Y151553D01*
G01X371261Y151555D02*
Y156396D01*
G01Y129981D02*
Y134822D01*
G01X371182Y150760D02*
Y151750D01*
G01Y134627D02*
Y135617D01*
G01X371103Y130965D02*
Y129901D01*
G01Y156476D02*
Y155412D01*
G01X370828Y130885D02*
Y129901D01*
G01Y156476D02*
Y155492D01*
G01X370434Y128523D02*
Y123011D01*
G01X370040Y155492D02*
Y156476D01*
G01Y130885D02*
Y129901D01*
G01X369765Y130965D02*
Y129901D01*
G01Y156476D02*
Y155412D01*
G01X369686Y135617D02*
Y134627D01*
G01Y151750D02*
Y150760D01*
G01X369607Y151555D02*
Y156396D01*
G01Y129981D02*
Y134822D01*
G01X369410Y151553D02*
Y152538D01*
G01Y133840D02*
Y134824D01*
G01X369332Y152539D02*
Y133838D01*
G01X369253Y135984D02*
Y129901D01*
G01Y156476D02*
Y150393D01*
G01X369056Y134822D02*
Y133838D01*
G01Y152539D02*
Y151555D01*
G01X369051Y152539D02*
Y151555D01*
G01X369017Y136515D02*
Y132342D01*
G01Y154035D02*
Y149862D01*
G01X367914D02*
Y154035D01*
G01Y132342D02*
Y136515D01*
G01X367880Y152539D02*
Y151555D01*
G01X367875Y134822D02*
Y133838D01*
G01X367870Y134822D02*
Y133838D01*
G01X367678Y135984D02*
Y129901D01*
G01Y156476D02*
Y150393D01*
G01X367599Y133838D02*
Y152539D01*
G01X367525Y152538D02*
Y151553D01*
G01X367516Y134824D02*
Y133840D01*
G01X367324Y147698D02*
Y152539D01*
G01Y133838D02*
Y138680D01*
G01X367250Y150760D02*
Y151750D01*
G01X367240Y134627D02*
Y135617D01*
G01X367166Y138760D02*
Y137696D01*
G01Y148681D02*
Y147618D01*
G01X366891D02*
Y148602D01*
G01Y138760D02*
Y137775D01*
G01X366497Y128523D02*
Y123011D01*
G01X366103Y147618D02*
Y148602D01*
G01Y137775D02*
Y138760D01*
G01X365828D02*
Y137696D01*
G01Y148681D02*
Y147618D01*
G01X365754Y151750D02*
Y150760D01*
G01X365744Y135617D02*
Y134627D01*
G01X365670Y147698D02*
Y152539D01*
G01Y133838D02*
Y138680D01*
G01X365478Y151553D02*
Y152538D01*
G01X365469Y133840D02*
Y134824D01*
G01X365395Y152539D02*
Y133838D01*
G01X365316Y135984D02*
Y129901D01*
G01Y156476D02*
Y150393D01*
G01X365124Y152539D02*
Y151555D01*
G01X365119Y152539D02*
Y151555D01*
G01X365114Y134822D02*
Y133838D01*
G01X365080Y136515D02*
Y132342D01*
G01Y154035D02*
Y149862D01*
G01X363977D02*
Y154035D01*
G01Y132342D02*
Y136515D01*
G01X363943Y134822D02*
Y133838D01*
G01X363938Y134822D02*
Y133838D01*
G01Y152539D02*
Y151555D01*
G01X363741Y135984D02*
Y129901D01*
G01Y156476D02*
Y150393D01*
G01X363662Y133838D02*
Y152539D01*
G01X363584Y134824D02*
Y133840D01*
G01Y152538D02*
Y151553D01*
G01X363387Y151555D02*
Y156396D01*
G01Y129981D02*
Y134822D01*
G01X363347Y128523D02*
Y123011D01*
G01X363308Y150760D02*
Y151750D01*
G01Y134627D02*
Y135617D01*
G01X363229Y130965D02*
Y129901D01*
G01Y156476D02*
Y155412D01*
G01X362954Y130885D02*
Y129901D01*
G01Y156476D02*
Y155492D01*
G01X362166D02*
Y156476D01*
G01Y130885D02*
Y129901D01*
G01X361891Y130965D02*
Y129901D01*
G01Y156476D02*
Y155412D01*
G01X361812Y135617D02*
Y134627D01*
G01Y151750D02*
Y150760D01*
G01X361733Y151555D02*
Y156396D01*
G01Y129981D02*
Y134822D01*
G01X361536Y133840D02*
Y134824D01*
G01Y151553D02*
Y152538D01*
G01X361458Y152539D02*
Y133838D01*
G01X361379Y135984D02*
Y129901D01*
G01Y156476D02*
Y150393D01*
G01X361182Y134822D02*
Y133838D01*
G01Y152539D02*
Y151555D01*
G01X361177Y152539D02*
Y151555D01*
G01X361143Y136515D02*
Y132342D01*
G01Y154035D02*
Y149862D01*
G01X360040D02*
Y154035D01*
G01Y132342D02*
Y136515D01*
G01X360006Y152539D02*
Y151555D01*
G01X360001Y134822D02*
Y133838D01*
G01X359996Y134822D02*
Y133838D01*
G01X359804Y135984D02*
Y129901D01*
G01Y156476D02*
Y150393D01*
G01X359725Y133838D02*
Y152539D01*
G01X359651Y152538D02*
Y151553D01*
G01X359642Y134824D02*
Y133840D01*
G01X359450Y147698D02*
Y152539D01*
G01Y133838D02*
Y138680D01*
G01X359376Y150760D02*
Y151750D01*
G01X359366Y134627D02*
Y135617D01*
G01X359292Y138760D02*
Y137696D01*
G01Y148681D02*
Y147618D01*
G01X359017Y138760D02*
Y137775D01*
G01Y148602D02*
Y147618D01*
G01X358229Y138760D02*
Y137775D01*
G01Y148602D02*
Y147618D01*
G01X357954Y138760D02*
Y137696D01*
G01Y148681D02*
Y147618D01*
G01X357880Y151750D02*
Y150760D01*
G01X357870Y135617D02*
Y134627D01*
G01X357796Y147698D02*
Y152539D01*
G01Y133838D02*
Y138680D01*
G01X357604Y151553D02*
Y152538D01*
G01X357595Y133840D02*
Y134824D01*
G01X357521Y152539D02*
Y133838D01*
G01X357442Y135984D02*
Y129901D01*
G01Y156476D02*
Y150393D01*
G01X357250Y152539D02*
Y151555D01*
G01X357245Y152539D02*
Y151555D01*
G01X357240Y134822D02*
Y133838D01*
G01X357206Y136515D02*
Y132342D01*
G01Y154035D02*
Y149862D01*
G01X356103D02*
Y154035D01*
G01Y132342D02*
Y136515D01*
G01X356069Y134822D02*
Y133838D01*
G01X356064Y134822D02*
Y133838D01*
G01Y152539D02*
Y151555D01*
G01X355867Y135984D02*
Y129901D01*
G01Y156476D02*
Y150393D01*
G01X355788Y133838D02*
Y152539D01*
G01X355710Y134824D02*
Y133840D01*
G01Y152538D02*
Y151553D01*
G01X355513Y151555D02*
Y156396D01*
G01Y129981D02*
Y134822D01*
G01X355434Y150760D02*
Y151750D01*
G01Y134627D02*
Y135617D01*
G01X355355Y130965D02*
Y129901D01*
G01Y156476D02*
Y155412D01*
G01X377825Y135009D02*
X377812Y135984D01*
G01X374858Y151368D02*
X374872Y150393D01*
G01X373884Y135009D02*
X373871Y135984D01*
G01X370917Y151368D02*
X370930Y150393D01*
G01X369951Y135009D02*
X369938Y135984D01*
G01X366984Y151368D02*
X366998Y150393D01*
G01X366010Y135009D02*
X365997Y135984D01*
G01X363043Y151368D02*
X363056Y150393D01*
G01X362077Y135009D02*
X362064Y135984D01*
G01X359110Y151368D02*
X359123Y150393D01*
G01X358136Y135009D02*
X358123Y135984D01*
G01X355169Y151368D02*
X355182Y150393D01*
G01X377439Y146239D02*
X377302Y152147D01*
G01X377298Y151260D02*
X377434Y145353D01*
G01X375377Y135117D02*
X375241Y141024D01*
G01X375236Y140138D02*
X375372Y134231D01*
G01X373506Y146239D02*
X373370Y152147D01*
G01X373365Y151260D02*
X373502Y145353D01*
G01X371444Y135117D02*
X371308Y141024D01*
G01X371303Y140138D02*
X371440Y134231D01*
G01X369565Y146239D02*
X369428Y152147D01*
G01X369424Y151260D02*
X369560Y145353D01*
G01X367503Y135117D02*
X367367Y141024D01*
G01X367362Y140138D02*
X367498Y134231D01*
G01X365632Y146239D02*
X365496Y152147D01*
G01X365491Y151260D02*
X365628Y145353D01*
G01X363570Y135117D02*
X363434Y141024D01*
G01X363429Y140138D02*
X363566Y134231D01*
G01X361691Y146239D02*
X361554Y152147D01*
G01X361550Y151260D02*
X361686Y145353D01*
G01X359629Y135117D02*
X359493Y141024D01*
G01X359488Y140138D02*
X359624Y134231D01*
G01X357758Y146239D02*
X357622Y152147D01*
G01X357617Y151260D02*
X357753Y145353D01*
G01X355696Y135117D02*
X355560Y141024D01*
G01X355555Y140138D02*
X355692Y134231D01*
G01X353817Y146239D02*
X353680Y152147D01*
G01X353676Y151260D02*
X353812Y145353D01*
G01X375224Y146012D02*
X375173Y146999D01*
G01X375171Y146037D02*
X375221Y145050D01*
G01X373571Y140340D02*
X373521Y141327D01*
G01X373518Y140365D02*
X373569Y139379D01*
G01X371282Y146012D02*
X371232Y146999D01*
G01X371229Y146037D02*
X371280Y145050D01*
G01X369639Y140340D02*
X369588Y141327D01*
G01X369586Y140365D02*
X369636Y139379D01*
G01X367350Y146012D02*
X367299Y146999D01*
G01X367297Y146037D02*
X367347Y145050D01*
G01X365697Y140340D02*
X365647Y141327D01*
G01X365644Y140365D02*
X365695Y139379D01*
G01X363408Y146012D02*
X363358Y146999D01*
G01X363355Y146037D02*
X363406Y145050D01*
G01X361765Y140340D02*
X361714Y141327D01*
G01X361712Y140365D02*
X361762Y139379D01*
G01X359476Y146012D02*
X359425Y146999D01*
G01X359423Y146037D02*
X359473Y145050D01*
G01X357823Y140340D02*
X357773Y141327D01*
G01X357770Y140365D02*
X357821Y139379D01*
G01X355534Y146012D02*
X355484Y146999D01*
G01X355481Y146037D02*
X355532Y145050D01*
G01X353891Y140340D02*
X353840Y141327D01*
G01X353838Y140365D02*
X353888Y139379D01*
G01X406608Y151737D02*
X406354Y151368D01*
G01X393320Y134640D02*
X393573Y135009D01*
G01X393528Y135937D02*
X393308Y135617D01*
G01X402458Y150441D02*
X402678Y150760D01*
G01X402667Y151737D02*
X402413Y151368D01*
G01X389378Y134640D02*
X389632Y135009D01*
G01X389365Y135615D02*
X389586Y135937D01*
G01X398747Y150762D02*
X398526Y150441D01*
G01X398734Y151737D02*
X398480Y151368D01*
G01X385446Y134640D02*
X385699Y135009D01*
G01X385432Y135615D02*
X385654Y135937D01*
G01X394584Y150441D02*
X394804Y150760D01*
G01X394793Y151737D02*
X394539Y151368D01*
G01X381504Y134640D02*
X381758Y135009D01*
G01X381491Y135615D02*
X381712Y135937D01*
G01X390873Y150762D02*
X390652Y150441D01*
G01X390860Y151737D02*
X390606Y151368D01*
G01X377572Y134640D02*
X377825Y135009D01*
G01X377558Y135615D02*
X377780Y135937D01*
G01X386932Y150762D02*
X386710Y150441D01*
G01X386919Y151737D02*
X386665Y151368D01*
G01X373630Y134640D02*
X373884Y135009D01*
G01X373617Y135615D02*
X373838Y135937D01*
G01X382999Y150762D02*
X382778Y150441D01*
G01X382986Y151737D02*
X382732Y151368D01*
G01X369698Y134640D02*
X369951Y135009D01*
G01X369684Y135615D02*
X369906Y135937D01*
G01X379058Y150762D02*
X378836Y150441D01*
G01X379045Y151737D02*
X378791Y151368D01*
G01X365756Y134640D02*
X366010Y135009D01*
G01X365974Y135984D02*
X365964Y135937D01*
G01X367020Y150393D02*
X367030Y150441D01*
G01X362041Y135984D02*
X362032Y135937D01*
G01X363079Y150393D02*
X363088Y150441D01*
G01X358100Y135984D02*
X358090Y135937D01*
G01X359146Y150393D02*
X359156Y150441D01*
G01X354167Y135984D02*
X354158Y135937D01*
G01X355205Y150393D02*
X355214Y150441D01*
G01X350226Y135984D02*
X350216Y135937D01*
G01X351272Y150393D02*
X351282Y150441D01*
G01X347331Y150393D02*
X347340Y150441D01*
G01X357782Y145050D02*
X357832Y146037D01*
G01X357830Y146999D02*
X357780Y146012D01*
G01X355484Y139379D02*
X355534Y140365D01*
G01X355532Y141327D02*
X355481Y140340D01*
G01X353840Y145050D02*
X353891Y146037D01*
G01X353888Y146999D02*
X353838Y146012D01*
G01X351542Y139379D02*
X351592Y140365D01*
G01X351590Y141327D02*
X351540Y140340D01*
G01X349908Y145050D02*
X349958Y146037D01*
G01X349956Y146999D02*
X349906Y146012D01*
G01X347610Y139379D02*
X347660Y140365D01*
G01X347658Y141327D02*
X347607Y140340D01*
G01X355560Y145353D02*
X355696Y151260D01*
G01X355692Y152147D02*
X355555Y146239D01*
G01X353680Y134231D02*
X353817Y140138D01*
G01X353812Y141024D02*
X353676Y135117D01*
G01X351628Y145353D02*
X351764Y151260D01*
G01X351759Y152147D02*
X351623Y146239D01*
G01X349739Y134231D02*
X349875Y140138D01*
G01X349870Y141024D02*
X349734Y135117D01*
G01X347686Y145353D02*
X347822Y151260D01*
G01X347818Y152147D02*
X347681Y146239D01*
G01X355182Y135984D02*
X355169Y135009D01*
G01X354190Y150393D02*
X354203Y151368D01*
G01X351240Y135984D02*
X351227Y135009D01*
G01X350258Y150393D02*
X350271Y151368D01*
G01X347308Y135984D02*
X347295Y135009D01*
G01X355080Y130885D02*
Y129901D01*
G01Y156476D02*
Y155492D01*
G01X354292D02*
Y156476D01*
G01Y130885D02*
Y129901D01*
G01X354017Y130965D02*
Y129901D01*
G01Y156476D02*
Y155412D01*
G01X353938Y135617D02*
Y134627D01*
G01Y151750D02*
Y150760D01*
G01X353859Y151555D02*
Y156396D01*
G01Y129981D02*
Y134822D01*
G01X353662Y133840D02*
Y134824D01*
G01Y151553D02*
Y152538D01*
G01X353584Y152539D02*
Y133838D01*
G01X353505Y135984D02*
Y129901D01*
G01Y156476D02*
Y150393D01*
G01X353308Y134822D02*
Y133838D01*
G01Y152539D02*
Y151555D01*
G01X353303Y152539D02*
Y151555D01*
G01X353269Y136515D02*
Y132342D01*
G01Y154035D02*
Y149862D01*
G01X352166D02*
Y154035D01*
G01Y132342D02*
Y136515D01*
G01X352132Y152539D02*
Y151555D01*
G01X352127Y134822D02*
Y133838D01*
G01X352122Y134822D02*
Y133838D01*
G01X351930Y135984D02*
Y129901D01*
G01Y156476D02*
Y150393D01*
G01X351851Y133838D02*
Y152539D01*
G01X351777Y152538D02*
Y151553D01*
G01X351768Y134824D02*
Y133840D01*
G01X351576Y147698D02*
Y152539D01*
G01Y133838D02*
Y138680D01*
G01X351502Y150760D02*
Y151750D01*
G01X351492Y134627D02*
Y135617D01*
G01X351418Y138760D02*
Y137696D01*
G01Y148681D02*
Y147618D01*
G01X351143Y138760D02*
Y137775D01*
G01Y148602D02*
Y147618D01*
G01X350355Y138760D02*
Y137775D01*
G01Y148602D02*
Y147618D01*
G01X350080Y138760D02*
Y137696D01*
G01Y148681D02*
Y147618D01*
G01X350006Y151750D02*
Y150760D01*
G01X349996Y135617D02*
Y134627D01*
G01X349962Y128523D02*
Y123011D01*
G01X349922Y147698D02*
Y152539D01*
G01Y133838D02*
Y138680D01*
G01X349730Y151553D02*
Y152538D01*
G01X349721Y133840D02*
Y134824D01*
G01X349647Y152539D02*
Y133838D01*
G01X349568Y135984D02*
Y129901D01*
G01Y156476D02*
Y150393D01*
G01X349376Y152539D02*
Y151555D01*
G01X349371Y152539D02*
Y151555D01*
G01X349366Y134822D02*
Y133838D01*
G01X349332Y136515D02*
Y132342D01*
G01Y154035D02*
Y149862D01*
G01X348229D02*
Y154035D01*
G01Y132342D02*
Y136515D01*
G01X348195Y134822D02*
Y133838D01*
G01X348190Y134822D02*
Y133838D01*
G01Y152539D02*
Y151555D01*
G01X347993Y135984D02*
Y129901D01*
G01Y156476D02*
Y150393D01*
G01X347914Y133838D02*
Y152539D01*
G01X347836Y134824D02*
Y133840D01*
G01Y152538D02*
Y151553D01*
G01X347639Y151555D02*
Y156396D01*
G01Y129981D02*
Y134822D01*
G01X347560Y150760D02*
Y151750D01*
G01Y134627D02*
Y135617D01*
G01X347481Y130965D02*
Y129901D01*
G01Y156476D02*
Y155412D01*
G01X347206Y130885D02*
Y129901D01*
G01Y156476D02*
Y155492D01*
G01X354203Y135009D02*
X354190Y135984D01*
G01X351236Y151368D02*
X351249Y150393D01*
G01X350262Y135009D02*
X350249Y135984D01*
G01X347295Y151368D02*
X347308Y150393D01*
G01X351755Y135117D02*
X351619Y141024D01*
G01X351614Y140138D02*
X351750Y134231D01*
G01X349884Y146239D02*
X349748Y152147D01*
G01X349743Y151260D02*
X349879Y145353D01*
G01X347822Y135117D02*
X347686Y141024D01*
G01X347681Y140138D02*
X347818Y134231D01*
G01X351602Y146012D02*
X351551Y146999D01*
G01X351549Y146037D02*
X351599Y145050D01*
G01X349949Y140340D02*
X349899Y141327D01*
G01X349896Y140365D02*
X349947Y139379D01*
G01X347660Y146012D02*
X347610Y146999D01*
G01X347607Y146037D02*
X347658Y145050D01*
G01X365743Y135615D02*
X365964Y135937D01*
G01X375125Y150762D02*
X374904Y150441D01*
G01X375112Y151737D02*
X374858Y151368D01*
G01X361824Y134640D02*
X362077Y135009D01*
G01X361810Y135615D02*
X362032Y135937D01*
G01X371184Y150762D02*
X370962Y150441D01*
G01X371171Y151737D02*
X370917Y151368D01*
G01X357882Y134640D02*
X358136Y135009D01*
G01X357869Y135615D02*
X358090Y135937D01*
G01X367251Y150762D02*
X367030Y150441D01*
G01X367238Y151737D02*
X366984Y151368D01*
G01X353950Y134640D02*
X354203Y135009D01*
G01X353936Y135615D02*
X354158Y135937D01*
G01X363310Y150762D02*
X363088Y150441D01*
G01X363297Y151737D02*
X363043Y151368D01*
G01X350008Y134640D02*
X350262Y135009D01*
G01X349995Y135615D02*
X350216Y135937D01*
G01X359377Y150762D02*
X359156Y150441D01*
G01X359364Y151737D02*
X359110Y151368D01*
G01X355436Y150762D02*
X355214Y150441D01*
G01X355423Y151737D02*
X355169Y151368D01*
G01X351503Y150762D02*
X351282Y150441D01*
G01X351490Y151737D02*
X351236Y151368D01*
G01X347562Y150762D02*
X347340Y150441D01*
G01X347548Y151737D02*
X347295Y151368D01*
G01X424693Y225965D02*
X424704Y226012D01*
G01X424688Y226063D02*
X424693Y225965D01*
G01X424683Y226239D02*
X424688Y226063D01*
G01X424778Y228861D02*
X424780Y229826D01*
G01X424776Y228414D02*
X424778Y228861D01*
G01X424773Y228009D02*
X424776Y228414D01*
G01X424769Y227656D02*
X424773Y228009D01*
G01X424765Y227364D02*
X424769Y227656D01*
G01X424760Y227143D02*
X424765Y227364D01*
G01X424755Y226999D02*
X424760Y227143D01*
G01X424789Y228520D02*
X424791Y229807D01*
G01X424786Y227925D02*
X424789Y228520D01*
G01X424781Y227384D02*
X424786Y227925D01*
G01X424776Y226913D02*
X424781Y227384D01*
G01X424770Y226524D02*
X424776Y226913D01*
G01X424764Y226230D02*
X424770Y226524D01*
G01X424757Y226037D02*
X424764Y226230D01*
G01X424692Y224988D02*
X424706Y225050D01*
G01X424685Y225118D02*
X424692Y224988D01*
G01X424678Y225353D02*
X424685Y225118D01*
G01X426411Y225965D02*
X426422Y226239D01*
G01X426406Y225948D02*
X426411Y225965D01*
G01X426400Y226012D02*
X426406Y225948D01*
G01X426412Y224988D02*
X426426Y225353D01*
G01X426405Y224965D02*
X426412Y224988D01*
G01X426398Y225050D02*
X426405Y224965D01*
G01X426334Y226524D02*
X426347Y226037D01*
G01X426328Y226913D02*
X426334Y226524D01*
G01X426323Y227384D02*
X426328Y226913D01*
G01X426319Y227925D02*
X426323Y227384D01*
G01X426316Y228520D02*
X426319Y227925D01*
G01X426314Y229153D02*
X426316Y228520D01*
G01X426313Y229807D02*
X426314Y229153D01*
G01X426340Y227364D02*
X426350Y226999D01*
G01X426335Y227656D02*
X426340Y227364D01*
G01X426331Y228009D02*
X426335Y227656D01*
G01X426328Y228414D02*
X426331Y228009D01*
G01X426326Y228861D02*
X426328Y228414D01*
G01X426324Y229336D02*
X426326Y228861D01*
G01X426324Y229826D02*
Y229336D01*
G01X426411Y220412D02*
X426400Y220365D01*
G01X426416Y220314D02*
X426411Y220412D01*
G01X426422Y220138D02*
X426416Y220314D01*
G01X426326Y217516D02*
X426324Y216551D01*
G01X426328Y217963D02*
X426326Y217516D01*
G01X426331Y218368D02*
X426328Y217963D01*
G01X426335Y218722D02*
X426331Y218368D01*
G01X426340Y219013D02*
X426335Y218722D01*
G01X426344Y219234D02*
X426340Y219013D01*
G01X426350Y219379D02*
X426344Y219234D01*
G01X426316Y217857D02*
X426313Y216570D01*
G01X426319Y218453D02*
X426316Y217857D01*
G01X426323Y218993D02*
X426319Y218453D01*
G01X426328Y219464D02*
X426323Y218993D01*
G01X426334Y219853D02*
X426328Y219464D01*
G01X426340Y220148D02*
X426334Y219853D01*
G01X426347Y220340D02*
X426340Y220148D01*
G01X426412Y221390D02*
X426398Y221327D01*
G01X426420Y221259D02*
X426412Y221390D01*
G01X426426Y221024D02*
X426420Y221259D01*
G01X424693Y220412D02*
X424683Y220138D01*
G01X424699Y220429D02*
X424693Y220412D01*
G01X424704Y220365D02*
X424699Y220429D01*
G01X424692Y221390D02*
X424678Y221024D01*
G01X424699Y221412D02*
X424692Y221390D01*
G01X424706Y221327D02*
X424699Y221412D01*
G01X424770Y219853D02*
X424757Y220340D01*
G01X424776Y219464D02*
X424770Y219853D01*
G01X424781Y218993D02*
X424776Y219464D01*
G01X424786Y218453D02*
X424781Y218993D01*
G01X424789Y217857D02*
X424786Y218453D01*
G01X424791Y217224D02*
X424789Y217857D01*
G01X424791Y216570D02*
Y217224D01*
G01X424765Y219013D02*
X424755Y219379D01*
G01X424769Y218722D02*
X424765Y219013D01*
G01X424773Y218368D02*
X424769Y218722D01*
G01X424776Y217963D02*
X424773Y218368D01*
G01X424778Y217516D02*
X424776Y217963D01*
G01X424780Y217041D02*
X424778Y217516D01*
G01X424780Y216551D02*
Y217041D01*
G01X422479Y225965D02*
X422489Y226239D01*
G01X422473Y225948D02*
X422479Y225965D01*
G01X422468Y226012D02*
X422473Y225948D01*
G01X422480Y224988D02*
X422494Y225353D01*
G01X422473Y224965D02*
X422480Y224988D01*
G01X422466Y225050D02*
X422473Y224965D01*
G01X422402Y226524D02*
X422415Y226037D01*
G01X422396Y226913D02*
X422402Y226524D01*
G01X422390Y227384D02*
X422396Y226913D01*
G01X422386Y227925D02*
X422390Y227384D01*
G01X422383Y228520D02*
X422386Y227925D01*
G01X422381Y229153D02*
X422383Y228520D01*
G01X422381Y229807D02*
Y229153D01*
G01X422376Y231677D02*
X422368Y231750D01*
G01X422379Y231547D02*
X422376Y231677D01*
G01X422383Y231359D02*
X422379Y231547D01*
G01X422386Y231120D02*
X422383Y231359D01*
G01X422388Y230838D02*
X422386Y231120D01*
G01X422390Y230521D02*
X422388Y230838D01*
G01X422391Y230180D02*
X422390Y230521D01*
G01X422391Y229826D02*
Y230180D01*
G01X422407Y227364D02*
X422417Y226999D01*
G01X422403Y227656D02*
X422407Y227364D01*
G01X422399Y228009D02*
X422403Y227656D01*
G01X422396Y228414D02*
X422399Y228009D01*
G01X422394Y228861D02*
X422396Y228414D01*
G01X422392Y229336D02*
X422394Y228861D01*
G01X422391Y229826D02*
X422392Y229336D01*
G01X420761Y225965D02*
X420772Y226012D01*
G01X420755Y226063D02*
X420761Y225965D01*
G01X420750Y226239D02*
X420755Y226063D01*
G01X420846Y228861D02*
X420848Y229826D01*
G01X420844Y228414D02*
X420846Y228861D01*
G01X420841Y228009D02*
X420844Y228414D01*
G01X420837Y227656D02*
X420841Y228009D01*
G01X420832Y227364D02*
X420837Y227656D01*
G01X420827Y227143D02*
X420832Y227364D01*
G01X420822Y226999D02*
X420827Y227143D01*
G01X420850Y230521D02*
X420848Y229826D01*
G01X420851Y230838D02*
X420850Y230521D01*
G01X420854Y231120D02*
X420851Y230838D01*
G01X420857Y231359D02*
X420854Y231120D01*
G01X420860Y231547D02*
X420857Y231359D01*
G01X420864Y231677D02*
X420860Y231547D01*
G01X420868Y231746D02*
X420864Y231677D01*
G01X420872Y231750D02*
X420868Y231746D01*
G01X420856Y228520D02*
X420859Y229807D01*
G01X420853Y227925D02*
X420856Y228520D01*
G01X420849Y227384D02*
X420853Y227925D01*
G01X420844Y226913D02*
X420849Y227384D01*
G01X420838Y226524D02*
X420844Y226913D01*
G01X420832Y226230D02*
X420838Y226524D01*
G01X420825Y226037D02*
X420832Y226230D01*
G01X420760Y224988D02*
X420774Y225050D01*
G01X420752Y225118D02*
X420760Y224988D01*
G01X420746Y225353D02*
X420752Y225118D01*
G01Y220412D02*
X420741Y220138D01*
G01X420757Y220429D02*
X420752Y220412D01*
G01X420762Y220365D02*
X420757Y220429D01*
G01X420750Y221390D02*
X420736Y221024D01*
G01X420757Y221412D02*
X420750Y221390D01*
G01X420765Y221327D02*
X420757Y221412D01*
G01X420829Y219853D02*
X420815Y220340D01*
G01X420835Y219464D02*
X420829Y219853D01*
G01X420840Y218993D02*
X420835Y219464D01*
G01X420844Y218453D02*
X420840Y218993D01*
G01X420847Y217857D02*
X420844Y218453D01*
G01X420849Y217224D02*
X420847Y217857D01*
G01X420850Y216570D02*
X420849Y217224D01*
G01X420855Y214700D02*
X420862Y214627D01*
G01X420851Y214830D02*
X420855Y214700D01*
G01X420848Y215018D02*
X420851Y214830D01*
G01X420845Y215257D02*
X420848Y215018D01*
G01X420842Y215540D02*
X420845Y215257D01*
G01X420840Y215857D02*
X420842Y215540D01*
G01X420839Y216198D02*
X420840Y215857D01*
G01X420839Y216551D02*
Y216198D01*
G01X420823Y219013D02*
X420813Y219379D01*
G01X420827Y218722D02*
X420823Y219013D01*
G01X420831Y218368D02*
X420827Y218722D01*
G01X420834Y217963D02*
X420831Y218368D01*
G01X420837Y217516D02*
X420834Y217963D01*
G01X420838Y217041D02*
X420837Y217516D01*
G01X420839Y216551D02*
X420838Y217041D01*
G01X422469Y220412D02*
X422459Y220365D01*
G01X422475Y220314D02*
X422469Y220412D01*
G01X422480Y220138D02*
X422475Y220314D01*
G01X422384Y217516D02*
X422382Y216551D01*
G01X422387Y217963D02*
X422384Y217516D01*
G01X422390Y218368D02*
X422387Y217963D01*
G01X422393Y218722D02*
X422390Y218368D01*
G01X422398Y219013D02*
X422393Y218722D01*
G01X422403Y219234D02*
X422398Y219013D01*
G01X422408Y219379D02*
X422403Y219234D01*
G01X422381Y215857D02*
X422382Y216551D01*
G01X422379Y215540D02*
X422381Y215857D01*
G01X422376Y215257D02*
X422379Y215540D01*
G01X422373Y215018D02*
X422376Y215257D01*
G01X422370Y214830D02*
X422373Y215018D01*
G01X422366Y214700D02*
X422370Y214830D01*
G01X422362Y214632D02*
X422366Y214700D01*
G01X422359Y214627D02*
X422362Y214632D01*
G01X422374Y217857D02*
X422371Y216570D01*
G01X422377Y218453D02*
X422374Y217857D01*
G01X422381Y218993D02*
X422377Y218453D01*
G01X422386Y219464D02*
X422381Y218993D01*
G01X422392Y219853D02*
X422386Y219464D01*
G01X422399Y220148D02*
X422392Y219853D01*
G01X422406Y220340D02*
X422399Y220148D01*
G01X422471Y221390D02*
X422456Y221327D01*
G01X422478Y221259D02*
X422471Y221390D01*
G01X422485Y221024D02*
X422478Y221259D01*
G01X416819Y225965D02*
X416830Y226012D01*
G01X416814Y226063D02*
X416819Y225965D01*
G01X416809Y226239D02*
X416814Y226063D01*
G01X416904Y228861D02*
X416906Y229826D01*
G01X416902Y228414D02*
X416904Y228861D01*
G01X416899Y228009D02*
X416902Y228414D01*
G01X416895Y227656D02*
X416899Y228009D01*
G01X416891Y227364D02*
X416895Y227656D01*
G01X416886Y227143D02*
X416891Y227364D01*
G01X416881Y226999D02*
X416886Y227143D01*
G01X416915Y228520D02*
X416917Y229807D01*
G01X416912Y227925D02*
X416915Y228520D01*
G01X416907Y227384D02*
X416912Y227925D01*
G01X416902Y226913D02*
X416907Y227384D01*
G01X416896Y226524D02*
X416902Y226913D01*
G01X416890Y226230D02*
X416896Y226524D01*
G01X416883Y226037D02*
X416890Y226230D01*
G01X416818Y224988D02*
X416832Y225050D01*
G01X416811Y225118D02*
X416818Y224988D01*
G01X416804Y225353D02*
X416811Y225118D01*
G01X418537Y225965D02*
X418548Y226239D01*
G01X418532Y225948D02*
X418537Y225965D01*
G01X418526Y226012D02*
X418532Y225948D01*
G01X418538Y224988D02*
X418552Y225353D01*
G01X418531Y224965D02*
X418538Y224988D01*
G01X418524Y225050D02*
X418531Y224965D01*
G01X418460Y226524D02*
X418473Y226037D01*
G01X418454Y226913D02*
X418460Y226524D01*
G01X418449Y227384D02*
X418454Y226913D01*
G01X418445Y227925D02*
X418449Y227384D01*
G01X418442Y228520D02*
X418445Y227925D01*
G01X418440Y229153D02*
X418442Y228520D01*
G01X418439Y229807D02*
X418440Y229153D01*
G01X418466Y227364D02*
X418476Y226999D01*
G01X418461Y227656D02*
X418466Y227364D01*
G01X418457Y228009D02*
X418461Y227656D01*
G01X418454Y228414D02*
X418457Y228009D01*
G01X418452Y228861D02*
X418454Y228414D01*
G01X418450Y229336D02*
X418452Y228861D01*
G01X418450Y229826D02*
Y229336D01*
G01X418537Y220412D02*
X418526Y220365D01*
G01X418542Y220314D02*
X418537Y220412D01*
G01X418548Y220138D02*
X418542Y220314D01*
G01X418452Y217516D02*
X418450Y216551D01*
G01X418454Y217963D02*
X418452Y217516D01*
G01X418457Y218368D02*
X418454Y217963D01*
G01X418461Y218722D02*
X418457Y218368D01*
G01X418466Y219013D02*
X418461Y218722D01*
G01X418470Y219234D02*
X418466Y219013D01*
G01X418476Y219379D02*
X418470Y219234D01*
G01X418442Y217857D02*
X418439Y216570D01*
G01X418445Y218453D02*
X418442Y217857D01*
G01X418449Y218993D02*
X418445Y218453D01*
G01X418454Y219464D02*
X418449Y218993D01*
G01X418460Y219853D02*
X418454Y219464D01*
G01X418466Y220148D02*
X418460Y219853D01*
G01X418473Y220340D02*
X418466Y220148D01*
G01X418538Y221390D02*
X418524Y221327D01*
G01X418546Y221259D02*
X418538Y221390D01*
G01X418552Y221024D02*
X418546Y221259D01*
G01X416819Y220412D02*
X416809Y220138D01*
G01X416825Y220429D02*
X416819Y220412D01*
G01X416830Y220365D02*
X416825Y220429D01*
G01X416818Y221390D02*
X416804Y221024D01*
G01X416825Y221412D02*
X416818Y221390D01*
G01X416832Y221327D02*
X416825Y221412D01*
G01X416896Y219853D02*
X416883Y220340D01*
G01X416902Y219464D02*
X416896Y219853D01*
G01X416907Y218993D02*
X416902Y219464D01*
G01X416912Y218453D02*
X416907Y218993D01*
G01X416915Y217857D02*
X416912Y218453D01*
G01X416917Y217224D02*
X416915Y217857D01*
G01X416917Y216570D02*
Y217224D01*
G01X416891Y219013D02*
X416881Y219379D01*
G01X416895Y218722D02*
X416891Y219013D01*
G01X416899Y218368D02*
X416895Y218722D01*
G01X416902Y217963D02*
X416899Y218368D01*
G01X416904Y217516D02*
X416902Y217963D01*
G01X416906Y217041D02*
X416904Y217516D01*
G01X416906Y216551D02*
Y217041D01*
G01X414605Y225965D02*
X414615Y226239D01*
G01X414599Y225948D02*
X414605Y225965D01*
G01X414594Y226012D02*
X414599Y225948D01*
G01X414606Y224988D02*
X414620Y225353D01*
G01X414599Y224965D02*
X414606Y224988D01*
G01X414592Y225050D02*
X414599Y224965D01*
G01X414527Y226524D02*
X414541Y226037D01*
G01X414522Y226913D02*
X414527Y226524D01*
G01X414516Y227384D02*
X414522Y226913D01*
G01X414512Y227925D02*
X414516Y227384D01*
G01X414509Y228520D02*
X414512Y227925D01*
G01X414507Y229153D02*
X414509Y228520D01*
G01X414507Y229807D02*
Y229153D01*
G01X414502Y231677D02*
X414494Y231750D01*
G01X414505Y231547D02*
X414502Y231677D01*
G01X414509Y231359D02*
X414505Y231547D01*
G01X414512Y231120D02*
X414509Y231359D01*
G01X414514Y230838D02*
X414512Y231120D01*
G01X414516Y230521D02*
X414514Y230838D01*
G01X414517Y230180D02*
X414516Y230521D01*
G01X414517Y229826D02*
Y230180D01*
G01X414533Y227364D02*
X414543Y226999D01*
G01X414529Y227656D02*
X414533Y227364D01*
G01X414525Y228009D02*
X414529Y227656D01*
G01X414522Y228414D02*
X414525Y228009D01*
G01X414519Y228861D02*
X414522Y228414D01*
G01X414518Y229336D02*
X414519Y228861D01*
G01X414517Y229826D02*
X414518Y229336D01*
G01X412887Y225965D02*
X412898Y226012D01*
G01X412881Y226063D02*
X412887Y225965D01*
G01X412876Y226239D02*
X412881Y226063D01*
G01X412972Y228861D02*
X412974Y229826D01*
G01X412970Y228414D02*
X412972Y228861D01*
G01X412967Y228009D02*
X412970Y228414D01*
G01X412963Y227656D02*
X412967Y228009D01*
G01X412958Y227364D02*
X412963Y227656D01*
G01X412953Y227143D02*
X412958Y227364D01*
G01X412948Y226999D02*
X412953Y227143D01*
G01X412976Y230521D02*
X412974Y229826D01*
G01X412977Y230838D02*
X412976Y230521D01*
G01X412980Y231120D02*
X412977Y230838D01*
G01X412983Y231359D02*
X412980Y231120D01*
G01X412986Y231547D02*
X412983Y231359D01*
G01X412990Y231677D02*
X412986Y231547D01*
G01X412994Y231746D02*
X412990Y231677D01*
G01X412998Y231750D02*
X412994Y231746D01*
G01X412982Y228520D02*
X412985Y229807D01*
G01X412979Y227925D02*
X412982Y228520D01*
G01X412975Y227384D02*
X412979Y227925D01*
G01X412970Y226913D02*
X412975Y227384D01*
G01X412964Y226524D02*
X412970Y226913D01*
G01X412958Y226230D02*
X412964Y226524D01*
G01X412951Y226037D02*
X412958Y226230D01*
G01X412886Y224988D02*
X412900Y225050D01*
G01X412878Y225118D02*
X412886Y224988D01*
G01X412872Y225353D02*
X412878Y225118D01*
G01X412877Y220412D02*
X412867Y220138D01*
G01X412883Y220429D02*
X412877Y220412D01*
G01X412888Y220365D02*
X412883Y220429D01*
G01X412876Y221390D02*
X412862Y221024D01*
G01X412883Y221412D02*
X412876Y221390D01*
G01X412891Y221327D02*
X412883Y221412D01*
G01X412955Y219853D02*
X412941Y220340D01*
G01X412961Y219464D02*
X412955Y219853D01*
G01X412966Y218993D02*
X412961Y219464D01*
G01X412970Y218453D02*
X412966Y218993D01*
G01X412973Y217857D02*
X412970Y218453D01*
G01X412975Y217224D02*
X412973Y217857D01*
G01X412976Y216570D02*
X412975Y217224D01*
G01X412981Y214700D02*
X412988Y214627D01*
G01X412977Y214830D02*
X412981Y214700D01*
G01X412973Y215018D02*
X412977Y214830D01*
G01X412971Y215257D02*
X412973Y215018D01*
G01X412968Y215540D02*
X412971Y215257D01*
G01X412966Y215857D02*
X412968Y215540D01*
G01X412965Y216198D02*
X412966Y215857D01*
G01X412965Y216551D02*
Y216198D01*
G01X412949Y219013D02*
X412939Y219379D01*
G01X412953Y218722D02*
X412949Y219013D01*
G01X412957Y218368D02*
X412953Y218722D01*
G01X412960Y217963D02*
X412957Y218368D01*
G01X412963Y217516D02*
X412960Y217963D01*
G01X412964Y217041D02*
X412963Y217516D01*
G01X412965Y216551D02*
X412964Y217041D01*
G01X414595Y220412D02*
X414585Y220365D01*
G01X414601Y220314D02*
X414595Y220412D01*
G01X414606Y220138D02*
X414601Y220314D01*
G01X414510Y217516D02*
X414508Y216551D01*
G01X414512Y217963D02*
X414510Y217516D01*
G01X414516Y218368D02*
X414512Y217963D01*
G01X414519Y218722D02*
X414516Y218368D01*
G01X414524Y219013D02*
X414519Y218722D01*
G01X414529Y219234D02*
X414524Y219013D01*
G01X414534Y219379D02*
X414529Y219234D01*
G01X414507Y215857D02*
X414508Y216551D01*
G01X414505Y215540D02*
X414507Y215857D01*
G01X414502Y215257D02*
X414505Y215540D01*
G01X414499Y215018D02*
X414502Y215257D01*
G01X414496Y214830D02*
X414499Y215018D01*
G01X414492Y214700D02*
X414496Y214830D01*
G01X414488Y214632D02*
X414492Y214700D01*
G01X414484Y214627D02*
X414488Y214632D01*
G01X414500Y217857D02*
X414497Y216570D01*
G01X414503Y218453D02*
X414500Y217857D01*
G01X414507Y218993D02*
X414503Y218453D01*
G01X414512Y219464D02*
X414507Y218993D01*
G01X414518Y219853D02*
X414512Y219464D01*
G01X414525Y220148D02*
X414518Y219853D01*
G01X414532Y220340D02*
X414525Y220148D01*
G01X414597Y221390D02*
X414582Y221327D01*
G01X414604Y221259D02*
X414597Y221390D01*
G01X414611Y221024D02*
X414604Y221259D01*
G01X410663Y220412D02*
X410652Y220365D01*
G01X410668Y220314D02*
X410663Y220412D01*
G01X410674Y220138D02*
X410668Y220314D01*
G01X410578Y217516D02*
X410576Y216551D01*
G01X410580Y217963D02*
X410578Y217516D01*
G01X410583Y218368D02*
X410580Y217963D01*
G01X410587Y218722D02*
X410583Y218368D01*
G01X410592Y219013D02*
X410587Y218722D01*
G01X410596Y219234D02*
X410592Y219013D01*
G01X410602Y219379D02*
X410596Y219234D01*
G01X410568Y217857D02*
X410565Y216570D01*
G01X410571Y218453D02*
X410568Y217857D01*
G01X410575Y218993D02*
X410571Y218453D01*
G01X410580Y219464D02*
X410575Y218993D01*
G01X410586Y219853D02*
X410580Y219464D01*
G01X410592Y220148D02*
X410586Y219853D01*
G01X410599Y220340D02*
X410592Y220148D01*
G01X410664Y221390D02*
X410650Y221327D01*
G01X410671Y221259D02*
X410664Y221390D01*
G01X410678Y221024D02*
X410671Y221259D01*
G01X408945Y220412D02*
X408935Y220138D01*
G01X408951Y220429D02*
X408945Y220412D01*
G01X408956Y220365D02*
X408951Y220429D01*
G01X408944Y221390D02*
X408930Y221024D01*
G01X408951Y221412D02*
X408944Y221390D01*
G01X408958Y221327D02*
X408951Y221412D01*
G01X409022Y219853D02*
X409009Y220340D01*
G01X409028Y219464D02*
X409022Y219853D01*
G01X409033Y218993D02*
X409028Y219464D01*
G01X409038Y218453D02*
X409033Y218993D01*
G01X409041Y217857D02*
X409038Y218453D01*
G01X409043Y217224D02*
X409041Y217857D01*
G01X409043Y216570D02*
Y217224D01*
G01X409017Y219013D02*
X409007Y219379D01*
G01X409021Y218722D02*
X409017Y219013D01*
G01X409025Y218368D02*
X409021Y218722D01*
G01X409028Y217963D02*
X409025Y218368D01*
G01X409030Y217516D02*
X409028Y217963D01*
G01X409032Y217041D02*
X409030Y217516D01*
G01X409032Y216551D02*
Y217041D01*
G01X408945Y225965D02*
X408956Y226012D01*
G01X408940Y226063D02*
X408945Y225965D01*
G01X408935Y226239D02*
X408940Y226063D01*
G01X409030Y228861D02*
X409032Y229826D01*
G01X409028Y228414D02*
X409030Y228861D01*
G01X409025Y228009D02*
X409028Y228414D01*
G01X409021Y227656D02*
X409025Y228009D01*
G01X409017Y227364D02*
X409021Y227656D01*
G01X409012Y227143D02*
X409017Y227364D01*
G01X409007Y226999D02*
X409012Y227143D01*
G01X409041Y228520D02*
X409043Y229807D01*
G01X409038Y227925D02*
X409041Y228520D01*
G01X409033Y227384D02*
X409038Y227925D01*
G01X409028Y226913D02*
X409033Y227384D01*
G01X409022Y226524D02*
X409028Y226913D01*
G01X409016Y226230D02*
X409022Y226524D01*
G01X409009Y226037D02*
X409016Y226230D01*
G01X408944Y224988D02*
X408958Y225050D01*
G01X408937Y225118D02*
X408944Y224988D01*
G01X408930Y225353D02*
X408937Y225118D01*
G01X410663Y225965D02*
X410674Y226239D01*
G01X410658Y225948D02*
X410663Y225965D01*
G01X410652Y226012D02*
X410658Y225948D01*
G01X410664Y224988D02*
X410678Y225353D01*
G01X410657Y224965D02*
X410664Y224988D01*
G01X410650Y225050D02*
X410657Y224965D01*
G01X410586Y226524D02*
X410599Y226037D01*
G01X410580Y226913D02*
X410586Y226524D01*
G01X410575Y227384D02*
X410580Y226913D01*
G01X410571Y227925D02*
X410575Y227384D01*
G01X410568Y228520D02*
X410571Y227925D01*
G01X410566Y229153D02*
X410568Y228520D01*
G01X410565Y229807D02*
X410566Y229153D01*
G01X410592Y227364D02*
X410602Y226999D01*
G01X410587Y227656D02*
X410592Y227364D01*
G01X410583Y228009D02*
X410587Y227656D01*
G01X410580Y228414D02*
X410583Y228009D01*
G01X410578Y228861D02*
X410580Y228414D01*
G01X410576Y229336D02*
X410578Y228861D01*
G01X410576Y229826D02*
Y229336D01*
G01X406731Y225965D02*
X406741Y226239D01*
G01X406725Y225948D02*
X406731Y225965D01*
G01X406720Y226012D02*
X406725Y225948D01*
G01X406732Y224988D02*
X406746Y225353D01*
G01X406725Y224965D02*
X406732Y224988D01*
G01X406718Y225050D02*
X406725Y224965D01*
G01X406653Y226524D02*
X406667Y226037D01*
G01X406648Y226913D02*
X406653Y226524D01*
G01X406642Y227384D02*
X406648Y226913D01*
G01X406638Y227925D02*
X406642Y227384D01*
G01X406635Y228520D02*
X406638Y227925D01*
G01X406633Y229153D02*
X406635Y228520D01*
G01X406632Y229807D02*
X406633Y229153D01*
G01X406628Y231677D02*
X406620Y231750D01*
G01X406631Y231547D02*
X406628Y231677D01*
G01X406635Y231359D02*
X406631Y231547D01*
G01X406638Y231120D02*
X406635Y231359D01*
G01X406640Y230838D02*
X406638Y231120D01*
G01X406642Y230521D02*
X406640Y230838D01*
G01X406643Y230180D02*
X406642Y230521D01*
G01X406643Y229826D02*
Y230180D01*
G01X406659Y227364D02*
X406669Y226999D01*
G01X406655Y227656D02*
X406659Y227364D01*
G01X406651Y228009D02*
X406655Y227656D01*
G01X406648Y228414D02*
X406651Y228009D01*
G01X406645Y228861D02*
X406648Y228414D01*
G01X406644Y229336D02*
X406645Y228861D01*
G01X406643Y229826D02*
X406644Y229336D01*
G01X405013Y225965D02*
X405024Y226012D01*
G01X405007Y226063D02*
X405013Y225965D01*
G01X405002Y226239D02*
X405007Y226063D01*
G01X405098Y228861D02*
X405100Y229826D01*
G01X405096Y228414D02*
X405098Y228861D01*
G01X405093Y228009D02*
X405096Y228414D01*
G01X405089Y227656D02*
X405093Y228009D01*
G01X405084Y227364D02*
X405089Y227656D01*
G01X405079Y227143D02*
X405084Y227364D01*
G01X405074Y226999D02*
X405079Y227143D01*
G01X405102Y230521D02*
X405100Y229826D01*
G01X405103Y230838D02*
X405102Y230521D01*
G01X405106Y231120D02*
X405103Y230838D01*
G01X405109Y231359D02*
X405106Y231120D01*
G01X405112Y231547D02*
X405109Y231359D01*
G01X405116Y231677D02*
X405112Y231547D01*
G01X405120Y231746D02*
X405116Y231677D01*
G01X405124Y231750D02*
X405120Y231746D01*
G01X405108Y228520D02*
X405111Y229807D01*
G01X405105Y227925D02*
X405108Y228520D01*
G01X405101Y227384D02*
X405105Y227925D01*
G01X405096Y226913D02*
X405101Y227384D01*
G01X405090Y226524D02*
X405096Y226913D01*
G01X405084Y226230D02*
X405090Y226524D01*
G01X405077Y226037D02*
X405084Y226230D01*
G01X405012Y224988D02*
X405026Y225050D01*
G01X405004Y225118D02*
X405012Y224988D01*
G01X404998Y225353D02*
X405004Y225118D01*
G01X405003Y220412D02*
X404993Y220138D01*
G01X405009Y220429D02*
X405003Y220412D01*
G01X405014Y220365D02*
X405009Y220429D01*
G01X405002Y221390D02*
X404988Y221024D01*
G01X405009Y221412D02*
X405002Y221390D01*
G01X405017Y221327D02*
X405009Y221412D01*
G01X405081Y219853D02*
X405067Y220340D01*
G01X405087Y219464D02*
X405081Y219853D01*
G01X405092Y218993D02*
X405087Y219464D01*
G01X405096Y218453D02*
X405092Y218993D01*
G01X405099Y217857D02*
X405096Y218453D01*
G01X405101Y217224D02*
X405099Y217857D01*
G01X405102Y216570D02*
X405101Y217224D01*
G01X405107Y214700D02*
X405114Y214627D01*
G01X405103Y214830D02*
X405107Y214700D01*
G01X405099Y215018D02*
X405103Y214830D01*
G01X405097Y215257D02*
X405099Y215018D01*
G01X405094Y215540D02*
X405097Y215257D01*
G01X405092Y215857D02*
X405094Y215540D01*
G01X405091Y216198D02*
X405092Y215857D01*
G01X405091Y216551D02*
Y216198D01*
G01X405075Y219013D02*
X405065Y219379D01*
G01X405079Y218722D02*
X405075Y219013D01*
G01X405083Y218368D02*
X405079Y218722D01*
G01X405086Y217963D02*
X405083Y218368D01*
G01X405089Y217516D02*
X405086Y217963D01*
G01X405090Y217041D02*
X405089Y217516D01*
G01X405091Y216551D02*
X405090Y217041D01*
G01X406721Y220412D02*
X406711Y220365D01*
G01X406727Y220314D02*
X406721Y220412D01*
G01X406732Y220138D02*
X406727Y220314D01*
G01X406636Y217516D02*
X406634Y216551D01*
G01X406638Y217963D02*
X406636Y217516D01*
G01X406642Y218368D02*
X406638Y217963D01*
G01X406645Y218722D02*
X406642Y218368D01*
G01X406650Y219013D02*
X406645Y218722D01*
G01X406655Y219234D02*
X406650Y219013D01*
G01X406660Y219379D02*
X406655Y219234D01*
G01X406633Y215857D02*
X406634Y216551D01*
G01X406631Y215540D02*
X406633Y215857D01*
G01X406628Y215257D02*
X406631Y215540D01*
G01X406625Y215018D02*
X406628Y215257D01*
G01X406622Y214830D02*
X406625Y215018D01*
G01X406618Y214700D02*
X406622Y214830D01*
G01X406614Y214632D02*
X406618Y214700D01*
G01X406610Y214627D02*
X406614Y214632D01*
G01X406626Y217857D02*
X406623Y216570D01*
G01X406629Y218453D02*
X406626Y217857D01*
G01X406633Y218993D02*
X406629Y218453D01*
G01X406638Y219464D02*
X406633Y218993D01*
G01X406644Y219853D02*
X406638Y219464D01*
G01X406651Y220148D02*
X406644Y219853D01*
G01X406658Y220340D02*
X406651Y220148D01*
G01X406723Y221390D02*
X406708Y221327D01*
G01X406730Y221259D02*
X406723Y221390D01*
G01X406737Y221024D02*
X406730Y221259D01*
G01X401071Y225965D02*
X401082Y226012D01*
G01X401066Y226063D02*
X401071Y225965D01*
G01X401061Y226239D02*
X401066Y226063D01*
G01X401156Y228861D02*
X401158Y229826D01*
G01X401154Y228414D02*
X401156Y228861D01*
G01X401151Y228009D02*
X401154Y228414D01*
G01X401147Y227656D02*
X401151Y228009D01*
G01X401143Y227364D02*
X401147Y227656D01*
G01X401138Y227143D02*
X401143Y227364D01*
G01X401133Y226999D02*
X401138Y227143D01*
G01X401167Y228520D02*
X401169Y229807D01*
G01X401164Y227925D02*
X401167Y228520D01*
G01X401159Y227384D02*
X401164Y227925D01*
G01X401154Y226913D02*
X401159Y227384D01*
G01X401148Y226524D02*
X401154Y226913D01*
G01X401142Y226230D02*
X401148Y226524D01*
G01X401135Y226037D02*
X401142Y226230D01*
G01X401070Y224988D02*
X401084Y225050D01*
G01X401063Y225118D02*
X401070Y224988D01*
G01X401056Y225353D02*
X401063Y225118D01*
G01X402790Y224988D02*
X402804Y225353D01*
G01X402783Y224965D02*
X402790Y224988D01*
G01X402776Y225050D02*
X402783Y224965D01*
G01X402712Y226524D02*
X402725Y226037D01*
G01X402706Y226913D02*
X402712Y226524D01*
G01X402701Y227384D02*
X402706Y226913D01*
G01X402697Y227925D02*
X402701Y227384D01*
G01X402694Y228520D02*
X402697Y227925D01*
G01X402692Y229153D02*
X402694Y228520D01*
G01X402691Y229807D02*
X402692Y229153D01*
G01X402718Y227364D02*
X402728Y226999D01*
G01X402713Y227656D02*
X402718Y227364D01*
G01X402709Y228009D02*
X402713Y227656D01*
G01X402706Y228414D02*
X402709Y228009D01*
G01X402704Y228861D02*
X402706Y228414D01*
G01X402702Y229336D02*
X402704Y228861D01*
G01X402702Y229826D02*
Y229336D01*
G01X402789Y225965D02*
X402799Y226239D01*
G01X402784Y225948D02*
X402789Y225965D01*
G01X402778Y226012D02*
X402784Y225948D01*
G01X402789Y220412D02*
X402778Y220365D01*
G01X402794Y220314D02*
X402789Y220412D01*
G01X402799Y220138D02*
X402794Y220314D01*
G01X402704Y217516D02*
X402702Y216551D01*
G01X402706Y217963D02*
X402704Y217516D01*
G01X402709Y218368D02*
X402706Y217963D01*
G01X402713Y218722D02*
X402709Y218368D01*
G01X402718Y219013D02*
X402713Y218722D01*
G01X402722Y219234D02*
X402718Y219013D01*
G01X402728Y219379D02*
X402722Y219234D01*
G01X402694Y217857D02*
X402691Y216570D01*
G01X402697Y218453D02*
X402694Y217857D01*
G01X402701Y218993D02*
X402697Y218453D01*
G01X402706Y219464D02*
X402701Y218993D01*
G01X402712Y219853D02*
X402706Y219464D01*
G01X402718Y220148D02*
X402712Y219853D01*
G01X402725Y220340D02*
X402718Y220148D01*
G01X402790Y221390D02*
X402776Y221327D01*
G01X402797Y221259D02*
X402790Y221390D01*
G01X402804Y221024D02*
X402797Y221259D01*
G01X401070Y221390D02*
X401056Y221024D01*
G01X401077Y221412D02*
X401070Y221390D01*
G01X401084Y221327D02*
X401077Y221412D01*
G01X401148Y219853D02*
X401135Y220340D01*
G01X401154Y219464D02*
X401148Y219853D01*
G01X401159Y218993D02*
X401154Y219464D01*
G01X401164Y218453D02*
X401159Y218993D01*
G01X401167Y217857D02*
X401164Y218453D01*
G01X401169Y217224D02*
X401167Y217857D01*
G01X401169Y216570D02*
Y217224D01*
G01X401143Y219013D02*
X401133Y219379D01*
G01X401147Y218722D02*
X401143Y219013D01*
G01X401151Y218368D02*
X401147Y218722D01*
G01X401154Y217963D02*
X401151Y218368D01*
G01X401156Y217516D02*
X401154Y217963D01*
G01X401158Y217041D02*
X401156Y217516D01*
G01X401158Y216551D02*
Y217041D01*
G01X401071Y220412D02*
X401061Y220138D01*
G01X401077Y220429D02*
X401071Y220412D01*
G01X401082Y220365D02*
X401077Y220429D01*
G01X397139Y225965D02*
X397150Y226012D01*
G01X397133Y226063D02*
X397139Y225965D01*
G01X397128Y226239D02*
X397133Y226063D01*
G01X397224Y228861D02*
X397226Y229826D01*
G01X397222Y228414D02*
X397224Y228861D01*
G01X397219Y228009D02*
X397222Y228414D01*
G01X397215Y227656D02*
X397219Y228009D01*
G01X397210Y227364D02*
X397215Y227656D01*
G01X397205Y227143D02*
X397210Y227364D01*
G01X397200Y226999D02*
X397205Y227143D01*
G01X397228Y230521D02*
X397226Y229826D01*
G01X397229Y230838D02*
X397228Y230521D01*
G01X397232Y231120D02*
X397229Y230838D01*
G01X397235Y231359D02*
X397232Y231120D01*
G01X397238Y231547D02*
X397235Y231359D01*
G01X397242Y231677D02*
X397238Y231547D01*
G01X397246Y231746D02*
X397242Y231677D01*
G01X397250Y231750D02*
X397246Y231746D01*
G01X397234Y228520D02*
X397237Y229807D01*
G01X397231Y227925D02*
X397234Y228520D01*
G01X397227Y227384D02*
X397231Y227925D01*
G01X397222Y226913D02*
X397227Y227384D01*
G01X397216Y226524D02*
X397222Y226913D01*
G01X397210Y226230D02*
X397216Y226524D01*
G01X397203Y226037D02*
X397210Y226230D01*
G01X397138Y224988D02*
X397152Y225050D01*
G01X397130Y225118D02*
X397138Y224988D01*
G01X397124Y225353D02*
X397130Y225118D01*
G01X398858Y224988D02*
X398872Y225353D01*
G01X398851Y224965D02*
X398858Y224988D01*
G01X398843Y225050D02*
X398851Y224965D01*
G01X398779Y226524D02*
X398793Y226037D01*
G01X398774Y226913D02*
X398779Y226524D01*
G01X398768Y227384D02*
X398774Y226913D01*
G01X398764Y227925D02*
X398768Y227384D01*
G01X398761Y228520D02*
X398764Y227925D01*
G01X398759Y229153D02*
X398761Y228520D01*
G01X398758Y229807D02*
X398759Y229153D01*
G01X398754Y231677D02*
X398746Y231750D01*
G01X398757Y231547D02*
X398754Y231677D01*
G01X398761Y231359D02*
X398757Y231547D01*
G01X398764Y231120D02*
X398761Y231359D01*
G01X398766Y230838D02*
X398764Y231120D01*
G01X398768Y230521D02*
X398766Y230838D01*
G01X398769Y230180D02*
X398768Y230521D01*
G01X398769Y229826D02*
Y230180D01*
G01X398785Y227364D02*
X398795Y226999D01*
G01X398781Y227656D02*
X398785Y227364D01*
G01X398777Y228009D02*
X398781Y227656D01*
G01X398774Y228414D02*
X398777Y228009D01*
G01X398771Y228861D02*
X398774Y228414D01*
G01X398770Y229336D02*
X398771Y228861D01*
G01X398769Y229826D02*
X398770Y229336D01*
G01X398857Y225965D02*
X398867Y226239D01*
G01X398851Y225948D02*
X398857Y225965D01*
G01X398846Y226012D02*
X398851Y225948D01*
G01X398847Y220412D02*
X398836Y220365D01*
G01X398853Y220314D02*
X398847Y220412D01*
G01X398858Y220138D02*
X398853Y220314D01*
G01X398762Y217516D02*
X398760Y216551D01*
G01X398764Y217963D02*
X398762Y217516D01*
G01X398768Y218368D02*
X398764Y217963D01*
G01X398771Y218722D02*
X398768Y218368D01*
G01X398776Y219013D02*
X398771Y218722D01*
G01X398781Y219234D02*
X398776Y219013D01*
G01X398786Y219379D02*
X398781Y219234D01*
G01X398759Y215857D02*
X398760Y216551D01*
G01X398757Y215540D02*
X398759Y215857D01*
G01X398754Y215257D02*
X398757Y215540D01*
G01X398751Y215018D02*
X398754Y215257D01*
G01X398748Y214830D02*
X398751Y215018D01*
G01X398744Y214700D02*
X398748Y214830D01*
G01X398740Y214632D02*
X398744Y214700D01*
G01X398736Y214627D02*
X398740Y214632D01*
G01X398752Y217857D02*
X398749Y216570D01*
G01X398755Y218453D02*
X398752Y217857D01*
G01X398759Y218993D02*
X398755Y218453D01*
G01X398764Y219464D02*
X398759Y218993D01*
G01X398770Y219853D02*
X398764Y219464D01*
G01X398777Y220148D02*
X398770Y219853D01*
G01X398784Y220340D02*
X398777Y220148D01*
G01X398849Y221390D02*
X398834Y221327D01*
G01X398856Y221259D02*
X398849Y221390D01*
G01X398863Y221024D02*
X398856Y221259D01*
G01X397128Y221390D02*
X397114Y221024D01*
G01X397135Y221412D02*
X397128Y221390D01*
G01X397143Y221327D02*
X397135Y221412D01*
G01X397207Y219853D02*
X397193Y220340D01*
G01X397213Y219464D02*
X397207Y219853D01*
G01X397218Y218993D02*
X397213Y219464D01*
G01X397222Y218453D02*
X397218Y218993D01*
G01X397225Y217857D02*
X397222Y218453D01*
G01X397227Y217224D02*
X397225Y217857D01*
G01X397228Y216570D02*
X397227Y217224D01*
G01X397233Y214700D02*
X397240Y214627D01*
G01X397229Y214830D02*
X397233Y214700D01*
G01X397225Y215018D02*
X397229Y214830D01*
G01X397223Y215257D02*
X397225Y215018D01*
G01X397220Y215540D02*
X397223Y215257D01*
G01X397218Y215857D02*
X397220Y215540D01*
G01X397217Y216198D02*
X397218Y215857D01*
G01X397217Y216551D02*
Y216198D01*
G01X397201Y219013D02*
X397191Y219379D01*
G01X397205Y218722D02*
X397201Y219013D01*
G01X397209Y218368D02*
X397205Y218722D01*
G01X397212Y217963D02*
X397209Y218368D01*
G01X397215Y217516D02*
X397212Y217963D01*
G01X397216Y217041D02*
X397215Y217516D01*
G01X397217Y216551D02*
X397216Y217041D01*
G01X397129Y220412D02*
X397119Y220138D01*
G01X397135Y220429D02*
X397129Y220412D01*
G01X397140Y220365D02*
X397135Y220429D01*
G01X393197Y225965D02*
X393208Y226012D01*
G01X393192Y226063D02*
X393197Y225965D01*
G01X393187Y226239D02*
X393192Y226063D01*
G01X393282Y228861D02*
X393284Y229826D01*
G01X393280Y228414D02*
X393282Y228861D01*
G01X393277Y228009D02*
X393280Y228414D01*
G01X393273Y227656D02*
X393277Y228009D01*
G01X393269Y227364D02*
X393273Y227656D01*
G01X393264Y227143D02*
X393269Y227364D01*
G01X393258Y226999D02*
X393264Y227143D01*
G01X393293Y228520D02*
X393295Y229807D01*
G01X393290Y227925D02*
X393293Y228520D01*
G01X393285Y227384D02*
X393290Y227925D01*
G01X393280Y226913D02*
X393285Y227384D01*
G01X393274Y226524D02*
X393280Y226913D01*
G01X393268Y226230D02*
X393274Y226524D01*
G01X393261Y226037D02*
X393268Y226230D01*
G01X393196Y224988D02*
X393210Y225050D01*
G01X393189Y225118D02*
X393196Y224988D01*
G01X393182Y225353D02*
X393189Y225118D01*
G01X394916Y224988D02*
X394930Y225353D01*
G01X394909Y224965D02*
X394916Y224988D01*
G01X394902Y225050D02*
X394909Y224965D01*
G01X394838Y226524D02*
X394851Y226037D01*
G01X394832Y226913D02*
X394838Y226524D01*
G01X394827Y227384D02*
X394832Y226913D01*
G01X394823Y227925D02*
X394827Y227384D01*
G01X394819Y228520D02*
X394823Y227925D01*
G01X394818Y229153D02*
X394819Y228520D01*
G01X394817Y229807D02*
X394818Y229153D01*
G01X394844Y227364D02*
X394854Y226999D01*
G01X394839Y227656D02*
X394844Y227364D01*
G01X394835Y228009D02*
X394839Y227656D01*
G01X394832Y228414D02*
X394835Y228009D01*
G01X394830Y228861D02*
X394832Y228414D01*
G01X394828Y229336D02*
X394830Y228861D01*
G01X394828Y229826D02*
Y229336D01*
G01X394915Y225965D02*
X394925Y226239D01*
G01X394910Y225948D02*
X394915Y225965D01*
G01X394904Y226012D02*
X394910Y225948D01*
G01X394915Y220412D02*
X394904Y220365D01*
G01X394920Y220314D02*
X394915Y220412D01*
G01X394925Y220138D02*
X394920Y220314D01*
G01X394830Y217516D02*
X394828Y216551D01*
G01X394832Y217963D02*
X394830Y217516D01*
G01X394835Y218368D02*
X394832Y217963D01*
G01X394839Y218722D02*
X394835Y218368D01*
G01X394844Y219013D02*
X394839Y218722D01*
G01X394848Y219234D02*
X394844Y219013D01*
G01X394854Y219379D02*
X394848Y219234D01*
G01X394819Y217857D02*
X394817Y216570D01*
G01X394823Y218453D02*
X394819Y217857D01*
G01X394827Y218993D02*
X394823Y218453D01*
G01X394832Y219464D02*
X394827Y218993D01*
G01X394838Y219853D02*
X394832Y219464D01*
G01X394844Y220148D02*
X394838Y219853D01*
G01X394851Y220340D02*
X394844Y220148D01*
G01X394916Y221390D02*
X394902Y221327D01*
G01X394923Y221259D02*
X394916Y221390D01*
G01X394930Y221024D02*
X394923Y221259D01*
G01X393196Y221390D02*
X393182Y221024D01*
G01X393203Y221412D02*
X393196Y221390D01*
G01X393210Y221327D02*
X393203Y221412D01*
G01X393274Y219853D02*
X393261Y220340D01*
G01X393280Y219464D02*
X393274Y219853D01*
G01X393285Y218993D02*
X393280Y219464D01*
G01X393290Y218453D02*
X393285Y218993D01*
G01X393293Y217857D02*
X393290Y218453D01*
G01X393295Y217224D02*
X393293Y217857D01*
G01X393295Y216570D02*
Y217224D01*
G01X393269Y219013D02*
X393258Y219379D01*
G01X393273Y218722D02*
X393269Y219013D01*
G01X393277Y218368D02*
X393273Y218722D01*
G01X393280Y217963D02*
X393277Y218368D01*
G01X393282Y217516D02*
X393280Y217963D01*
G01X393284Y217041D02*
X393282Y217516D01*
G01X393284Y216551D02*
Y217041D01*
G01X393197Y220412D02*
X393187Y220138D01*
G01X393203Y220429D02*
X393197Y220412D01*
G01X393208Y220365D02*
X393203Y220429D01*
G01X389265Y225965D02*
X389276Y226012D01*
G01X389259Y226063D02*
X389265Y225965D01*
G01X389254Y226239D02*
X389259Y226063D01*
G01X389350Y228861D02*
X389352Y229826D01*
G01X389348Y228414D02*
X389350Y228861D01*
G01X389345Y228009D02*
X389348Y228414D01*
G01X389341Y227656D02*
X389345Y228009D01*
G01X389336Y227364D02*
X389341Y227656D01*
G01X389331Y227143D02*
X389336Y227364D01*
G01X389326Y226999D02*
X389331Y227143D01*
G01X389354Y230521D02*
X389352Y229826D01*
G01X389355Y230838D02*
X389354Y230521D01*
G01X389358Y231120D02*
X389355Y230838D01*
G01X389361Y231359D02*
X389358Y231120D01*
G01X389364Y231547D02*
X389361Y231359D01*
G01X389368Y231677D02*
X389364Y231547D01*
G01X389372Y231746D02*
X389368Y231677D01*
G01X389376Y231750D02*
X389372Y231746D01*
G01X389360Y228520D02*
X389363Y229807D01*
G01X389357Y227925D02*
X389360Y228520D01*
G01X389353Y227384D02*
X389357Y227925D01*
G01X389348Y226913D02*
X389353Y227384D01*
G01X389342Y226524D02*
X389348Y226913D01*
G01X389335Y226230D02*
X389342Y226524D01*
G01X389328Y226037D02*
X389335Y226230D01*
G01X389263Y224988D02*
X389278Y225050D01*
G01X389256Y225118D02*
X389263Y224988D01*
G01X389250Y225353D02*
X389256Y225118D01*
G01X390984Y224988D02*
X390998Y225353D01*
G01X390977Y224965D02*
X390984Y224988D01*
G01X390969Y225050D02*
X390977Y224965D01*
G01X390905Y226524D02*
X390919Y226037D01*
G01X390900Y226913D02*
X390905Y226524D01*
G01X390894Y227384D02*
X390900Y226913D01*
G01X390890Y227925D02*
X390894Y227384D01*
G01X390887Y228520D02*
X390890Y227925D01*
G01X390885Y229153D02*
X390887Y228520D01*
G01X390884Y229807D02*
X390885Y229153D01*
G01X390880Y231677D02*
X390872Y231750D01*
G01X390883Y231547D02*
X390880Y231677D01*
G01X390887Y231359D02*
X390883Y231547D01*
G01X390890Y231120D02*
X390887Y231359D01*
G01X390892Y230838D02*
X390890Y231120D01*
G01X390894Y230521D02*
X390892Y230838D01*
G01X390895Y230180D02*
X390894Y230521D01*
G01X390895Y229826D02*
Y230180D01*
G01X390911Y227364D02*
X390921Y226999D01*
G01X390907Y227656D02*
X390911Y227364D01*
G01X390903Y228009D02*
X390907Y227656D01*
G01X390900Y228414D02*
X390903Y228009D01*
G01X390897Y228861D02*
X390900Y228414D01*
G01X390896Y229336D02*
X390897Y228861D01*
G01X390895Y229826D02*
X390896Y229336D01*
G01X390983Y225965D02*
X390993Y226239D01*
G01X390977Y225948D02*
X390983Y225965D01*
G01X390972Y226012D02*
X390977Y225948D01*
G01X390973Y220412D02*
X390962Y220365D01*
G01X390979Y220314D02*
X390973Y220412D01*
G01X390984Y220138D02*
X390979Y220314D01*
G01X390888Y217516D02*
X390886Y216551D01*
G01X390890Y217963D02*
X390888Y217516D01*
G01X390894Y218368D02*
X390890Y217963D01*
G01X390897Y218722D02*
X390894Y218368D01*
G01X390902Y219013D02*
X390897Y218722D01*
G01X390907Y219234D02*
X390902Y219013D01*
G01X390912Y219379D02*
X390907Y219234D01*
G01X390885Y215857D02*
X390886Y216551D01*
G01X390883Y215540D02*
X390885Y215857D01*
G01X390880Y215257D02*
X390883Y215540D01*
G01X390877Y215018D02*
X390880Y215257D01*
G01X390874Y214830D02*
X390877Y215018D01*
G01X390870Y214700D02*
X390874Y214830D01*
G01X390866Y214632D02*
X390870Y214700D01*
G01X390862Y214627D02*
X390866Y214632D01*
G01X390878Y217857D02*
X390875Y216570D01*
G01X390881Y218453D02*
X390878Y217857D01*
G01X390885Y218993D02*
X390881Y218453D01*
G01X390890Y219464D02*
X390885Y218993D01*
G01X390896Y219853D02*
X390890Y219464D01*
G01X390903Y220148D02*
X390896Y219853D01*
G01X390910Y220340D02*
X390903Y220148D01*
G01X390975Y221390D02*
X390960Y221327D01*
G01X390982Y221259D02*
X390975Y221390D01*
G01X390989Y221024D02*
X390982Y221259D01*
G01X389254Y221390D02*
X389240Y221024D01*
G01X389261Y221412D02*
X389254Y221390D01*
G01X389269Y221327D02*
X389261Y221412D01*
G01X389333Y219853D02*
X389319Y220340D01*
G01X389339Y219464D02*
X389333Y219853D01*
G01X389344Y218993D02*
X389339Y219464D01*
G01X389348Y218453D02*
X389344Y218993D01*
G01X389351Y217857D02*
X389348Y218453D01*
G01X389353Y217224D02*
X389351Y217857D01*
G01X389354Y216570D02*
X389353Y217224D01*
G01X389359Y214700D02*
X389366Y214627D01*
G01X389355Y214830D02*
X389359Y214700D01*
G01X389351Y215018D02*
X389355Y214830D01*
G01X389349Y215257D02*
X389351Y215018D01*
G01X389346Y215540D02*
X389349Y215257D01*
G01X389344Y215857D02*
X389346Y215540D01*
G01X389343Y216198D02*
X389344Y215857D01*
G01X389343Y216551D02*
Y216198D01*
G01X389327Y219013D02*
X389317Y219379D01*
G01X389331Y218722D02*
X389327Y219013D01*
G01X389335Y218368D02*
X389331Y218722D01*
G01X389338Y217963D02*
X389335Y218368D01*
G01X389341Y217516D02*
X389338Y217963D01*
G01X389342Y217041D02*
X389341Y217516D01*
G01X389343Y216551D02*
X389342Y217041D01*
G01X389255Y220412D02*
X389245Y220138D01*
G01X389261Y220429D02*
X389255Y220412D01*
G01X389266Y220365D02*
X389261Y220429D01*
G01X385323Y225965D02*
X385334Y226012D01*
G01X385318Y226063D02*
X385323Y225965D01*
G01X385313Y226239D02*
X385318Y226063D01*
G01X385408Y228861D02*
X385410Y229826D01*
G01X385406Y228414D02*
X385408Y228861D01*
G01X385403Y228009D02*
X385406Y228414D01*
G01X385399Y227656D02*
X385403Y228009D01*
G01X385395Y227364D02*
X385399Y227656D01*
G01X385390Y227143D02*
X385395Y227364D01*
G01X385384Y226999D02*
X385390Y227143D01*
G01X385419Y228520D02*
X385421Y229807D01*
G01X385416Y227925D02*
X385419Y228520D01*
G01X385411Y227384D02*
X385416Y227925D01*
G01X385406Y226913D02*
X385411Y227384D01*
G01X385400Y226524D02*
X385406Y226913D01*
G01X385394Y226230D02*
X385400Y226524D01*
G01X385387Y226037D02*
X385394Y226230D01*
G01X385322Y224988D02*
X385336Y225050D01*
G01X385315Y225118D02*
X385322Y224988D01*
G01X385308Y225353D02*
X385315Y225118D01*
G01X387041Y225965D02*
X387051Y226239D01*
G01X387036Y225948D02*
X387041Y225965D01*
G01X387030Y226012D02*
X387036Y225948D01*
G01X387042Y224988D02*
X387056Y225353D01*
G01X387035Y224965D02*
X387042Y224988D01*
G01X387028Y225050D02*
X387035Y224965D01*
G01X386964Y226524D02*
X386977Y226037D01*
G01X386958Y226913D02*
X386964Y226524D01*
G01X386953Y227384D02*
X386958Y226913D01*
G01X386949Y227925D02*
X386953Y227384D01*
G01X386945Y228520D02*
X386949Y227925D01*
G01X386944Y229153D02*
X386945Y228520D01*
G01X386943Y229807D02*
X386944Y229153D01*
G01X386969Y227364D02*
X386980Y226999D01*
G01X386965Y227656D02*
X386969Y227364D01*
G01X386961Y228009D02*
X386965Y227656D01*
G01X386958Y228414D02*
X386961Y228009D01*
G01X386956Y228861D02*
X386958Y228414D01*
G01X386954Y229336D02*
X386956Y228861D01*
G01X386954Y229826D02*
Y229336D01*
G01X387041Y220412D02*
X387030Y220365D01*
G01X387046Y220314D02*
X387041Y220412D01*
G01X387051Y220138D02*
X387046Y220314D01*
G01X386956Y217516D02*
X386954Y216551D01*
G01X386958Y217963D02*
X386956Y217516D01*
G01X386961Y218368D02*
X386958Y217963D01*
G01X386965Y218722D02*
X386961Y218368D01*
G01X386969Y219013D02*
X386965Y218722D01*
G01X386974Y219234D02*
X386969Y219013D01*
G01X386980Y219379D02*
X386974Y219234D01*
G01X386945Y217857D02*
X386943Y216570D01*
G01X386949Y218453D02*
X386945Y217857D01*
G01X386953Y218993D02*
X386949Y218453D01*
G01X386958Y219464D02*
X386953Y218993D01*
G01X386964Y219853D02*
X386958Y219464D01*
G01X386970Y220148D02*
X386964Y219853D01*
G01X386977Y220340D02*
X386970Y220148D01*
G01X387042Y221390D02*
X387028Y221327D01*
G01X387049Y221259D02*
X387042Y221390D01*
G01X387056Y221024D02*
X387049Y221259D01*
G01X385323Y220412D02*
X385313Y220138D01*
G01X385329Y220429D02*
X385323Y220412D01*
G01X385334Y220365D02*
X385329Y220429D01*
G01X385322Y221390D02*
X385308Y221024D01*
G01X385329Y221412D02*
X385322Y221390D01*
G01X385336Y221327D02*
X385329Y221412D01*
G01X385400Y219853D02*
X385387Y220340D01*
G01X385406Y219464D02*
X385400Y219853D01*
G01X385411Y218993D02*
X385406Y219464D01*
G01X385416Y218453D02*
X385411Y218993D01*
G01X385419Y217857D02*
X385416Y218453D01*
G01X385421Y217224D02*
X385419Y217857D01*
G01X385421Y216570D02*
Y217224D01*
G01X385395Y219013D02*
X385384Y219379D01*
G01X385399Y218722D02*
X385395Y219013D01*
G01X385403Y218368D02*
X385399Y218722D01*
G01X385406Y217963D02*
X385403Y218368D01*
G01X385408Y217516D02*
X385406Y217963D01*
G01X385410Y217041D02*
X385408Y217516D01*
G01X385410Y216551D02*
Y217041D01*
G01X383109Y225965D02*
X383119Y226239D01*
G01X383103Y225948D02*
X383109Y225965D01*
G01X383098Y226012D02*
X383103Y225948D01*
G01X383110Y224988D02*
X383124Y225353D01*
G01X383103Y224965D02*
X383110Y224988D01*
G01X383095Y225050D02*
X383103Y224965D01*
G01X383031Y226524D02*
X383045Y226037D01*
G01X383026Y226913D02*
X383031Y226524D01*
G01X383020Y227384D02*
X383026Y226913D01*
G01X383016Y227925D02*
X383020Y227384D01*
G01X383013Y228520D02*
X383016Y227925D01*
G01X383011Y229153D02*
X383013Y228520D01*
G01X383010Y229807D02*
X383011Y229153D01*
G01X383006Y231677D02*
X382998Y231750D01*
G01X383009Y231547D02*
X383006Y231677D01*
G01X383013Y231359D02*
X383009Y231547D01*
G01X383016Y231120D02*
X383013Y231359D01*
G01X383018Y230838D02*
X383016Y231120D01*
G01X383020Y230521D02*
X383018Y230838D01*
G01X383021Y230180D02*
X383020Y230521D01*
G01X383021Y229826D02*
Y230180D01*
G01X383037Y227364D02*
X383047Y226999D01*
G01X383033Y227656D02*
X383037Y227364D01*
G01X383029Y228009D02*
X383033Y227656D01*
G01X383026Y228414D02*
X383029Y228009D01*
G01X383023Y228861D02*
X383026Y228414D01*
G01X383022Y229336D02*
X383023Y228861D01*
G01X383021Y229826D02*
X383022Y229336D01*
G01X381391Y225965D02*
X381402Y226012D01*
G01X381385Y226063D02*
X381391Y225965D01*
G01X381380Y226239D02*
X381385Y226063D01*
G01X381476Y228861D02*
X381478Y229826D01*
G01X381474Y228414D02*
X381476Y228861D01*
G01X381471Y228009D02*
X381474Y228414D01*
G01X381467Y227656D02*
X381471Y228009D01*
G01X381462Y227364D02*
X381467Y227656D01*
G01X381457Y227143D02*
X381462Y227364D01*
G01X381452Y226999D02*
X381457Y227143D01*
G01X381480Y230521D02*
X381478Y229826D01*
G01X381481Y230838D02*
X381480Y230521D01*
G01X381484Y231120D02*
X381481Y230838D01*
G01X381487Y231359D02*
X381484Y231120D01*
G01X381490Y231547D02*
X381487Y231359D01*
G01X381494Y231677D02*
X381490Y231547D01*
G01X381498Y231746D02*
X381494Y231677D01*
G01X381502Y231750D02*
X381498Y231746D01*
G01X381486Y228520D02*
X381489Y229807D01*
G01X381483Y227925D02*
X381486Y228520D01*
G01X381479Y227384D02*
X381483Y227925D01*
G01X381474Y226913D02*
X381479Y227384D01*
G01X381468Y226524D02*
X381474Y226913D01*
G01X381461Y226230D02*
X381468Y226524D01*
G01X381454Y226037D02*
X381461Y226230D01*
G01X381389Y224988D02*
X381404Y225050D01*
G01X381382Y225118D02*
X381389Y224988D01*
G01X381376Y225353D02*
X381382Y225118D01*
G01X381381Y220412D02*
X381371Y220138D01*
G01X381387Y220429D02*
X381381Y220412D01*
G01X381392Y220365D02*
X381387Y220429D01*
G01X381380Y221390D02*
X381366Y221024D01*
G01X381387Y221412D02*
X381380Y221390D01*
G01X381395Y221327D02*
X381387Y221412D01*
G01X381459Y219853D02*
X381445Y220340D01*
G01X381465Y219464D02*
X381459Y219853D01*
G01X381470Y218993D02*
X381465Y219464D01*
G01X381474Y218453D02*
X381470Y218993D01*
G01X381477Y217857D02*
X381474Y218453D01*
G01X381479Y217224D02*
X381477Y217857D01*
G01X381480Y216570D02*
X381479Y217224D01*
G01X381484Y214700D02*
X381492Y214627D01*
G01X381481Y214830D02*
X381484Y214700D01*
G01X381477Y215018D02*
X381481Y214830D01*
G01X381474Y215257D02*
X381477Y215018D01*
G01X381472Y215540D02*
X381474Y215257D01*
G01X381470Y215857D02*
X381472Y215540D01*
G01X381469Y216198D02*
X381470Y215857D01*
G01X381469Y216551D02*
Y216198D01*
G01X381453Y219013D02*
X381443Y219379D01*
G01X381457Y218722D02*
X381453Y219013D01*
G01X381461Y218368D02*
X381457Y218722D01*
G01X381464Y217963D02*
X381461Y218368D01*
G01X381467Y217516D02*
X381464Y217963D01*
G01X381468Y217041D02*
X381467Y217516D01*
G01X381469Y216551D02*
X381468Y217041D01*
G01X383099Y220412D02*
X383088Y220365D01*
G01X383105Y220314D02*
X383099Y220412D01*
G01X383110Y220138D02*
X383105Y220314D01*
G01X383014Y217516D02*
X383012Y216551D01*
G01X383016Y217963D02*
X383014Y217516D01*
G01X383020Y218368D02*
X383016Y217963D01*
G01X383023Y218722D02*
X383020Y218368D01*
G01X383028Y219013D02*
X383023Y218722D01*
G01X383033Y219234D02*
X383028Y219013D01*
G01X383038Y219379D02*
X383033Y219234D01*
G01X383010Y215857D02*
X383012Y216551D01*
G01X383009Y215540D02*
X383010Y215857D01*
G01X383006Y215257D02*
X383009Y215540D01*
G01X383003Y215018D02*
X383006Y215257D01*
G01X383000Y214830D02*
X383003Y215018D01*
G01X382996Y214700D02*
X383000Y214830D01*
G01X382992Y214632D02*
X382996Y214700D01*
G01X382988Y214627D02*
X382992Y214632D01*
G01X383004Y217857D02*
X383001Y216570D01*
G01X383007Y218453D02*
X383004Y217857D01*
G01X383011Y218993D02*
X383007Y218453D01*
G01X383016Y219464D02*
X383011Y218993D01*
G01X383022Y219853D02*
X383016Y219464D01*
G01X383029Y220148D02*
X383022Y219853D01*
G01X383036Y220340D02*
X383029Y220148D01*
G01X383101Y221390D02*
X383086Y221327D01*
G01X383108Y221259D02*
X383101Y221390D01*
G01X383115Y221024D02*
X383108Y221259D01*
G01X377449Y225965D02*
X377460Y226012D01*
G01X377444Y226063D02*
X377449Y225965D01*
G01X377439Y226239D02*
X377444Y226063D01*
G01X377534Y228861D02*
X377536Y229826D01*
G01X377532Y228414D02*
X377534Y228861D01*
G01X377529Y228009D02*
X377532Y228414D01*
G01X377525Y227656D02*
X377529Y228009D01*
G01X377521Y227364D02*
X377525Y227656D01*
G01X377516Y227143D02*
X377521Y227364D01*
G01X377510Y226999D02*
X377516Y227143D01*
G01X377545Y228520D02*
X377547Y229807D01*
G01X377542Y227925D02*
X377545Y228520D01*
G01X377537Y227384D02*
X377542Y227925D01*
G01X377532Y226913D02*
X377537Y227384D01*
G01X377526Y226524D02*
X377532Y226913D01*
G01X377520Y226230D02*
X377526Y226524D01*
G01X377513Y226037D02*
X377520Y226230D01*
G01X377448Y224988D02*
X377462Y225050D01*
G01X377441Y225118D02*
X377448Y224988D01*
G01X377434Y225353D02*
X377441Y225118D01*
G01X379167Y225965D02*
X379177Y226239D01*
G01X379162Y225948D02*
X379167Y225965D01*
G01X379156Y226012D02*
X379162Y225948D01*
G01X379168Y224988D02*
X379182Y225353D01*
G01X379161Y224965D02*
X379168Y224988D01*
G01X379154Y225050D02*
X379161Y224965D01*
G01X379090Y226524D02*
X379103Y226037D01*
G01X379084Y226913D02*
X379090Y226524D01*
G01X379079Y227384D02*
X379084Y226913D01*
G01X379075Y227925D02*
X379079Y227384D01*
G01X379071Y228520D02*
X379075Y227925D01*
G01X379070Y229153D02*
X379071Y228520D01*
G01X379069Y229807D02*
X379070Y229153D01*
G01X379095Y227364D02*
X379106Y226999D01*
G01X379091Y227656D02*
X379095Y227364D01*
G01X379087Y228009D02*
X379091Y227656D01*
G01X379084Y228414D02*
X379087Y228009D01*
G01X379082Y228861D02*
X379084Y228414D01*
G01X379080Y229336D02*
X379082Y228861D01*
G01X379080Y229826D02*
Y229336D01*
G01X379167Y220412D02*
X379156Y220365D01*
G01X379172Y220314D02*
X379167Y220412D01*
G01X379177Y220138D02*
X379172Y220314D01*
G01X379082Y217516D02*
X379080Y216551D01*
G01X379084Y217963D02*
X379082Y217516D01*
G01X379087Y218368D02*
X379084Y217963D01*
G01X379091Y218722D02*
X379087Y218368D01*
G01X379095Y219013D02*
X379091Y218722D01*
G01X379100Y219234D02*
X379095Y219013D01*
G01X379106Y219379D02*
X379100Y219234D01*
G01X379071Y217857D02*
X379069Y216570D01*
G01X379075Y218453D02*
X379071Y217857D01*
G01X379079Y218993D02*
X379075Y218453D01*
G01X379084Y219464D02*
X379079Y218993D01*
G01X379090Y219853D02*
X379084Y219464D01*
G01X379096Y220148D02*
X379090Y219853D01*
G01X379103Y220340D02*
X379096Y220148D01*
G01X379168Y221390D02*
X379154Y221327D01*
G01X379175Y221259D02*
X379168Y221390D01*
G01X379182Y221024D02*
X379175Y221259D01*
G01X377449Y220412D02*
X377439Y220138D01*
G01X377455Y220429D02*
X377449Y220412D01*
G01X377460Y220365D02*
X377455Y220429D01*
G01X377448Y221390D02*
X377434Y221024D01*
G01X377455Y221412D02*
X377448Y221390D01*
G01X377462Y221327D02*
X377455Y221412D01*
G01X377526Y219853D02*
X377513Y220340D01*
G01X377532Y219464D02*
X377526Y219853D01*
G01X377537Y218993D02*
X377532Y219464D01*
G01X377542Y218453D02*
X377537Y218993D01*
G01X377545Y217857D02*
X377542Y218453D01*
G01X377547Y217224D02*
X377545Y217857D01*
G01X377547Y216570D02*
Y217224D01*
G01X377521Y219013D02*
X377510Y219379D01*
G01X377525Y218722D02*
X377521Y219013D01*
G01X377529Y218368D02*
X377525Y218722D01*
G01X377532Y217963D02*
X377529Y218368D01*
G01X377534Y217516D02*
X377532Y217963D01*
G01X377536Y217041D02*
X377534Y217516D01*
G01X377536Y216551D02*
Y217041D01*
G01X375235Y225965D02*
X375245Y226239D01*
G01X375229Y225948D02*
X375235Y225965D01*
G01X375224Y226012D02*
X375229Y225948D01*
G01X375236Y224988D02*
X375250Y225353D01*
G01X375229Y224965D02*
X375236Y224988D01*
G01X375221Y225050D02*
X375229Y224965D01*
G01X375157Y226524D02*
X375171Y226037D01*
G01X375151Y226913D02*
X375157Y226524D01*
G01X375146Y227384D02*
X375151Y226913D01*
G01X375142Y227925D02*
X375146Y227384D01*
G01X375139Y228520D02*
X375142Y227925D01*
G01X375137Y229153D02*
X375139Y228520D01*
G01X375136Y229807D02*
X375137Y229153D01*
G01X375132Y231677D02*
X375124Y231750D01*
G01X375135Y231547D02*
X375132Y231677D01*
G01X375139Y231359D02*
X375135Y231547D01*
G01X375142Y231120D02*
X375139Y231359D01*
G01X375144Y230838D02*
X375142Y231120D01*
G01X375146Y230521D02*
X375144Y230838D01*
G01X375147Y230180D02*
X375146Y230521D01*
G01X375147Y229826D02*
Y230180D01*
G01X375163Y227364D02*
X375173Y226999D01*
G01X375159Y227656D02*
X375163Y227364D01*
G01X375155Y228009D02*
X375159Y227656D01*
G01X375152Y228414D02*
X375155Y228009D01*
G01X375149Y228861D02*
X375152Y228414D01*
G01X375148Y229336D02*
X375149Y228861D01*
G01X375147Y229826D02*
X375148Y229336D01*
G01X373517Y225965D02*
X373528Y226012D01*
G01X373511Y226063D02*
X373517Y225965D01*
G01X373506Y226239D02*
X373511Y226063D01*
G01X373602Y228861D02*
X373604Y229826D01*
G01X373600Y228414D02*
X373602Y228861D01*
G01X373597Y228009D02*
X373600Y228414D01*
G01X373593Y227656D02*
X373597Y228009D01*
G01X373588Y227364D02*
X373593Y227656D01*
G01X373583Y227143D02*
X373588Y227364D01*
G01X373578Y226999D02*
X373583Y227143D01*
G01X373606Y230521D02*
X373604Y229826D01*
G01X373607Y230838D02*
X373606Y230521D01*
G01X373610Y231120D02*
X373607Y230838D01*
G01X373613Y231359D02*
X373610Y231120D01*
G01X373616Y231547D02*
X373613Y231359D01*
G01X373620Y231677D02*
X373616Y231547D01*
G01X373624Y231746D02*
X373620Y231677D01*
G01X373628Y231750D02*
X373624Y231746D01*
G01X373612Y228520D02*
X373615Y229807D01*
G01X373609Y227925D02*
X373612Y228520D01*
G01X373605Y227384D02*
X373609Y227925D01*
G01X373600Y226913D02*
X373605Y227384D01*
G01X373594Y226524D02*
X373600Y226913D01*
G01X373587Y226230D02*
X373594Y226524D01*
G01X373580Y226037D02*
X373587Y226230D01*
G01X373515Y224988D02*
X373530Y225050D01*
G01X373508Y225118D02*
X373515Y224988D01*
G01X373502Y225353D02*
X373508Y225118D01*
G01X373507Y220412D02*
X373497Y220138D01*
G01X373513Y220429D02*
X373507Y220412D01*
G01X373518Y220365D02*
X373513Y220429D01*
G01X373506Y221390D02*
X373492Y221024D01*
G01X373513Y221412D02*
X373506Y221390D01*
G01X373521Y221327D02*
X373513Y221412D01*
G01X373585Y219853D02*
X373571Y220340D01*
G01X373591Y219464D02*
X373585Y219853D01*
G01X373596Y218993D02*
X373591Y219464D01*
G01X373600Y218453D02*
X373596Y218993D01*
G01X373603Y217857D02*
X373600Y218453D01*
G01X373605Y217224D02*
X373603Y217857D01*
G01X373606Y216570D02*
X373605Y217224D01*
G01X373610Y214700D02*
X373618Y214627D01*
G01X373607Y214830D02*
X373610Y214700D01*
G01X373603Y215018D02*
X373607Y214830D01*
G01X373600Y215257D02*
X373603Y215018D01*
G01X373598Y215540D02*
X373600Y215257D01*
G01X373596Y215857D02*
X373598Y215540D01*
G01X373595Y216198D02*
X373596Y215857D01*
G01X373595Y216551D02*
Y216198D01*
G01X373579Y219013D02*
X373569Y219379D01*
G01X373583Y218722D02*
X373579Y219013D01*
G01X373587Y218368D02*
X373583Y218722D01*
G01X373590Y217963D02*
X373587Y218368D01*
G01X373593Y217516D02*
X373590Y217963D01*
G01X373594Y217041D02*
X373593Y217516D01*
G01X373595Y216551D02*
X373594Y217041D01*
G01X375225Y220412D02*
X375214Y220365D01*
G01X375231Y220314D02*
X375225Y220412D01*
G01X375236Y220138D02*
X375231Y220314D01*
G01X375140Y217516D02*
X375138Y216551D01*
G01X375142Y217963D02*
X375140Y217516D01*
G01X375146Y218368D02*
X375142Y217963D01*
G01X375149Y218722D02*
X375146Y218368D01*
G01X375154Y219013D02*
X375149Y218722D01*
G01X375159Y219234D02*
X375154Y219013D01*
G01X375164Y219379D02*
X375159Y219234D01*
G01X375136Y215857D02*
X375138Y216551D01*
G01X375135Y215540D02*
X375136Y215857D01*
G01X375132Y215257D02*
X375135Y215540D01*
G01X375129Y215018D02*
X375132Y215257D01*
G01X375126Y214830D02*
X375129Y215018D01*
G01X375122Y214700D02*
X375126Y214830D01*
G01X375118Y214632D02*
X375122Y214700D01*
G01X375114Y214627D02*
X375118Y214632D01*
G01X375130Y217857D02*
X375127Y216570D01*
G01X375133Y218453D02*
X375130Y217857D01*
G01X375137Y218993D02*
X375133Y218453D01*
G01X375142Y219464D02*
X375137Y218993D01*
G01X375148Y219853D02*
X375142Y219464D01*
G01X375155Y220148D02*
X375148Y219853D01*
G01X375162Y220340D02*
X375155Y220148D01*
G01X375227Y221390D02*
X375212Y221327D01*
G01X375234Y221259D02*
X375227Y221390D01*
G01X375241Y221024D02*
X375234Y221259D01*
G01X369575Y225965D02*
X369586Y226012D01*
G01X369570Y226063D02*
X369575Y225965D01*
G01X369565Y226239D02*
X369570Y226063D01*
G01X369660Y228861D02*
X369662Y229826D01*
G01X369658Y228414D02*
X369660Y228861D01*
G01X369655Y228009D02*
X369658Y228414D01*
G01X369651Y227656D02*
X369655Y228009D01*
G01X369647Y227364D02*
X369651Y227656D01*
G01X369642Y227143D02*
X369647Y227364D01*
G01X369636Y226999D02*
X369642Y227143D01*
G01X369671Y228520D02*
X369673Y229807D01*
G01X369668Y227925D02*
X369671Y228520D01*
G01X369663Y227384D02*
X369668Y227925D01*
G01X369658Y226913D02*
X369663Y227384D01*
G01X369652Y226524D02*
X369658Y226913D01*
G01X369646Y226230D02*
X369652Y226524D01*
G01X369639Y226037D02*
X369646Y226230D01*
G01X369574Y224988D02*
X369588Y225050D01*
G01X369567Y225118D02*
X369574Y224988D01*
G01X369560Y225353D02*
X369567Y225118D01*
G01X371293Y225965D02*
X371303Y226239D01*
G01X371288Y225948D02*
X371293Y225965D01*
G01X371282Y226012D02*
X371288Y225948D01*
G01X371294Y224988D02*
X371308Y225353D01*
G01X371287Y224965D02*
X371294Y224988D01*
G01X371280Y225050D02*
X371287Y224965D01*
G01X371216Y226524D02*
X371229Y226037D01*
G01X371210Y226913D02*
X371216Y226524D01*
G01X371205Y227384D02*
X371210Y226913D01*
G01X371201Y227925D02*
X371205Y227384D01*
G01X371197Y228520D02*
X371201Y227925D01*
G01X371195Y229153D02*
X371197Y228520D01*
G01X371195Y229807D02*
Y229153D01*
G01X371221Y227364D02*
X371232Y226999D01*
G01X371217Y227656D02*
X371221Y227364D01*
G01X371213Y228009D02*
X371217Y227656D01*
G01X371210Y228414D02*
X371213Y228009D01*
G01X371208Y228861D02*
X371210Y228414D01*
G01X371206Y229336D02*
X371208Y228861D01*
G01X371206Y229826D02*
Y229336D01*
G01X371293Y220412D02*
X371282Y220365D01*
G01X371298Y220314D02*
X371293Y220412D01*
G01X371303Y220138D02*
X371298Y220314D01*
G01X371208Y217516D02*
X371206Y216551D01*
G01X371210Y217963D02*
X371208Y217516D01*
G01X371213Y218368D02*
X371210Y217963D01*
G01X371217Y218722D02*
X371213Y218368D01*
G01X371221Y219013D02*
X371217Y218722D01*
G01X371226Y219234D02*
X371221Y219013D01*
G01X371232Y219379D02*
X371226Y219234D01*
G01X371197Y217857D02*
X371195Y216570D01*
G01X371201Y218453D02*
X371197Y217857D01*
G01X371205Y218993D02*
X371201Y218453D01*
G01X371210Y219464D02*
X371205Y218993D01*
G01X371216Y219853D02*
X371210Y219464D01*
G01X371222Y220148D02*
X371216Y219853D01*
G01X371229Y220340D02*
X371222Y220148D01*
G01X371294Y221390D02*
X371280Y221327D01*
G01X371301Y221259D02*
X371294Y221390D01*
G01X371308Y221024D02*
X371301Y221259D01*
G01X369575Y220412D02*
X369565Y220138D01*
G01X369581Y220429D02*
X369575Y220412D01*
G01X369586Y220365D02*
X369581Y220429D01*
G01X369574Y221390D02*
X369560Y221024D01*
G01X369581Y221412D02*
X369574Y221390D01*
G01X369588Y221327D02*
X369581Y221412D01*
G01X369652Y219853D02*
X369639Y220340D01*
G01X369658Y219464D02*
X369652Y219853D01*
G01X369663Y218993D02*
X369658Y219464D01*
G01X369668Y218453D02*
X369663Y218993D01*
G01X369671Y217857D02*
X369668Y218453D01*
G01X369673Y217224D02*
X369671Y217857D01*
G01X369673Y216570D02*
Y217224D01*
G01X369647Y219013D02*
X369636Y219379D01*
G01X369651Y218722D02*
X369647Y219013D01*
G01X369655Y218368D02*
X369651Y218722D01*
G01X369658Y217963D02*
X369655Y218368D01*
G01X369660Y217516D02*
X369658Y217963D01*
G01X369662Y217041D02*
X369660Y217516D01*
G01X369662Y216551D02*
Y217041D01*
G01X367361Y225965D02*
X367371Y226239D01*
G01X367355Y225948D02*
X367361Y225965D01*
G01X367350Y226012D02*
X367355Y225948D01*
G01X367362Y224988D02*
X367376Y225353D01*
G01X367355Y224965D02*
X367362Y224988D01*
G01X367347Y225050D02*
X367355Y224965D01*
G01X367283Y226524D02*
X367297Y226037D01*
G01X367277Y226913D02*
X367283Y226524D01*
G01X367272Y227384D02*
X367277Y226913D01*
G01X367268Y227925D02*
X367272Y227384D01*
G01X367265Y228520D02*
X367268Y227925D01*
G01X367263Y229153D02*
X367265Y228520D01*
G01X367262Y229807D02*
X367263Y229153D01*
G01X367258Y231677D02*
X367250Y231750D01*
G01X367261Y231547D02*
X367258Y231677D01*
G01X367265Y231359D02*
X367261Y231547D01*
G01X367268Y231120D02*
X367265Y231359D01*
G01X367270Y230838D02*
X367268Y231120D01*
G01X367272Y230521D02*
X367270Y230838D01*
G01X367273Y230180D02*
X367272Y230521D01*
G01X367273Y229826D02*
Y230180D01*
G01X367289Y227364D02*
X367299Y226999D01*
G01X367285Y227656D02*
X367289Y227364D01*
G01X367281Y228009D02*
X367285Y227656D01*
G01X367278Y228414D02*
X367281Y228009D01*
G01X367275Y228861D02*
X367278Y228414D01*
G01X367274Y229336D02*
X367275Y228861D01*
G01X367273Y229826D02*
X367274Y229336D01*
G01X365643Y225965D02*
X365654Y226012D01*
G01X365637Y226063D02*
X365643Y225965D01*
G01X365632Y226239D02*
X365637Y226063D01*
G01X365728Y228861D02*
X365730Y229826D01*
G01X365726Y228414D02*
X365728Y228861D01*
G01X365723Y228009D02*
X365726Y228414D01*
G01X365719Y227656D02*
X365723Y228009D01*
G01X365714Y227364D02*
X365719Y227656D01*
G01X365709Y227143D02*
X365714Y227364D01*
G01X365704Y226999D02*
X365709Y227143D01*
G01X365732Y230521D02*
X365730Y229826D01*
G01X365733Y230838D02*
X365732Y230521D01*
G01X365736Y231120D02*
X365733Y230838D01*
G01X365739Y231359D02*
X365736Y231120D01*
G01X365742Y231547D02*
X365739Y231359D01*
G01X365746Y231677D02*
X365742Y231547D01*
G01X365750Y231746D02*
X365746Y231677D01*
G01X365754Y231750D02*
X365750Y231746D01*
G01X365738Y228520D02*
X365741Y229807D01*
G01X365735Y227925D02*
X365738Y228520D01*
G01X365731Y227384D02*
X365735Y227925D01*
G01X365726Y226913D02*
X365731Y227384D01*
G01X365720Y226524D02*
X365726Y226913D01*
G01X365713Y226230D02*
X365720Y226524D01*
G01X365706Y226037D02*
X365713Y226230D01*
G01X365641Y224988D02*
X365656Y225050D01*
G01X365634Y225118D02*
X365641Y224988D01*
G01X365628Y225353D02*
X365634Y225118D01*
G01X365633Y220412D02*
X365623Y220138D01*
G01X365639Y220429D02*
X365633Y220412D01*
G01X365644Y220365D02*
X365639Y220429D01*
G01X365632Y221390D02*
X365618Y221024D01*
G01X365639Y221412D02*
X365632Y221390D01*
G01X365647Y221327D02*
X365639Y221412D01*
G01X365711Y219853D02*
X365697Y220340D01*
G01X365717Y219464D02*
X365711Y219853D01*
G01X365722Y218993D02*
X365717Y219464D01*
G01X365726Y218453D02*
X365722Y218993D01*
G01X365729Y217857D02*
X365726Y218453D01*
G01X365731Y217224D02*
X365729Y217857D01*
G01X365732Y216570D02*
X365731Y217224D01*
G01X365736Y214700D02*
X365744Y214627D01*
G01X365733Y214830D02*
X365736Y214700D01*
G01X365729Y215018D02*
X365733Y214830D01*
G01X365726Y215257D02*
X365729Y215018D01*
G01X365724Y215540D02*
X365726Y215257D01*
G01X365722Y215857D02*
X365724Y215540D01*
G01X365721Y216198D02*
X365722Y215857D01*
G01X365721Y216551D02*
Y216198D01*
G01X365705Y219013D02*
X365695Y219379D01*
G01X365709Y218722D02*
X365705Y219013D01*
G01X365713Y218368D02*
X365709Y218722D01*
G01X365716Y217963D02*
X365713Y218368D01*
G01X365719Y217516D02*
X365716Y217963D01*
G01X365720Y217041D02*
X365719Y217516D01*
G01X365721Y216551D02*
X365720Y217041D01*
G01X367351Y220412D02*
X367340Y220365D01*
G01X367357Y220314D02*
X367351Y220412D01*
G01X367362Y220138D02*
X367357Y220314D01*
G01X367266Y217516D02*
X367264Y216551D01*
G01X367268Y217963D02*
X367266Y217516D01*
G01X367272Y218368D02*
X367268Y217963D01*
G01X367275Y218722D02*
X367272Y218368D01*
G01X367280Y219013D02*
X367275Y218722D01*
G01X367285Y219234D02*
X367280Y219013D01*
G01X367290Y219379D02*
X367285Y219234D01*
G01X367262Y215857D02*
X367264Y216551D01*
G01X367261Y215540D02*
X367262Y215857D01*
G01X367258Y215257D02*
X367261Y215540D01*
G01X367255Y215018D02*
X367258Y215257D01*
G01X367252Y214830D02*
X367255Y215018D01*
G01X367248Y214700D02*
X367252Y214830D01*
G01X367244Y214632D02*
X367248Y214700D01*
G01X367240Y214627D02*
X367244Y214632D01*
G01X367256Y217857D02*
X367253Y216570D01*
G01X367259Y218453D02*
X367256Y217857D01*
G01X367263Y218993D02*
X367259Y218453D01*
G01X367268Y219464D02*
X367263Y218993D01*
G01X367274Y219853D02*
X367268Y219464D01*
G01X367281Y220148D02*
X367274Y219853D01*
G01X367288Y220340D02*
X367281Y220148D01*
G01X367353Y221390D02*
X367338Y221327D01*
G01X367360Y221259D02*
X367353Y221390D01*
G01X367367Y221024D02*
X367360Y221259D01*
G01X361701Y225965D02*
X361712Y226012D01*
G01X361696Y226063D02*
X361701Y225965D01*
G01X361691Y226239D02*
X361696Y226063D01*
G01X361786Y228861D02*
X361788Y229826D01*
G01X361784Y228414D02*
X361786Y228861D01*
G01X361781Y228009D02*
X361784Y228414D01*
G01X361777Y227656D02*
X361781Y228009D01*
G01X361773Y227364D02*
X361777Y227656D01*
G01X361768Y227143D02*
X361773Y227364D01*
G01X361762Y226999D02*
X361768Y227143D01*
G01X361797Y228520D02*
X361799Y229807D01*
G01X361793Y227925D02*
X361797Y228520D01*
G01X361789Y227384D02*
X361793Y227925D01*
G01X361784Y226913D02*
X361789Y227384D01*
G01X361778Y226524D02*
X361784Y226913D01*
G01X361772Y226230D02*
X361778Y226524D01*
G01X361765Y226037D02*
X361772Y226230D01*
G01X361700Y224988D02*
X361714Y225050D01*
G01X361693Y225118D02*
X361700Y224988D01*
G01X361686Y225353D02*
X361693Y225118D01*
G01X363419Y225965D02*
X363429Y226239D01*
G01X363414Y225948D02*
X363419Y225965D01*
G01X363408Y226012D02*
X363414Y225948D01*
G01X363420Y224988D02*
X363434Y225353D01*
G01X363413Y224965D02*
X363420Y224988D01*
G01X363406Y225050D02*
X363413Y224965D01*
G01X363342Y226524D02*
X363355Y226037D01*
G01X363336Y226913D02*
X363342Y226524D01*
G01X363331Y227384D02*
X363336Y226913D01*
G01X363327Y227925D02*
X363331Y227384D01*
G01X363323Y228520D02*
X363327Y227925D01*
G01X363321Y229153D02*
X363323Y228520D01*
G01X363321Y229807D02*
Y229153D01*
G01X363347Y227364D02*
X363358Y226999D01*
G01X363343Y227656D02*
X363347Y227364D01*
G01X363339Y228009D02*
X363343Y227656D01*
G01X363336Y228414D02*
X363339Y228009D01*
G01X363334Y228861D02*
X363336Y228414D01*
G01X363332Y229336D02*
X363334Y228861D01*
G01X363332Y229826D02*
Y229336D01*
G01X363419Y220412D02*
X363408Y220365D01*
G01X363424Y220314D02*
X363419Y220412D01*
G01X363429Y220138D02*
X363424Y220314D01*
G01X363334Y217516D02*
X363332Y216551D01*
G01X363336Y217963D02*
X363334Y217516D01*
G01X363339Y218368D02*
X363336Y217963D01*
G01X363343Y218722D02*
X363339Y218368D01*
G01X363347Y219013D02*
X363343Y218722D01*
G01X363352Y219234D02*
X363347Y219013D01*
G01X363358Y219379D02*
X363352Y219234D01*
G01X363323Y217857D02*
X363321Y216570D01*
G01X363327Y218453D02*
X363323Y217857D01*
G01X363331Y218993D02*
X363327Y218453D01*
G01X363336Y219464D02*
X363331Y218993D01*
G01X363342Y219853D02*
X363336Y219464D01*
G01X363348Y220148D02*
X363342Y219853D01*
G01X363355Y220340D02*
X363348Y220148D01*
G01X363420Y221390D02*
X363406Y221327D01*
G01X363427Y221259D02*
X363420Y221390D01*
G01X363434Y221024D02*
X363427Y221259D01*
G01X361701Y220412D02*
X361691Y220138D01*
G01X361707Y220429D02*
X361701Y220412D01*
G01X361712Y220365D02*
X361707Y220429D01*
G01X361700Y221390D02*
X361686Y221024D01*
G01X361707Y221412D02*
X361700Y221390D01*
G01X361714Y221327D02*
X361707Y221412D01*
G01X361778Y219853D02*
X361765Y220340D01*
G01X361784Y219464D02*
X361778Y219853D01*
G01X361789Y218993D02*
X361784Y219464D01*
G01X361793Y218453D02*
X361789Y218993D01*
G01X361797Y217857D02*
X361793Y218453D01*
G01X361799Y217224D02*
X361797Y217857D01*
G01X361799Y216570D02*
Y217224D01*
G01X361773Y219013D02*
X361762Y219379D01*
G01X361777Y218722D02*
X361773Y219013D01*
G01X361781Y218368D02*
X361777Y218722D01*
G01X361784Y217963D02*
X361781Y218368D01*
G01X361786Y217516D02*
X361784Y217963D01*
G01X361788Y217041D02*
X361786Y217516D01*
G01X361788Y216551D02*
Y217041D01*
G01X359487Y225965D02*
X359497Y226239D01*
G01X359481Y225948D02*
X359487Y225965D01*
G01X359476Y226012D02*
X359481Y225948D01*
G01X359488Y224988D02*
X359502Y225353D01*
G01X359481Y224965D02*
X359488Y224988D01*
G01X359473Y225050D02*
X359481Y224965D01*
G01X359409Y226524D02*
X359423Y226037D01*
G01X359403Y226913D02*
X359409Y226524D01*
G01X359398Y227384D02*
X359403Y226913D01*
G01X359394Y227925D02*
X359398Y227384D01*
G01X359391Y228520D02*
X359394Y227925D01*
G01X359389Y229153D02*
X359391Y228520D01*
G01X359388Y229807D02*
X359389Y229153D01*
G01X359384Y231677D02*
X359376Y231750D01*
G01X359387Y231547D02*
X359384Y231677D01*
G01X359391Y231359D02*
X359387Y231547D01*
G01X359394Y231120D02*
X359391Y231359D01*
G01X359396Y230838D02*
X359394Y231120D01*
G01X359398Y230521D02*
X359396Y230838D01*
G01X359399Y230180D02*
X359398Y230521D01*
G01X359399Y229826D02*
Y230180D01*
G01X359415Y227364D02*
X359425Y226999D01*
G01X359411Y227656D02*
X359415Y227364D01*
G01X359407Y228009D02*
X359411Y227656D01*
G01X359404Y228414D02*
X359407Y228009D01*
G01X359401Y228861D02*
X359404Y228414D01*
G01X359400Y229336D02*
X359401Y228861D01*
G01X359399Y229826D02*
X359400Y229336D01*
G01X357769Y225965D02*
X357780Y226012D01*
G01X357763Y226063D02*
X357769Y225965D01*
G01X357758Y226239D02*
X357763Y226063D01*
G01X357854Y228861D02*
X357856Y229826D01*
G01X357852Y228414D02*
X357854Y228861D01*
G01X357849Y228009D02*
X357852Y228414D01*
G01X357845Y227656D02*
X357849Y228009D01*
G01X357840Y227364D02*
X357845Y227656D01*
G01X357835Y227143D02*
X357840Y227364D01*
G01X357830Y226999D02*
X357835Y227143D01*
G01X357858Y230521D02*
X357856Y229826D01*
G01X357859Y230838D02*
X357858Y230521D01*
G01X357862Y231120D02*
X357859Y230838D01*
G01X357865Y231359D02*
X357862Y231120D01*
G01X357868Y231547D02*
X357865Y231359D01*
G01X357872Y231677D02*
X357868Y231547D01*
G01X357876Y231746D02*
X357872Y231677D01*
G01X357880Y231750D02*
X357876Y231746D01*
G01X357864Y228520D02*
X357867Y229807D01*
G01X357861Y227925D02*
X357864Y228520D01*
G01X357857Y227384D02*
X357861Y227925D01*
G01X357852Y226913D02*
X357857Y227384D01*
G01X357846Y226524D02*
X357852Y226913D01*
G01X357839Y226230D02*
X357846Y226524D01*
G01X357832Y226037D02*
X357839Y226230D01*
G01X357767Y224988D02*
X357782Y225050D01*
G01X357760Y225118D02*
X357767Y224988D01*
G01X357753Y225353D02*
X357760Y225118D01*
G01X357759Y220412D02*
X357749Y220138D01*
G01X357765Y220429D02*
X357759Y220412D01*
G01X357770Y220365D02*
X357765Y220429D01*
G01X357758Y221390D02*
X357744Y221024D01*
G01X357765Y221412D02*
X357758Y221390D01*
G01X357773Y221327D02*
X357765Y221412D01*
G01X357837Y219853D02*
X357823Y220340D01*
G01X357843Y219464D02*
X357837Y219853D01*
G01X357848Y218993D02*
X357843Y219464D01*
G01X357852Y218453D02*
X357848Y218993D01*
G01X357855Y217857D02*
X357852Y218453D01*
G01X357857Y217224D02*
X357855Y217857D01*
G01X357858Y216570D02*
X357857Y217224D01*
G01X357862Y214700D02*
X357870Y214627D01*
G01X357859Y214830D02*
X357862Y214700D01*
G01X357855Y215018D02*
X357859Y214830D01*
G01X357852Y215257D02*
X357855Y215018D01*
G01X357850Y215540D02*
X357852Y215257D01*
G01X357848Y215857D02*
X357850Y215540D01*
G01X357847Y216198D02*
X357848Y215857D01*
G01X357847Y216551D02*
Y216198D01*
G01X357831Y219013D02*
X357821Y219379D01*
G01X357835Y218722D02*
X357831Y219013D01*
G01X357839Y218368D02*
X357835Y218722D01*
G01X357842Y217963D02*
X357839Y218368D01*
G01X357845Y217516D02*
X357842Y217963D01*
G01X357846Y217041D02*
X357845Y217516D01*
G01X357847Y216551D02*
X357846Y217041D01*
G01X359477Y220412D02*
X359466Y220365D01*
G01X359483Y220314D02*
X359477Y220412D01*
G01X359488Y220138D02*
X359483Y220314D01*
G01X359392Y217516D02*
X359390Y216551D01*
G01X359394Y217963D02*
X359392Y217516D01*
G01X359397Y218368D02*
X359394Y217963D01*
G01X359401Y218722D02*
X359397Y218368D01*
G01X359406Y219013D02*
X359401Y218722D01*
G01X359411Y219234D02*
X359406Y219013D01*
G01X359416Y219379D02*
X359411Y219234D01*
G01X359388Y215857D02*
X359390Y216551D01*
G01X359387Y215540D02*
X359388Y215857D01*
G01X359384Y215257D02*
X359387Y215540D01*
G01X359381Y215018D02*
X359384Y215257D01*
G01X359378Y214830D02*
X359381Y215018D01*
G01X359374Y214700D02*
X359378Y214830D01*
G01X359370Y214632D02*
X359374Y214700D01*
G01X359366Y214627D02*
X359370Y214632D01*
G01X359382Y217857D02*
X359379Y216570D01*
G01X359385Y218453D02*
X359382Y217857D01*
G01X359389Y218993D02*
X359385Y218453D01*
G01X359394Y219464D02*
X359389Y218993D01*
G01X359400Y219853D02*
X359394Y219464D01*
G01X359407Y220148D02*
X359400Y219853D01*
G01X359414Y220340D02*
X359407Y220148D01*
G01X359479Y221390D02*
X359464Y221327D01*
G01X359486Y221259D02*
X359479Y221390D01*
G01X359493Y221024D02*
X359486Y221259D01*
G01X353827Y225965D02*
X353838Y226012D01*
G01X353822Y226063D02*
X353827Y225965D01*
G01X353817Y226239D02*
X353822Y226063D01*
G01X353912Y228861D02*
X353914Y229826D01*
G01X353910Y228414D02*
X353912Y228861D01*
G01X353907Y228009D02*
X353910Y228414D01*
G01X353903Y227656D02*
X353907Y228009D01*
G01X353899Y227364D02*
X353903Y227656D01*
G01X353894Y227143D02*
X353899Y227364D01*
G01X353888Y226999D02*
X353894Y227143D01*
G01X353923Y228520D02*
X353925Y229807D01*
G01X353919Y227925D02*
X353923Y228520D01*
G01X353915Y227384D02*
X353919Y227925D01*
G01X353910Y226913D02*
X353915Y227384D01*
G01X353904Y226524D02*
X353910Y226913D01*
G01X353898Y226230D02*
X353904Y226524D01*
G01X353891Y226037D02*
X353898Y226230D01*
G01X353826Y224988D02*
X353840Y225050D01*
G01X353819Y225118D02*
X353826Y224988D01*
G01X353812Y225353D02*
X353819Y225118D01*
G01X355545Y225965D02*
X355555Y226239D01*
G01X355539Y225948D02*
X355545Y225965D01*
G01X355534Y226012D02*
X355539Y225948D01*
G01X355546Y224988D02*
X355560Y225353D01*
G01X355539Y224965D02*
X355546Y224988D01*
G01X355532Y225050D02*
X355539Y224965D01*
G01X355468Y226524D02*
X355481Y226037D01*
G01X355462Y226913D02*
X355468Y226524D01*
G01X355457Y227384D02*
X355462Y226913D01*
G01X355453Y227925D02*
X355457Y227384D01*
G01X355449Y228520D02*
X355453Y227925D01*
G01X355447Y229153D02*
X355449Y228520D01*
G01X355447Y229807D02*
Y229153D01*
G01X355473Y227364D02*
X355484Y226999D01*
G01X355469Y227656D02*
X355473Y227364D01*
G01X355465Y228009D02*
X355469Y227656D01*
G01X355462Y228414D02*
X355465Y228009D01*
G01X355460Y228861D02*
X355462Y228414D01*
G01X355458Y229336D02*
X355460Y228861D01*
G01X355458Y229826D02*
Y229336D01*
G01X355545Y220412D02*
X355534Y220365D01*
G01X355550Y220314D02*
X355545Y220412D01*
G01X355555Y220138D02*
X355550Y220314D01*
G01X355460Y217516D02*
X355458Y216551D01*
G01X355462Y217963D02*
X355460Y217516D01*
G01X355465Y218368D02*
X355462Y217963D01*
G01X355469Y218722D02*
X355465Y218368D01*
G01X355473Y219013D02*
X355469Y218722D01*
G01X355478Y219234D02*
X355473Y219013D01*
G01X355484Y219379D02*
X355478Y219234D01*
G01X355449Y217857D02*
X355447Y216570D01*
G01X355453Y218453D02*
X355449Y217857D01*
G01X355457Y218993D02*
X355453Y218453D01*
G01X355462Y219464D02*
X355457Y218993D01*
G01X355468Y219853D02*
X355462Y219464D01*
G01X355474Y220148D02*
X355468Y219853D01*
G01X355481Y220340D02*
X355474Y220148D01*
G01X355546Y221390D02*
X355532Y221327D01*
G01X355553Y221259D02*
X355546Y221390D01*
G01X355560Y221024D02*
X355553Y221259D01*
G01X353827Y220412D02*
X353817Y220138D01*
G01X353833Y220429D02*
X353827Y220412D01*
G01X353838Y220365D02*
X353833Y220429D01*
G01X353826Y221390D02*
X353812Y221024D01*
G01X353833Y221412D02*
X353826Y221390D01*
G01X353840Y221327D02*
X353833Y221412D01*
G01X353904Y219853D02*
X353891Y220340D01*
G01X353910Y219464D02*
X353904Y219853D01*
G01X353915Y218993D02*
X353910Y219464D01*
G01X353919Y218453D02*
X353915Y218993D01*
G01X353923Y217857D02*
X353919Y218453D01*
G01X353925Y217224D02*
X353923Y217857D01*
G01X353925Y216570D02*
Y217224D01*
G01X353899Y219013D02*
X353888Y219379D01*
G01X353903Y218722D02*
X353899Y219013D01*
G01X353907Y218368D02*
X353903Y218722D01*
G01X353910Y217963D02*
X353907Y218368D01*
G01X353912Y217516D02*
X353910Y217963D01*
G01X353914Y217041D02*
X353912Y217516D01*
G01X353914Y216551D02*
Y217041D01*
G01X351613Y225965D02*
X351623Y226239D01*
G01X351607Y225948D02*
X351613Y225965D01*
G01X351602Y226012D02*
X351607Y225948D01*
G01X351614Y224988D02*
X351628Y225353D01*
G01X351607Y224965D02*
X351614Y224988D01*
G01X351599Y225050D02*
X351607Y224965D01*
G01X351535Y226524D02*
X351549Y226037D01*
G01X351529Y226913D02*
X351535Y226524D01*
G01X351524Y227384D02*
X351529Y226913D01*
G01X351520Y227925D02*
X351524Y227384D01*
G01X351517Y228520D02*
X351520Y227925D01*
G01X351515Y229153D02*
X351517Y228520D01*
G01X351514Y229807D02*
X351515Y229153D01*
G01X351510Y231677D02*
X351502Y231750D01*
G01X351513Y231547D02*
X351510Y231677D01*
G01X351517Y231359D02*
X351513Y231547D01*
G01X351520Y231120D02*
X351517Y231359D01*
G01X351522Y230838D02*
X351520Y231120D01*
G01X351524Y230521D02*
X351522Y230838D01*
G01X351525Y230180D02*
X351524Y230521D01*
G01X351525Y229826D02*
Y230180D01*
G01X351541Y227364D02*
X351551Y226999D01*
G01X351537Y227656D02*
X351541Y227364D01*
G01X351533Y228009D02*
X351537Y227656D01*
G01X351530Y228414D02*
X351533Y228009D01*
G01X351527Y228861D02*
X351530Y228414D01*
G01X351526Y229336D02*
X351527Y228861D01*
G01X351525Y229826D02*
X351526Y229336D01*
G01X349895Y225965D02*
X349906Y226012D01*
G01X349889Y226063D02*
X349895Y225965D01*
G01X349884Y226239D02*
X349889Y226063D01*
G01X349980Y228861D02*
X349982Y229826D01*
G01X349978Y228414D02*
X349980Y228861D01*
G01X349975Y228009D02*
X349978Y228414D01*
G01X349971Y227656D02*
X349975Y228009D01*
G01X349966Y227364D02*
X349971Y227656D01*
G01X349961Y227143D02*
X349966Y227364D01*
G01X349956Y226999D02*
X349961Y227143D01*
G01X349984Y230521D02*
X349982Y229826D01*
G01X349985Y230838D02*
X349984Y230521D01*
G01X349988Y231120D02*
X349985Y230838D01*
G01X349991Y231359D02*
X349988Y231120D01*
G01X349994Y231547D02*
X349991Y231359D01*
G01X349998Y231677D02*
X349994Y231547D01*
G01X350002Y231746D02*
X349998Y231677D01*
G01X350006Y231750D02*
X350002Y231746D01*
G01X349990Y228520D02*
X349993Y229807D01*
G01X349987Y227925D02*
X349990Y228520D01*
G01X349983Y227384D02*
X349987Y227925D01*
G01X349978Y226913D02*
X349983Y227384D01*
G01X349972Y226524D02*
X349978Y226913D01*
G01X349965Y226230D02*
X349972Y226524D01*
G01X349958Y226037D02*
X349965Y226230D01*
G01X349893Y224988D02*
X349908Y225050D01*
G01X349886Y225118D02*
X349893Y224988D01*
G01X349879Y225353D02*
X349886Y225118D01*
G01X349885Y220412D02*
X349875Y220138D01*
G01X349891Y220429D02*
X349885Y220412D01*
G01X349896Y220365D02*
X349891Y220429D01*
G01X349884Y221390D02*
X349870Y221024D01*
G01X349891Y221412D02*
X349884Y221390D01*
G01X349899Y221327D02*
X349891Y221412D01*
G01X349963Y219853D02*
X349949Y220340D01*
G01X349969Y219464D02*
X349963Y219853D01*
G01X349974Y218993D02*
X349969Y219464D01*
G01X349978Y218453D02*
X349974Y218993D01*
G01X349981Y217857D02*
X349978Y218453D01*
G01X349983Y217224D02*
X349981Y217857D01*
G01X349984Y216570D02*
X349983Y217224D01*
G01X349988Y214700D02*
X349996Y214627D01*
G01X349985Y214830D02*
X349988Y214700D01*
G01X349981Y215018D02*
X349985Y214830D01*
G01X349978Y215257D02*
X349981Y215018D01*
G01X349976Y215540D02*
X349978Y215257D01*
G01X349974Y215857D02*
X349976Y215540D01*
G01X349973Y216198D02*
X349974Y215857D01*
G01X349973Y216551D02*
Y216198D01*
G01X349957Y219013D02*
X349947Y219379D01*
G01X349961Y218722D02*
X349957Y219013D01*
G01X349965Y218368D02*
X349961Y218722D01*
G01X349968Y217963D02*
X349965Y218368D01*
G01X349971Y217516D02*
X349968Y217963D01*
G01X349972Y217041D02*
X349971Y217516D01*
G01X349973Y216551D02*
X349972Y217041D01*
G01X351603Y220412D02*
X351592Y220365D01*
G01X351609Y220314D02*
X351603Y220412D01*
G01X351614Y220138D02*
X351609Y220314D01*
G01X351518Y217516D02*
X351516Y216551D01*
G01X351520Y217963D02*
X351518Y217516D01*
G01X351523Y218368D02*
X351520Y217963D01*
G01X351527Y218722D02*
X351523Y218368D01*
G01X351532Y219013D02*
X351527Y218722D01*
G01X351537Y219234D02*
X351532Y219013D01*
G01X351542Y219379D02*
X351537Y219234D01*
G01X351514Y215857D02*
X351516Y216551D01*
G01X351513Y215540D02*
X351514Y215857D01*
G01X351510Y215257D02*
X351513Y215540D01*
G01X351507Y215018D02*
X351510Y215257D01*
G01X351504Y214830D02*
X351507Y215018D01*
G01X351500Y214700D02*
X351504Y214830D01*
G01X351496Y214632D02*
X351500Y214700D01*
G01X351492Y214627D02*
X351496Y214632D01*
G01X351508Y217857D02*
X351505Y216570D01*
G01X351511Y218453D02*
X351508Y217857D01*
G01X351515Y218993D02*
X351511Y218453D01*
G01X351520Y219464D02*
X351515Y218993D01*
G01X351526Y219853D02*
X351520Y219464D01*
G01X351533Y220148D02*
X351526Y219853D01*
G01X351540Y220340D02*
X351533Y220148D01*
G01X351605Y221390D02*
X351590Y221327D01*
G01X351612Y221259D02*
X351605Y221390D01*
G01X351619Y221024D02*
X351612Y221259D01*
G01X347671Y225965D02*
X347681Y226239D01*
G01X347665Y225948D02*
X347671Y225965D01*
G01X347660Y226012D02*
X347665Y225948D01*
G01X347672Y224988D02*
X347686Y225353D01*
G01X347665Y224965D02*
X347672Y224988D01*
G01X347658Y225050D02*
X347665Y224965D01*
G01X347594Y226524D02*
X347607Y226037D01*
G01X347588Y226913D02*
X347594Y226524D01*
G01X347583Y227384D02*
X347588Y226913D01*
G01X347579Y227925D02*
X347583Y227384D01*
G01X347575Y228520D02*
X347579Y227925D01*
G01X347573Y229153D02*
X347575Y228520D01*
G01X347573Y229807D02*
Y229153D01*
G01X347599Y227364D02*
X347610Y226999D01*
G01X347595Y227656D02*
X347599Y227364D01*
G01X347591Y228009D02*
X347595Y227656D01*
G01X347588Y228414D02*
X347591Y228009D01*
G01X347586Y228861D02*
X347588Y228414D01*
G01X347584Y229336D02*
X347586Y228861D01*
G01X347584Y229826D02*
Y229336D01*
G01X347671Y220412D02*
X347660Y220365D01*
G01X347676Y220314D02*
X347671Y220412D01*
G01X347681Y220138D02*
X347676Y220314D01*
G01X347586Y217516D02*
X347584Y216551D01*
G01X347588Y217963D02*
X347586Y217516D01*
G01X347591Y218368D02*
X347588Y217963D01*
G01X347595Y218722D02*
X347591Y218368D01*
G01X347599Y219013D02*
X347595Y218722D01*
G01X347604Y219234D02*
X347599Y219013D01*
G01X347610Y219379D02*
X347604Y219234D01*
G01X347575Y217857D02*
X347573Y216570D01*
G01X347579Y218453D02*
X347575Y217857D01*
G01X347583Y218993D02*
X347579Y218453D01*
G01X347588Y219464D02*
X347583Y218993D01*
G01X347594Y219853D02*
X347588Y219464D01*
G01X347600Y220148D02*
X347594Y219853D01*
G01X347607Y220340D02*
X347600Y220148D01*
G01X347672Y221390D02*
X347658Y221327D01*
G01X347679Y221259D02*
X347672Y221390D01*
G01X347686Y221024D02*
X347679Y221259D01*
G01X347561Y231754D02*
X347560Y231750D01*
G01X347561Y231756D02*
Y231754D01*
G01X347562Y231756D02*
X347561D01*
G01X355435Y231754D02*
X355434Y231750D01*
G01X355435Y231756D02*
Y231754D01*
G01X355436Y231756D02*
X355435D01*
G01X363309Y231754D02*
X363308Y231750D01*
G01X363309Y231756D02*
Y231754D01*
G01X363310Y231756D02*
X363309D01*
G01X353937Y214624D02*
X353938Y214627D01*
G01X353937Y214622D02*
Y214624D01*
G01X353936Y214621D02*
X353937Y214622D01*
G01X371183Y231754D02*
X371182Y231750D01*
G01X371183Y231756D02*
Y231754D01*
G01X371184Y231756D02*
X371183D01*
G01X361811Y214624D02*
X361812Y214627D01*
G01X361811Y214622D02*
Y214624D01*
G01X361810Y214621D02*
X361811Y214622D01*
G01X379057Y231754D02*
X379056Y231750D01*
G01X379057Y231756D02*
Y231754D01*
G01X379058Y231756D02*
X379057D01*
G01X369685Y214624D02*
X369686Y214627D01*
G01X369685Y214622D02*
Y214624D01*
G01X369684Y214621D02*
X369685Y214622D01*
G01X386931Y231754D02*
X386930Y231750D01*
G01X386931Y231756D02*
Y231754D01*
G01X386932Y231756D02*
X386931D01*
G01X377559Y214624D02*
X377560Y214627D01*
G01X377559Y214622D02*
Y214624D01*
G01X377558Y214621D02*
X377559Y214622D01*
G01X347561Y230768D02*
X347560Y230762D01*
G01X347561Y230771D02*
Y230768D01*
G01X347562Y230772D02*
X347561Y230771D01*
G01X355435Y230768D02*
X355434Y230762D01*
G01X355435Y230771D02*
Y230768D01*
G01X355436Y230772D02*
X355435Y230771D01*
G01X353937Y215610D02*
X353938Y215615D01*
G01X353937Y215606D02*
Y215610D01*
G01X353936Y215605D02*
X353937Y215606D01*
G01X363309Y230768D02*
X363308Y230762D01*
G01X363309Y230771D02*
Y230768D01*
G01X363310Y230772D02*
X363309Y230771D01*
G01X361811Y215610D02*
X361812Y215615D01*
G01X361811Y215606D02*
Y215610D01*
G01X361810Y215605D02*
X361811Y215606D01*
G01X371183Y230768D02*
X371182Y230762D01*
G01X371183Y230771D02*
Y230768D01*
G01X371184Y230772D02*
X371183Y230771D01*
G01X394805Y231754D02*
X394804Y231750D01*
G01X394805Y231756D02*
Y231754D01*
G01X394806Y231756D02*
X394805D01*
G01X385433Y214624D02*
X385434Y214627D01*
G01X385433Y214622D02*
Y214624D01*
G01X385432Y214621D02*
X385433Y214622D01*
G01X402679Y231754D02*
X402678Y231750D01*
G01X402679Y231756D02*
Y231754D01*
G01X402680Y231756D02*
X402679D01*
G01X393307Y214624D02*
X393308Y214627D01*
G01X393307Y214622D02*
Y214624D01*
G01X393306Y214621D02*
X393307Y214622D01*
G01X410553Y231754D02*
X410552Y231750D01*
G01X410553Y231756D02*
Y231754D01*
G01X410554Y231756D02*
X410553D01*
G01X401181Y214624D02*
X401182Y214627D01*
G01X401181Y214622D02*
Y214624D01*
G01X401180Y214621D02*
X401181Y214622D01*
G01X418427Y231754D02*
X418426Y231750D01*
G01X418427Y231756D02*
Y231754D01*
G01X418428Y231756D02*
X418427D01*
G01X409056Y214624D02*
Y214627D01*
G01X409055Y214622D02*
X409056Y214624D01*
G01X409054Y214621D02*
X409055Y214622D01*
G01X349994Y230209D02*
X349993Y229807D01*
G01X349997Y230537D02*
X349994Y230209D01*
G01X350001Y230733D02*
X349997Y230537D01*
G01X350005Y230762D02*
X350001Y230733D01*
G01X369685Y215610D02*
X369686Y215615D01*
G01X369685Y215606D02*
Y215610D01*
G01X369684Y215605D02*
X369685Y215606D01*
G01X379057Y230768D02*
X379056Y230762D01*
G01X379057Y230771D02*
Y230768D01*
G01X379058Y230772D02*
X379057Y230771D01*
G01X377559Y215610D02*
X377560Y215615D01*
G01X377559Y215606D02*
Y215610D01*
G01X377558Y215605D02*
X377559Y215606D01*
G01X386931Y230768D02*
X386930Y230762D01*
G01X386931Y230771D02*
Y230768D01*
G01X386932Y230772D02*
X386931Y230771D01*
G01X385433Y215610D02*
X385434Y215615D01*
G01X385433Y215606D02*
Y215610D01*
G01X385432Y215605D02*
X385433Y215606D01*
G01X426301Y231754D02*
X426300Y231750D01*
G01X426301Y231756D02*
Y231754D01*
G01X426302Y231756D02*
X426301D01*
G01X416930Y214624D02*
Y214627D01*
G01X416929Y214622D02*
X416930Y214624D01*
G01X416928Y214621D02*
X416929Y214622D01*
G01X424804Y214624D02*
Y214627D01*
G01X424803Y214622D02*
X424804Y214624D01*
G01X424802Y214621D02*
X424803Y214622D01*
G01X347829Y213893D02*
X347836Y213840D01*
G01X347823Y214024D02*
X347829Y213893D01*
G01X347818Y214231D02*
X347823Y214024D01*
G01X349736Y232484D02*
X349730Y232538D01*
G01X349742Y232353D02*
X349736Y232484D01*
G01X349748Y232147D02*
X349742Y232353D01*
G01X347831Y214866D02*
X347836Y214824D01*
G01X347827Y214965D02*
X347831Y214866D01*
G01X347822Y215117D02*
X347827Y214965D01*
G01X349735Y231511D02*
X349730Y231553D01*
G01X349739Y231413D02*
X349735Y231511D01*
G01X349743Y231260D02*
X349739Y231413D01*
G01X349992Y215645D02*
X349996Y215615D01*
G01X349987Y215841D02*
X349992Y215645D01*
G01X349985Y216168D02*
X349987Y215841D01*
G01X349984Y216570D02*
X349985Y216168D01*
G01X351506Y230733D02*
X351502Y230762D01*
G01X351511Y230537D02*
X351506Y230733D01*
G01X351513Y230209D02*
X351511Y230537D01*
G01X351514Y229807D02*
X351513Y230209D01*
G01X347566Y230699D02*
X347562Y230772D01*
G01X347569Y230490D02*
X347566Y230699D01*
G01X347572Y230178D02*
X347569Y230490D01*
G01X347573Y229807D02*
X347572Y230178D01*
G01X347570Y231608D02*
X347562Y231756D01*
G01X347577Y231193D02*
X347570Y231608D01*
G01X347582Y230573D02*
X347577Y231193D01*
G01X347584Y229826D02*
X347582Y230573D01*
G01X353928Y214770D02*
X353936Y214621D01*
G01X353921Y215184D02*
X353928Y214770D01*
G01X353916Y215804D02*
X353921Y215184D01*
G01X353914Y216551D02*
X353916Y215804D01*
G01X353932Y215678D02*
X353936Y215605D01*
G01X353929Y215887D02*
X353932Y215678D01*
G01X353926Y216200D02*
X353929Y215887D01*
G01X353925Y216570D02*
X353926Y216200D01*
G01X347582Y215804D02*
X347584Y216551D01*
G01X347577Y215184D02*
X347582Y215804D01*
G01X347570Y214770D02*
X347577Y215184D01*
G01X347562Y214621D02*
X347570Y214770D01*
G01X353916Y230573D02*
X353914Y229826D01*
G01X353921Y231193D02*
X353916Y230573D01*
G01X353928Y231608D02*
X353921Y231193D01*
G01X353936Y231756D02*
X353928Y231608D01*
G01X355456Y215804D02*
X355458Y216551D01*
G01X355451Y215184D02*
X355456Y215804D01*
G01X355444Y214770D02*
X355451Y215184D01*
G01X355436Y214621D02*
X355444Y214770D01*
G01X361790Y230573D02*
X361788Y229826D01*
G01X361795Y231193D02*
X361790Y230573D01*
G01X361802Y231608D02*
X361795Y231193D01*
G01X361810Y231756D02*
X361802Y231608D01*
G01X347572Y216200D02*
X347573Y216570D01*
G01X347569Y215887D02*
X347572Y216200D01*
G01X347566Y215678D02*
X347569Y215887D01*
G01X347562Y215605D02*
X347566Y215678D01*
G01X353926Y230178D02*
X353925Y229807D01*
G01X353929Y230490D02*
X353926Y230178D01*
G01X353932Y230699D02*
X353929Y230490D01*
G01X353936Y230772D02*
X353932Y230699D01*
G01X355446Y216200D02*
X355447Y216570D01*
G01X355443Y215887D02*
X355446Y216200D01*
G01X355440Y215678D02*
X355443Y215887D01*
G01X355436Y215605D02*
X355440Y215678D01*
G01X361800Y230178D02*
X361799Y229807D01*
G01X361803Y230490D02*
X361800Y230178D01*
G01X361806Y230699D02*
X361803Y230490D01*
G01X361810Y230772D02*
X361806Y230699D01*
G01X347827Y231413D02*
X347822Y231260D01*
G01X347831Y231511D02*
X347827Y231413D01*
G01X347836Y231553D02*
X347831Y231511D01*
G01X349730Y214965D02*
X349734Y215117D01*
G01X349725Y214866D02*
X349730Y214965D01*
G01X349721Y214824D02*
X349725Y214866D01*
G01X351768Y231413D02*
X351764Y231260D01*
G01X351773Y231511D02*
X351768Y231413D01*
G01X351777Y231553D02*
X351773Y231511D01*
G01X353671Y214965D02*
X353676Y215117D01*
G01X353667Y214866D02*
X353671Y214965D01*
G01X353662Y214824D02*
X353667Y214866D01*
G01X355701Y231413D02*
X355696Y231260D01*
G01X355705Y231511D02*
X355701Y231413D01*
G01X355710Y231553D02*
X355705Y231511D01*
G01X357604Y214965D02*
X357608Y215117D01*
G01X357599Y214866D02*
X357604Y214965D01*
G01X357595Y214824D02*
X357599Y214866D01*
G01X359642Y231413D02*
X359638Y231260D01*
G01X359647Y231511D02*
X359642Y231413D01*
G01X359651Y231553D02*
X359647Y231511D01*
G01X361545Y214965D02*
X361550Y215117D01*
G01X361541Y214866D02*
X361545Y214965D01*
G01X361536Y214824D02*
X361541Y214866D01*
G01X363575Y231413D02*
X363570Y231260D01*
G01X363579Y231511D02*
X363575Y231413D01*
G01X363584Y231553D02*
X363579Y231511D01*
G01X365478Y214965D02*
X365482Y215117D01*
G01X365473Y214866D02*
X365478Y214965D01*
G01X365469Y214824D02*
X365473Y214866D01*
G01X367516Y231413D02*
X367512Y231260D01*
G01X367521Y231511D02*
X367516Y231413D01*
G01X367525Y231553D02*
X367521Y231511D01*
G01X347823Y232353D02*
X347818Y232147D01*
G01X347829Y232484D02*
X347823Y232353D01*
G01X347836Y232538D02*
X347829Y232484D01*
G01X351765Y232353D02*
X351759Y232147D01*
G01X351771Y232484D02*
X351765Y232353D01*
G01X351777Y232538D02*
X351771Y232484D01*
G01X349733Y214024D02*
X349739Y214231D01*
G01X349727Y213893D02*
X349733Y214024D01*
G01X349721Y213840D02*
X349727Y213893D01*
G01X355697Y232353D02*
X355692Y232147D01*
G01X355703Y232484D02*
X355697Y232353D01*
G01X355710Y232538D02*
X355703Y232484D01*
G01X353675Y214024D02*
X353680Y214231D01*
G01X353669Y213893D02*
X353675Y214024D01*
G01X353662Y213840D02*
X353669Y213893D01*
G01X359639Y232353D02*
X359633Y232147D01*
G01X359645Y232484D02*
X359639Y232353D01*
G01X359651Y232538D02*
X359645Y232484D01*
G01X357607Y214024D02*
X357613Y214231D01*
G01X357601Y213893D02*
X357607Y214024D01*
G01X357595Y213840D02*
X357601Y213893D01*
G01X363571Y232353D02*
X363566Y232147D01*
G01X363577Y232484D02*
X363571Y232353D01*
G01X363584Y232538D02*
X363577Y232484D01*
G01X361549Y214024D02*
X361554Y214231D01*
G01X361543Y213893D02*
X361549Y214024D01*
G01X361536Y213840D02*
X361543Y213893D01*
G01X367513Y232353D02*
X367507Y232147D01*
G01X367519Y232484D02*
X367513Y232353D01*
G01X367525Y232538D02*
X367519Y232484D01*
G01X365481Y214024D02*
X365487Y214231D01*
G01X365475Y213893D02*
X365481Y214024D01*
G01X365469Y213840D02*
X365475Y213893D01*
G01X371445Y232353D02*
X371440Y232147D01*
G01X371451Y232484D02*
X371445Y232353D01*
G01X371458Y232538D02*
X371451Y232484D01*
G01X369423Y214024D02*
X369428Y214231D01*
G01X369417Y213893D02*
X369423Y214024D01*
G01X369410Y213840D02*
X369417Y213893D01*
G01X351504Y216168D02*
X351505Y216570D01*
G01X351501Y215841D02*
X351504Y216168D01*
G01X351497Y215645D02*
X351501Y215841D01*
G01X351493Y215615D02*
X351497Y215645D01*
G01X357868Y230209D02*
X357867Y229807D01*
G01X357871Y230537D02*
X357868Y230209D01*
G01X357875Y230733D02*
X357871Y230537D01*
G01X357879Y230762D02*
X357875Y230733D01*
G01X359378Y216168D02*
X359379Y216570D01*
G01X359375Y215841D02*
X359378Y216168D01*
G01X359371Y215645D02*
X359375Y215841D01*
G01X359367Y215615D02*
X359371Y215645D01*
G01X365742Y230209D02*
X365741Y229807D01*
G01X365745Y230537D02*
X365742Y230209D01*
G01X365749Y230733D02*
X365745Y230537D01*
G01X365753Y230762D02*
X365749Y230733D01*
G01X367252Y216168D02*
X367253Y216570D01*
G01X367249Y215841D02*
X367252Y216168D01*
G01X367245Y215645D02*
X367249Y215841D01*
G01X367241Y215615D02*
X367245Y215645D01*
G01X373616Y230209D02*
X373615Y229807D01*
G01X373619Y230537D02*
X373616Y230209D01*
G01X373623Y230733D02*
X373619Y230537D01*
G01X373627Y230762D02*
X373623Y230733D01*
G01X375126Y216168D02*
X375127Y216570D01*
G01X375123Y215841D02*
X375126Y216168D01*
G01X375119Y215645D02*
X375123Y215841D01*
G01X375115Y215615D02*
X375119Y215645D01*
G01X410553Y230768D02*
X410552Y230762D01*
G01X410553Y230771D02*
Y230768D01*
G01X410554Y230772D02*
X410553Y230771D01*
G01X409055Y215610D02*
X409056Y215615D01*
G01X409055Y215606D02*
Y215610D01*
G01X409054Y215605D02*
X409055Y215606D01*
G01X418427Y230768D02*
X418426Y230762D01*
G01X418427Y230771D02*
Y230768D01*
G01X418428Y230772D02*
X418427Y230771D01*
G01X416929Y215610D02*
X416930Y215615D01*
G01X416929Y215606D02*
Y215610D01*
G01X416928Y215605D02*
X416929Y215606D01*
G01X426301Y230768D02*
X426300Y230762D01*
G01X426301Y230771D02*
Y230768D01*
G01X426302Y230772D02*
X426301Y230771D01*
G01X347561Y215606D02*
X347562Y215605D01*
G01X347561Y215610D02*
Y215606D01*
G01X347560Y215615D02*
X347561Y215610D01*
G01X353937Y230771D02*
X353936Y230772D01*
G01X353937Y230768D02*
Y230771D01*
G01X353938Y230762D02*
X353937Y230768D01*
G01X355435Y215606D02*
X355436Y215605D01*
G01X355435Y215610D02*
Y215606D01*
G01X355434Y215615D02*
X355435Y215610D01*
G01X361811Y230771D02*
X361810Y230772D01*
G01X361811Y230768D02*
Y230771D01*
G01X361812Y230762D02*
X361811Y230768D01*
G01X363309Y215606D02*
X363310Y215605D01*
G01X363309Y215610D02*
Y215606D01*
G01X363308Y215615D02*
X363309Y215610D01*
G01X351762Y213893D02*
X351768Y213840D01*
G01X351756Y214024D02*
X351762Y213893D01*
G01X351750Y214231D02*
X351756Y214024D01*
G01X353669Y232484D02*
X353662Y232538D01*
G01X353675Y232353D02*
X353669Y232484D01*
G01X353680Y232147D02*
X353675Y232353D01*
G01X355703Y213893D02*
X355710Y213840D01*
G01X355697Y214024D02*
X355703Y213893D01*
G01X355692Y214231D02*
X355697Y214024D01*
G01X357610Y232484D02*
X357604Y232538D01*
G01X357616Y232353D02*
X357610Y232484D01*
G01X357622Y232147D02*
X357616Y232353D01*
G01X359636Y213893D02*
X359642Y213840D01*
G01X359630Y214024D02*
X359636Y213893D01*
G01X359624Y214231D02*
X359630Y214024D01*
G01X361543Y232484D02*
X361536Y232538D01*
G01X361549Y232353D02*
X361543Y232484D01*
G01X361554Y232147D02*
X361549Y232353D01*
G01X363577Y213893D02*
X363584Y213840D01*
G01X363571Y214024D02*
X363577Y213893D01*
G01X363566Y214231D02*
X363571Y214024D01*
G01X365484Y232484D02*
X365478Y232538D01*
G01X365490Y232353D02*
X365484Y232484D01*
G01X365496Y232147D02*
X365490Y232353D01*
G01X367510Y213893D02*
X367516Y213840D01*
G01X367504Y214024D02*
X367510Y213893D01*
G01X367498Y214231D02*
X367504Y214024D01*
G01X369417Y232484D02*
X369410Y232538D01*
G01X369423Y232353D02*
X369417Y232484D01*
G01X369428Y232147D02*
X369423Y232353D01*
G01X371451Y213893D02*
X371458Y213840D01*
G01X371445Y214024D02*
X371451Y213893D01*
G01X371440Y214231D02*
X371445Y214024D01*
G01X373358Y232484D02*
X373352Y232538D01*
G01X373364Y232353D02*
X373358Y232484D01*
G01X373370Y232147D02*
X373364Y232353D01*
G01X375384Y213893D02*
X375390Y213840D01*
G01X375378Y214024D02*
X375384Y213893D01*
G01X375372Y214231D02*
X375378Y214024D01*
G01X351763Y214866D02*
X351768Y214824D01*
G01X351759Y214965D02*
X351763Y214866D01*
G01X351755Y215117D02*
X351759Y214965D01*
G01X353667Y231511D02*
X353662Y231553D01*
G01X353671Y231413D02*
X353667Y231511D01*
G01X353676Y231260D02*
X353671Y231413D01*
G01X355705Y214866D02*
X355710Y214824D01*
G01X355701Y214965D02*
X355705Y214866D01*
G01X355696Y215117D02*
X355701Y214965D01*
G01X357609Y231511D02*
X357604Y231553D01*
G01X357613Y231413D02*
X357609Y231511D01*
G01X357617Y231260D02*
X357613Y231413D01*
G01X359637Y214866D02*
X359642Y214824D01*
G01X359633Y214965D02*
X359637Y214866D01*
G01X359629Y215117D02*
X359633Y214965D01*
G01X361541Y231511D02*
X361536Y231553D01*
G01X361545Y231413D02*
X361541Y231511D01*
G01X361550Y231260D02*
X361545Y231413D01*
G01X363579Y214866D02*
X363584Y214824D01*
G01X363575Y214965D02*
X363579Y214866D01*
G01X363570Y215117D02*
X363575Y214965D01*
G01X365483Y231511D02*
X365478Y231553D01*
G01X365487Y231413D02*
X365483Y231511D01*
G01X365491Y231260D02*
X365487Y231413D01*
G01X367511Y214866D02*
X367516Y214824D01*
G01X367507Y214965D02*
X367511Y214866D01*
G01X367503Y215117D02*
X367507Y214965D01*
G01X369415Y231511D02*
X369410Y231553D01*
G01X369419Y231413D02*
X369415Y231511D01*
G01X369424Y231260D02*
X369419Y231413D01*
G01X371453Y214866D02*
X371458Y214824D01*
G01X371449Y214965D02*
X371453Y214866D01*
G01X371444Y215117D02*
X371449Y214965D01*
G01X373357Y231511D02*
X373352Y231553D01*
G01X373361Y231413D02*
X373357Y231511D01*
G01X373365Y231260D02*
X373361Y231413D01*
G01X375385Y214866D02*
X375390Y214824D01*
G01X375381Y214965D02*
X375385Y214866D01*
G01X375377Y215117D02*
X375381Y214965D01*
G01X357866Y215645D02*
X357870Y215615D01*
G01X357861Y215841D02*
X357866Y215645D01*
G01X357859Y216168D02*
X357861Y215841D01*
G01X357858Y216570D02*
X357859Y216168D01*
G01X359380Y230733D02*
X359376Y230762D01*
G01X359385Y230537D02*
X359380Y230733D01*
G01X359387Y230209D02*
X359385Y230537D01*
G01X359388Y229807D02*
X359387Y230209D01*
G01X365740Y215645D02*
X365744Y215615D01*
G01X365735Y215841D02*
X365740Y215645D01*
G01X365733Y216168D02*
X365735Y215841D01*
G01X365732Y216570D02*
X365733Y216168D01*
G01X367255Y230733D02*
X367250Y230762D01*
G01X367259Y230537D02*
X367255Y230733D01*
G01X367261Y230209D02*
X367259Y230537D01*
G01X367262Y229807D02*
X367261Y230209D01*
G01X373614Y215645D02*
X373618Y215615D01*
G01X373610Y215841D02*
X373614Y215645D01*
G01X373607Y216168D02*
X373610Y215841D01*
G01X373606Y216570D02*
X373607Y216168D01*
G01X375129Y230733D02*
X375124Y230762D01*
G01X375133Y230537D02*
X375129Y230733D01*
G01X375135Y230209D02*
X375133Y230537D01*
G01X375136Y229807D02*
X375135Y230209D01*
G01X355440Y230699D02*
X355436Y230772D01*
G01X355443Y230490D02*
X355440Y230699D01*
G01X355446Y230178D02*
X355443Y230490D01*
G01X355447Y229807D02*
X355446Y230178D01*
G01X355444Y231608D02*
X355436Y231756D01*
G01X355451Y231193D02*
X355444Y231608D01*
G01X355456Y230573D02*
X355451Y231193D01*
G01X355458Y229826D02*
X355456Y230573D01*
G01X361802Y214770D02*
X361810Y214621D01*
G01X361795Y215184D02*
X361802Y214770D01*
G01X361790Y215804D02*
X361795Y215184D01*
G01X361788Y216551D02*
X361790Y215804D01*
G01X361806Y215678D02*
X361810Y215605D01*
G01X361803Y215887D02*
X361806Y215678D01*
G01X361800Y216200D02*
X361803Y215887D01*
G01X361799Y216570D02*
X361800Y216200D01*
G01X363314Y230699D02*
X363310Y230772D01*
G01X363317Y230490D02*
X363314Y230699D01*
G01X363320Y230178D02*
X363317Y230490D01*
G01X363321Y229807D02*
X363320Y230178D01*
G01X363318Y231608D02*
X363310Y231756D01*
G01X363325Y231193D02*
X363318Y231608D01*
G01X363330Y230573D02*
X363325Y231193D01*
G01X363332Y229826D02*
X363330Y230573D01*
G01X369676Y214770D02*
X369684Y214621D01*
G01X369669Y215184D02*
X369676Y214770D01*
G01X369664Y215804D02*
X369669Y215184D01*
G01X369662Y216551D02*
X369664Y215804D01*
G01X369680Y215678D02*
X369684Y215605D01*
G01X369677Y215887D02*
X369680Y215678D01*
G01X369674Y216200D02*
X369677Y215887D01*
G01X369673Y216570D02*
X369674Y216200D01*
G01X371188Y230699D02*
X371184Y230772D01*
G01X371191Y230490D02*
X371188Y230699D01*
G01X371194Y230178D02*
X371191Y230490D01*
G01X371195Y229807D02*
X371194Y230178D01*
G01X371192Y231608D02*
X371184Y231756D01*
G01X371199Y231193D02*
X371192Y231608D01*
G01X371204Y230573D02*
X371199Y231193D01*
G01X371206Y229826D02*
X371204Y230573D01*
G01X377550Y214770D02*
X377558Y214621D01*
G01X377543Y215184D02*
X377550Y214770D01*
G01X377538Y215804D02*
X377543Y215184D01*
G01X377536Y216551D02*
X377538Y215804D01*
G01X377554Y215678D02*
X377558Y215605D01*
G01X377551Y215887D02*
X377554Y215678D01*
G01X377548Y216200D02*
X377551Y215887D01*
G01X377547Y216570D02*
X377548Y216200D01*
G01X379062Y230699D02*
X379058Y230772D01*
G01X379065Y230490D02*
X379062Y230699D01*
G01X379068Y230178D02*
X379065Y230490D01*
G01X379069Y229807D02*
X379068Y230178D01*
G01X379066Y231608D02*
X379058Y231756D01*
G01X379073Y231193D02*
X379066Y231608D01*
G01X379078Y230573D02*
X379073Y231193D01*
G01X379080Y229826D02*
X379078Y230573D01*
G01X363330Y215804D02*
X363332Y216551D01*
G01X363325Y215184D02*
X363330Y215804D01*
G01X363318Y214770D02*
X363325Y215184D01*
G01X363310Y214621D02*
X363318Y214770D01*
G01X369664Y230573D02*
X369662Y229826D01*
G01X369669Y231193D02*
X369664Y230573D01*
G01X369676Y231608D02*
X369669Y231193D01*
G01X369684Y231756D02*
X369676Y231608D01*
G01X371204Y215804D02*
X371206Y216551D01*
G01X371199Y215184D02*
X371204Y215804D01*
G01X371192Y214770D02*
X371199Y215184D01*
G01X371184Y214621D02*
X371192Y214770D01*
G01X377538Y230573D02*
X377536Y229826D01*
G01X377543Y231193D02*
X377538Y230573D01*
G01X377550Y231608D02*
X377543Y231193D01*
G01X377558Y231756D02*
X377550Y231608D01*
G01X379078Y215804D02*
X379080Y216551D01*
G01X379073Y215184D02*
X379078Y215804D01*
G01X379066Y214770D02*
X379073Y215184D01*
G01X379058Y214621D02*
X379066Y214770D01*
G01X385412Y230573D02*
X385410Y229826D01*
G01X385417Y231193D02*
X385412Y230573D01*
G01X385424Y231608D02*
X385417Y231193D01*
G01X385432Y231756D02*
X385424Y231608D01*
G01X386952Y215804D02*
X386954Y216551D01*
G01X386947Y215184D02*
X386952Y215804D01*
G01X386940Y214770D02*
X386947Y215184D01*
G01X386932Y214621D02*
X386940Y214770D01*
G01X363320Y216200D02*
X363321Y216570D01*
G01X363317Y215887D02*
X363320Y216200D01*
G01X363314Y215678D02*
X363317Y215887D01*
G01X363310Y215605D02*
X363314Y215678D01*
G01X369674Y230178D02*
X369673Y229807D01*
G01X369677Y230490D02*
X369674Y230178D01*
G01X369680Y230699D02*
X369677Y230490D01*
G01X369684Y230772D02*
X369680Y230699D01*
G01X371194Y216200D02*
X371195Y216570D01*
G01X371191Y215887D02*
X371194Y216200D01*
G01X371188Y215678D02*
X371191Y215887D01*
G01X371184Y215605D02*
X371188Y215678D01*
G01X377548Y230178D02*
X377547Y229807D01*
G01X377551Y230490D02*
X377548Y230178D01*
G01X377554Y230699D02*
X377551Y230490D01*
G01X377558Y230772D02*
X377554Y230699D01*
G01X379068Y216200D02*
X379069Y216570D01*
G01X379065Y215887D02*
X379068Y216200D01*
G01X379062Y215678D02*
X379065Y215887D01*
G01X379058Y215605D02*
X379062Y215678D01*
G01X385422Y230178D02*
X385421Y229807D01*
G01X385425Y230490D02*
X385422Y230178D01*
G01X385428Y230699D02*
X385425Y230490D01*
G01X385432Y230772D02*
X385428Y230699D01*
G01X386942Y216200D02*
X386943Y216570D01*
G01X386939Y215887D02*
X386942Y216200D01*
G01X386936Y215678D02*
X386939Y215887D01*
G01X386932Y215605D02*
X386936Y215678D01*
G01X369419Y214965D02*
X369424Y215117D01*
G01X369415Y214866D02*
X369419Y214965D01*
G01X369410Y214824D02*
X369415Y214866D01*
G01X371449Y231413D02*
X371444Y231260D01*
G01X371453Y231511D02*
X371449Y231413D01*
G01X371458Y231553D02*
X371453Y231511D01*
G01X373352Y214965D02*
X373356Y215117D01*
G01X373347Y214866D02*
X373352Y214965D01*
G01X373343Y214824D02*
X373347Y214866D01*
G01X375390Y231413D02*
X375386Y231260D01*
G01X375395Y231511D02*
X375390Y231413D01*
G01X375399Y231553D02*
X375395Y231511D01*
G01X377293Y214965D02*
X377298Y215117D01*
G01X377289Y214866D02*
X377293Y214965D01*
G01X377284Y214824D02*
X377289Y214866D01*
G01X379323Y231413D02*
X379318Y231260D01*
G01X379327Y231511D02*
X379323Y231413D01*
G01X379332Y231553D02*
X379327Y231511D01*
G01X381226Y214965D02*
X381230Y215117D01*
G01X381221Y214866D02*
X381226Y214965D01*
G01X381217Y214824D02*
X381221Y214866D01*
G01X383264Y231413D02*
X383260Y231260D01*
G01X383269Y231511D02*
X383264Y231413D01*
G01X383273Y231553D02*
X383269Y231511D01*
G01X385167Y214965D02*
X385172Y215117D01*
G01X385163Y214866D02*
X385167Y214965D01*
G01X385158Y214824D02*
X385163Y214866D01*
G01X387197Y231413D02*
X387192Y231260D01*
G01X387201Y231511D02*
X387197Y231413D01*
G01X387206Y231553D02*
X387201Y231511D01*
G01X389100Y214965D02*
X389104Y215117D01*
G01X389095Y214866D02*
X389100Y214965D01*
G01X389091Y214824D02*
X389095Y214866D01*
G01X391138Y231413D02*
X391134Y231260D01*
G01X391143Y231511D02*
X391138Y231413D01*
G01X391147Y231553D02*
X391143Y231511D01*
G01X393041Y214965D02*
X393046Y215117D01*
G01X393037Y214866D02*
X393041Y214965D01*
G01X393032Y214824D02*
X393037Y214866D01*
G01X395071Y231413D02*
X395066Y231260D01*
G01X395075Y231511D02*
X395071Y231413D01*
G01X395080Y231553D02*
X395075Y231511D01*
G01X375387Y232353D02*
X375381Y232147D01*
G01X375393Y232484D02*
X375387Y232353D01*
G01X375399Y232538D02*
X375393Y232484D01*
G01X373355Y214024D02*
X373361Y214231D01*
G01X373349Y213893D02*
X373355Y214024D01*
G01X373343Y213840D02*
X373349Y213893D01*
G01X379319Y232353D02*
X379314Y232147D01*
G01X379325Y232484D02*
X379319Y232353D01*
G01X379332Y232538D02*
X379325Y232484D01*
G01X377297Y214024D02*
X377302Y214231D01*
G01X377291Y213893D02*
X377297Y214024D01*
G01X377284Y213840D02*
X377291Y213893D01*
G01X383261Y232353D02*
X383255Y232147D01*
G01X383267Y232484D02*
X383261Y232353D01*
G01X383273Y232538D02*
X383267Y232484D01*
G01X381229Y214024D02*
X381235Y214231D01*
G01X381223Y213893D02*
X381229Y214024D01*
G01X381217Y213840D02*
X381223Y213893D01*
G01X387193Y232353D02*
X387188Y232147D01*
G01X387199Y232484D02*
X387193Y232353D01*
G01X387206Y232538D02*
X387199Y232484D01*
G01X385171Y214024D02*
X385176Y214231D01*
G01X385165Y213893D02*
X385171Y214024D01*
G01X385158Y213840D02*
X385165Y213893D01*
G01X391135Y232353D02*
X391129Y232147D01*
G01X391141Y232484D02*
X391135Y232353D01*
G01X391147Y232538D02*
X391141Y232484D01*
G01X389103Y214024D02*
X389109Y214231D01*
G01X389097Y213893D02*
X389103Y214024D01*
G01X389091Y213840D02*
X389097Y213893D01*
G01X395067Y232353D02*
X395062Y232147D01*
G01X395074Y232484D02*
X395067Y232353D01*
G01X395080Y232538D02*
X395074Y232484D01*
G01X393045Y214024D02*
X393050Y214231D01*
G01X393039Y213893D02*
X393045Y214024D01*
G01X393032Y213840D02*
X393039Y213893D01*
G01X381490Y230209D02*
X381489Y229807D01*
G01X381493Y230537D02*
X381490Y230209D01*
G01X381497Y230733D02*
X381493Y230537D01*
G01X381502Y230762D02*
X381497Y230733D01*
G01X383000Y216168D02*
X383001Y216570D01*
G01X382997Y215841D02*
X383000Y216168D01*
G01X382993Y215645D02*
X382997Y215841D01*
G01X382989Y215615D02*
X382993Y215645D01*
G01X389364Y230209D02*
X389363Y229807D01*
G01X389367Y230537D02*
X389364Y230209D01*
G01X389371Y230733D02*
X389367Y230537D01*
G01X389376Y230762D02*
X389371Y230733D01*
G01X390874Y216168D02*
X390875Y216570D01*
G01X390871Y215841D02*
X390874Y216168D01*
G01X390867Y215645D02*
X390871Y215841D01*
G01X390863Y215615D02*
X390867Y215645D01*
G01X397238Y230209D02*
X397237Y229807D01*
G01X397241Y230537D02*
X397238Y230209D01*
G01X397245Y230733D02*
X397241Y230537D01*
G01X397250Y230762D02*
X397245Y230733D01*
G01X398748Y216168D02*
X398749Y216570D01*
G01X398745Y215841D02*
X398748Y216168D01*
G01X398741Y215645D02*
X398745Y215841D01*
G01X398737Y215615D02*
X398741Y215645D01*
G01X424803Y215610D02*
X424804Y215615D01*
G01X424803Y215606D02*
Y215610D01*
G01X424802Y215605D02*
X424803Y215606D01*
G01X347561Y214622D02*
X347562Y214621D01*
G01X347561Y214624D02*
Y214622D01*
G01X347560Y214627D02*
X347561Y214624D01*
G01X355435Y214622D02*
X355436Y214621D01*
G01X355435Y214624D02*
Y214622D01*
G01X355434Y214627D02*
X355435Y214624D01*
G01X353937Y231756D02*
X353936D01*
G01X353937Y231754D02*
Y231756D01*
G01X353938Y231750D02*
X353937Y231754D01*
G01X369685Y230771D02*
X369684Y230772D01*
G01X369685Y230768D02*
Y230771D01*
G01X369686Y230762D02*
X369685Y230768D01*
G01X371183Y215606D02*
X371184Y215605D01*
G01X371183Y215610D02*
Y215606D01*
G01X371182Y215615D02*
X371183Y215610D01*
G01X377559Y230771D02*
X377558Y230772D01*
G01X377559Y230768D02*
Y230771D01*
G01X377560Y230762D02*
X377559Y230768D01*
G01X379057Y215606D02*
X379058Y215605D01*
G01X379057Y215610D02*
Y215606D01*
G01X379056Y215615D02*
X379057Y215610D01*
G01X385433Y230771D02*
X385432Y230772D01*
G01X385433Y230768D02*
Y230771D01*
G01X385434Y230762D02*
X385433Y230768D01*
G01X386931Y215606D02*
X386932Y215605D01*
G01X386931Y215610D02*
Y215606D01*
G01X386930Y215615D02*
X386931Y215610D01*
G01X393296Y216197D02*
X393295Y216570D01*
G01X393299Y215887D02*
X393296Y216197D01*
G01X393302Y215680D02*
X393299Y215887D01*
G01X393306Y215605D02*
X393302Y215680D01*
G01X394816Y230180D02*
X394817Y229807D01*
G01X394813Y230490D02*
X394816Y230180D01*
G01X394810Y230698D02*
X394813Y230490D01*
G01X394806Y230772D02*
X394810Y230698D01*
G01X377291Y232484D02*
X377284Y232538D01*
G01X377297Y232353D02*
X377291Y232484D01*
G01X377302Y232147D02*
X377297Y232353D01*
G01X379325Y213893D02*
X379332Y213840D01*
G01X379319Y214024D02*
X379325Y213893D01*
G01X379314Y214231D02*
X379319Y214024D01*
G01X381232Y232484D02*
X381226Y232538D01*
G01X381238Y232353D02*
X381232Y232484D01*
G01X381244Y232147D02*
X381238Y232353D01*
G01X383258Y213893D02*
X383264Y213840D01*
G01X383252Y214024D02*
X383258Y213893D01*
G01X383246Y214231D02*
X383252Y214024D01*
G01X385165Y232484D02*
X385158Y232538D01*
G01X385171Y232353D02*
X385165Y232484D01*
G01X385176Y232147D02*
X385171Y232353D01*
G01X387199Y213893D02*
X387206Y213840D01*
G01X387193Y214024D02*
X387199Y213893D01*
G01X387188Y214231D02*
X387193Y214024D01*
G01X389106Y232484D02*
X389100Y232538D01*
G01X389112Y232353D02*
X389106Y232484D01*
G01X389118Y232147D02*
X389112Y232353D01*
G01X391132Y213893D02*
X391138Y213840D01*
G01X391126Y214024D02*
X391132Y213893D01*
G01X391120Y214231D02*
X391126Y214024D01*
G01X393039Y232484D02*
X393032Y232538D01*
G01X393045Y232353D02*
X393039Y232484D01*
G01X393050Y232147D02*
X393045Y232353D01*
G01X395074Y213893D02*
X395080Y213840D01*
G01X395067Y214024D02*
X395074Y213893D01*
G01X395062Y214231D02*
X395067Y214024D01*
G01X396980Y232484D02*
X396974Y232538D01*
G01X396986Y232353D02*
X396980Y232484D01*
G01X396992Y232147D02*
X396986Y232353D01*
G01X399006Y213893D02*
X399012Y213840D01*
G01X399000Y214024D02*
X399006Y213893D01*
G01X398994Y214231D02*
X399000Y214024D01*
G01X377289Y231511D02*
X377284Y231553D01*
G01X377293Y231413D02*
X377289Y231511D01*
G01X377298Y231260D02*
X377293Y231413D01*
G01X379327Y214866D02*
X379332Y214824D01*
G01X379323Y214965D02*
X379327Y214866D01*
G01X379318Y215117D02*
X379323Y214965D01*
G01X381231Y231511D02*
X381226Y231553D01*
G01X381235Y231413D02*
X381231Y231511D01*
G01X381239Y231260D02*
X381235Y231413D01*
G01X383259Y214866D02*
X383264Y214824D01*
G01X383255Y214965D02*
X383259Y214866D01*
G01X383251Y215117D02*
X383255Y214965D01*
G01X385163Y231511D02*
X385158Y231553D01*
G01X385167Y231413D02*
X385163Y231511D01*
G01X385172Y231260D02*
X385167Y231413D01*
G01X387201Y214866D02*
X387206Y214824D01*
G01X387197Y214965D02*
X387201Y214866D01*
G01X387192Y215117D02*
X387197Y214965D01*
G01X389105Y231511D02*
X389100Y231553D01*
G01X389109Y231413D02*
X389105Y231511D01*
G01X389113Y231260D02*
X389109Y231413D01*
G01X391133Y214866D02*
X391138Y214824D01*
G01X391129Y214965D02*
X391133Y214866D01*
G01X391125Y215117D02*
X391129Y214965D01*
G01X393037Y231511D02*
X393032Y231553D01*
G01X393041Y231413D02*
X393037Y231511D01*
G01X393046Y231260D02*
X393041Y231413D01*
G01X395075Y214866D02*
X395080Y214824D01*
G01X395071Y214965D02*
X395075Y214866D01*
G01X395066Y215117D02*
X395071Y214965D01*
G01X396979Y231511D02*
X396974Y231553D01*
G01X396983Y231413D02*
X396979Y231511D01*
G01X396987Y231260D02*
X396983Y231413D01*
G01X399007Y214866D02*
X399012Y214824D01*
G01X399003Y214965D02*
X399007Y214866D01*
G01X398999Y215117D02*
X399003Y214965D01*
G01X381488Y215645D02*
X381492Y215615D01*
G01X381484Y215841D02*
X381488Y215645D01*
G01X381481Y216168D02*
X381484Y215841D01*
G01X381480Y216570D02*
X381481Y216168D01*
G01X383003Y230733D02*
X382998Y230762D01*
G01X383007Y230537D02*
X383003Y230733D01*
G01X383009Y230209D02*
X383007Y230537D01*
G01X383010Y229807D02*
X383009Y230209D01*
G01X389362Y215645D02*
X389366Y215615D01*
G01X389358Y215841D02*
X389362Y215645D01*
G01X389355Y216168D02*
X389358Y215841D01*
G01X389354Y216570D02*
X389355Y216168D01*
G01X390877Y230733D02*
X390872Y230762D01*
G01X390881Y230537D02*
X390877Y230733D01*
G01X390883Y230209D02*
X390881Y230537D01*
G01X390884Y229807D02*
X390883Y230209D01*
G01X397236Y215645D02*
X397240Y215615D01*
G01X397232Y215841D02*
X397236Y215645D01*
G01X397229Y216168D02*
X397232Y215841D01*
G01X397228Y216570D02*
X397229Y216168D01*
G01X398751Y230733D02*
X398746Y230762D01*
G01X398755Y230537D02*
X398751Y230733D01*
G01X398757Y230209D02*
X398755Y230537D01*
G01X398758Y229807D02*
X398757Y230209D01*
G01X385424Y214770D02*
X385432Y214621D01*
G01X385417Y215184D02*
X385424Y214770D01*
G01X385412Y215804D02*
X385417Y215184D01*
G01X385410Y216551D02*
X385412Y215804D01*
G01X385428Y215678D02*
X385432Y215605D01*
G01X385425Y215887D02*
X385428Y215678D01*
G01X385422Y216200D02*
X385425Y215887D01*
G01X385421Y216570D02*
X385422Y216200D01*
G01X386936Y230699D02*
X386932Y230772D01*
G01X386939Y230490D02*
X386936Y230699D01*
G01X386942Y230178D02*
X386939Y230490D01*
G01X386943Y229807D02*
X386942Y230178D01*
G01X386940Y231608D02*
X386932Y231756D01*
G01X386947Y231193D02*
X386940Y231608D01*
G01X386952Y230573D02*
X386947Y231193D01*
G01X386954Y229826D02*
X386952Y230573D01*
G01X393298Y214770D02*
X393306Y214621D01*
G01X393291Y215184D02*
X393298Y214770D01*
G01X393286Y215804D02*
X393291Y215184D01*
G01X393284Y216551D02*
X393286Y215804D01*
G01X394814Y231608D02*
X394806Y231756D01*
G01X394821Y231193D02*
X394814Y231608D01*
G01X394826Y230573D02*
X394821Y231193D01*
G01X394828Y229826D02*
X394826Y230573D01*
G01X401172Y214770D02*
X401180Y214621D01*
G01X401165Y215184D02*
X401172Y214770D01*
G01X401160Y215804D02*
X401165Y215184D01*
G01X401158Y216551D02*
X401160Y215804D01*
G01X402688Y231608D02*
X402680Y231756D01*
G01X402695Y231193D02*
X402688Y231608D01*
G01X402700Y230573D02*
X402695Y231193D01*
G01X402702Y229826D02*
X402700Y230573D01*
G01X393302Y230698D02*
X393306Y230772D01*
G01X393299Y230490D02*
X393302Y230698D01*
G01X393296Y230180D02*
X393299Y230490D01*
G01X393295Y229807D02*
X393296Y230180D01*
G01X394810Y215680D02*
X394806Y215605D01*
G01X394813Y215887D02*
X394810Y215680D01*
G01X394816Y216197D02*
X394813Y215887D01*
G01X394817Y216570D02*
X394816Y216197D01*
G01X401176Y230698D02*
X401180Y230772D01*
G01X401173Y230490D02*
X401176Y230698D01*
G01X401170Y230180D02*
X401173Y230490D01*
G01X401169Y229807D02*
X401170Y230180D01*
G01X402684Y215680D02*
X402680Y215605D01*
G01X402688Y215887D02*
X402684Y215680D01*
G01X402690Y216197D02*
X402688Y215887D01*
G01X402691Y216570D02*
X402690Y216197D01*
G01X393286Y230573D02*
X393284Y229826D01*
G01X393291Y231193D02*
X393286Y230573D01*
G01X393298Y231608D02*
X393291Y231193D01*
G01X393306Y231756D02*
X393298Y231608D01*
G01X394826Y215804D02*
X394828Y216551D01*
G01X394821Y215184D02*
X394826Y215804D01*
G01X394814Y214770D02*
X394821Y215184D01*
G01X394806Y214621D02*
X394814Y214770D01*
G01X401160Y230573D02*
X401158Y229826D01*
G01X401165Y231193D02*
X401160Y230573D01*
G01X401172Y231608D02*
X401165Y231193D01*
G01X401180Y231756D02*
X401172Y231608D01*
G01X402700Y215804D02*
X402702Y216551D01*
G01X402695Y215184D02*
X402700Y215804D01*
G01X402688Y214770D02*
X402695Y215184D01*
G01X402680Y214621D02*
X402688Y214770D01*
G01X409034Y230573D02*
X409032Y229826D01*
G01X409039Y231193D02*
X409034Y230573D01*
G01X409046Y231608D02*
X409039Y231193D01*
G01X409054Y231756D02*
X409046Y231608D01*
G01X410574Y215804D02*
X410576Y216551D01*
G01X410569Y215184D02*
X410574Y215804D01*
G01X410562Y214770D02*
X410569Y215184D01*
G01X410554Y214621D02*
X410562Y214770D01*
G01X409044Y230178D02*
X409043Y229807D01*
G01X409047Y230490D02*
X409044Y230178D01*
G01X409050Y230699D02*
X409047Y230490D01*
G01X409054Y230772D02*
X409050Y230699D01*
G01X410564Y216200D02*
X410565Y216570D01*
G01X410562Y215887D02*
X410564Y216200D01*
G01X410558Y215678D02*
X410562Y215887D01*
G01X410554Y215605D02*
X410558Y215678D01*
G01X393307Y215606D02*
X393306Y215605D01*
G01X393307Y215610D02*
Y215606D01*
G01X393308Y215617D02*
X393307Y215610D01*
G01X394805Y230771D02*
X394806Y230772D01*
G01X394805Y230768D02*
Y230771D01*
G01X394804Y230760D02*
X394805Y230768D01*
G01X401181Y215606D02*
X401180Y215605D01*
G01X401181Y215610D02*
Y215606D01*
G01X401182Y215617D02*
X401181Y215610D01*
G01X402679Y230771D02*
X402680Y230772D01*
G01X402679Y230768D02*
Y230771D01*
G01X402678Y230760D02*
X402679Y230768D01*
G01X396974Y214965D02*
X396978Y215117D01*
G01X396969Y214866D02*
X396974Y214965D01*
G01X396965Y214824D02*
X396969Y214866D01*
G01X399012Y231413D02*
X399008Y231260D01*
G01X399017Y231511D02*
X399012Y231413D01*
G01X399021Y231553D02*
X399017Y231511D01*
G01X400915Y214965D02*
X400920Y215117D01*
G01X400911Y214866D02*
X400915Y214965D01*
G01X400906Y214824D02*
X400911Y214866D01*
G01X402945Y231413D02*
X402941Y231260D01*
G01X402949Y231511D02*
X402945Y231413D01*
G01X402954Y231553D02*
X402949Y231511D01*
G01X404848Y214965D02*
X404852Y215117D01*
G01X404843Y214866D02*
X404848Y214965D01*
G01X404839Y214824D02*
X404843Y214866D01*
G01X406886Y231413D02*
X406882Y231260D01*
G01X406891Y231511D02*
X406886Y231413D01*
G01X406895Y231553D02*
X406891Y231511D01*
G01X408789Y214965D02*
X408794Y215117D01*
G01X408785Y214866D02*
X408789Y214965D01*
G01X408780Y214824D02*
X408785Y214866D01*
G01X410819Y231413D02*
X410815Y231260D01*
G01X410823Y231511D02*
X410819Y231413D01*
G01X410828Y231553D02*
X410823Y231511D01*
G01X412722Y214965D02*
X412726Y215117D01*
G01X412717Y214866D02*
X412722Y214965D01*
G01X412713Y214824D02*
X412717Y214866D01*
G01X414760Y231413D02*
X414756Y231260D01*
G01X414765Y231511D02*
X414760Y231413D01*
G01X414769Y231553D02*
X414765Y231511D01*
G01X416663Y214965D02*
X416668Y215117D01*
G01X416659Y214866D02*
X416663Y214965D01*
G01X416655Y214824D02*
X416659Y214866D01*
G01X418693Y231413D02*
X418689Y231260D01*
G01X418697Y231511D02*
X418693Y231413D01*
G01X418702Y231553D02*
X418697Y231511D01*
G01X399009Y232353D02*
X399003Y232147D01*
G01X399015Y232484D02*
X399009Y232353D01*
G01X399021Y232538D02*
X399015Y232484D01*
G01X396977Y214024D02*
X396983Y214231D01*
G01X396971Y213893D02*
X396977Y214024D01*
G01X396965Y213840D02*
X396971Y213893D01*
G01X402941Y232353D02*
X402936Y232147D01*
G01X402948Y232484D02*
X402941Y232353D01*
G01X402954Y232538D02*
X402948Y232484D01*
G01X400919Y214024D02*
X400924Y214231D01*
G01X400913Y213893D02*
X400919Y214024D01*
G01X400906Y213840D02*
X400913Y213893D01*
G01X406883Y232353D02*
X406877Y232147D01*
G01X406889Y232484D02*
X406883Y232353D01*
G01X406895Y232538D02*
X406889Y232484D01*
G01X404851Y214024D02*
X404857Y214231D01*
G01X404845Y213893D02*
X404851Y214024D01*
G01X404839Y213840D02*
X404845Y213893D01*
G01X410816Y232353D02*
X410810Y232147D01*
G01X410822Y232484D02*
X410816Y232353D01*
G01X410828Y232538D02*
X410822Y232484D01*
G01X408793Y214024D02*
X408798Y214231D01*
G01X408787Y213893D02*
X408793Y214024D01*
G01X408780Y213840D02*
X408787Y213893D01*
G01X414757Y232353D02*
X414751Y232147D01*
G01X414763Y232484D02*
X414757Y232353D01*
G01X414769Y232538D02*
X414763Y232484D01*
G01X412725Y214024D02*
X412731Y214231D01*
G01X412719Y213893D02*
X412725Y214024D01*
G01X412713Y213840D02*
X412719Y213893D01*
G01X418690Y232353D02*
X418684Y232147D01*
G01X418696Y232484D02*
X418690Y232353D01*
G01X418702Y232538D02*
X418696Y232484D01*
G01X416667Y214024D02*
X416673Y214231D01*
G01X416661Y213893D02*
X416667Y214024D01*
G01X416655Y213840D02*
X416661Y213893D01*
G01X405112Y230209D02*
X405111Y229807D01*
G01X405115Y230537D02*
X405112Y230209D01*
G01X405119Y230733D02*
X405115Y230537D01*
G01X405124Y230762D02*
X405119Y230733D01*
G01X406622Y216168D02*
X406623Y216570D01*
G01X406619Y215841D02*
X406622Y216168D01*
G01X406615Y215645D02*
X406619Y215841D01*
G01X406611Y215615D02*
X406615Y215645D01*
G01X412986Y230209D02*
X412985Y229807D01*
G01X412989Y230537D02*
X412986Y230209D01*
G01X412993Y230733D02*
X412989Y230537D01*
G01X412998Y230762D02*
X412993Y230733D01*
G01X414496Y216168D02*
X414497Y216570D01*
G01X414493Y215841D02*
X414496Y216168D01*
G01X414489Y215645D02*
X414493Y215841D01*
G01X414485Y215615D02*
X414489Y215645D01*
G01X420860Y230209D02*
X420859Y229807D01*
G01X420863Y230537D02*
X420860Y230209D01*
G01X420867Y230733D02*
X420863Y230537D01*
G01X420872Y230762D02*
X420867Y230733D01*
G01X422370Y216168D02*
X422371Y216570D01*
G01X422367Y215841D02*
X422370Y216168D01*
G01X422363Y215645D02*
X422367Y215841D01*
G01X422359Y215615D02*
X422363Y215645D01*
G01X363309Y214622D02*
X363310Y214621D01*
G01X363309Y214624D02*
Y214622D01*
G01X363308Y214627D02*
X363309Y214624D01*
G01X361811Y231756D02*
X361810D01*
G01X361811Y231754D02*
Y231756D01*
G01X361812Y231750D02*
X361811Y231754D01*
G01X371183Y214622D02*
X371184Y214621D01*
G01X371183Y214624D02*
Y214622D01*
G01X371182Y214627D02*
X371183Y214624D01*
G01X369685Y231756D02*
X369684D01*
G01X369685Y231754D02*
Y231756D01*
G01X369686Y231750D02*
X369685Y231754D01*
G01X379057Y214622D02*
X379058Y214621D01*
G01X379057Y214624D02*
Y214622D01*
G01X379056Y214627D02*
X379057Y214624D01*
G01X377559Y231756D02*
X377558D01*
G01X377559Y231754D02*
Y231756D01*
G01X377560Y231750D02*
X377559Y231754D01*
G01X409055Y230771D02*
X409054Y230772D01*
G01X409055Y230768D02*
Y230771D01*
G01X409056Y230762D02*
X409055Y230768D01*
G01X410553Y215606D02*
X410554Y215605D01*
G01X410553Y215610D02*
Y215606D01*
G01X410552Y215615D02*
X410553Y215610D01*
G01X401170Y216197D02*
X401169Y216570D01*
G01X401173Y215887D02*
X401170Y216197D01*
G01X401176Y215680D02*
X401173Y215887D01*
G01X401180Y215605D02*
X401176Y215680D01*
G01X402690Y230180D02*
X402691Y229807D01*
G01X402688Y230490D02*
X402690Y230180D01*
G01X402684Y230698D02*
X402688Y230490D01*
G01X402680Y230772D02*
X402684Y230698D01*
G01X400913Y232484D02*
X400906Y232538D01*
G01X400919Y232353D02*
X400913Y232484D01*
G01X400924Y232147D02*
X400919Y232353D01*
G01X402948Y213893D02*
X402954Y213840D01*
G01X402941Y214024D02*
X402948Y213893D01*
G01X402936Y214231D02*
X402941Y214024D01*
G01X404854Y232484D02*
X404848Y232538D01*
G01X404860Y232353D02*
X404854Y232484D01*
G01X404866Y232147D02*
X404860Y232353D01*
G01X406880Y213893D02*
X406886Y213840D01*
G01X406874Y214024D02*
X406880Y213893D01*
G01X406868Y214231D02*
X406874Y214024D01*
G01X408787Y232484D02*
X408780Y232538D01*
G01X408793Y232353D02*
X408787Y232484D01*
G01X408798Y232147D02*
X408793Y232353D01*
G01X410822Y213893D02*
X410828Y213840D01*
G01X410816Y214024D02*
X410822Y213893D01*
G01X410810Y214231D02*
X410816Y214024D01*
G01X412728Y232484D02*
X412722Y232538D01*
G01X412734Y232353D02*
X412728Y232484D01*
G01X412740Y232147D02*
X412734Y232353D01*
G01X414754Y213893D02*
X414760Y213840D01*
G01X414748Y214024D02*
X414754Y213893D01*
G01X414742Y214231D02*
X414748Y214024D01*
G01X416661Y232484D02*
X416655Y232538D01*
G01X416667Y232353D02*
X416661Y232484D01*
G01X416673Y232147D02*
X416667Y232353D01*
G01X418696Y213893D02*
X418702Y213840D01*
G01X418690Y214024D02*
X418696Y213893D01*
G01X418684Y214231D02*
X418690Y214024D01*
G01X420602Y232484D02*
X420596Y232538D01*
G01X420608Y232353D02*
X420602Y232484D01*
G01X420614Y232147D02*
X420608Y232353D01*
G01X422628Y213893D02*
X422634Y213840D01*
G01X422622Y214024D02*
X422628Y213893D01*
G01X422616Y214231D02*
X422622Y214024D01*
G01X400911Y231511D02*
X400906Y231553D01*
G01X400915Y231413D02*
X400911Y231511D01*
G01X400920Y231260D02*
X400915Y231413D01*
G01X402949Y214866D02*
X402954Y214824D01*
G01X402945Y214965D02*
X402949Y214866D01*
G01X402941Y215117D02*
X402945Y214965D01*
G01X404853Y231511D02*
X404848Y231553D01*
G01X404857Y231413D02*
X404853Y231511D01*
G01X404861Y231260D02*
X404857Y231413D01*
G01X406882Y214866D02*
X406886Y214824D01*
G01X406877Y214965D02*
X406882Y214866D01*
G01X406873Y215117D02*
X406877Y214965D01*
G01X408785Y231511D02*
X408780Y231553D01*
G01X408789Y231413D02*
X408785Y231511D01*
G01X408794Y231260D02*
X408789Y231413D01*
G01X410823Y214866D02*
X410828Y214824D01*
G01X410819Y214965D02*
X410823Y214866D01*
G01X410815Y215117D02*
X410819Y214965D01*
G01X412727Y231511D02*
X412722Y231553D01*
G01X412731Y231413D02*
X412727Y231511D01*
G01X412735Y231260D02*
X412731Y231413D01*
G01X414756Y214866D02*
X414760Y214824D01*
G01X414751Y214965D02*
X414756Y214866D01*
G01X414747Y215117D02*
X414751Y214965D01*
G01X416659Y231511D02*
X416655Y231553D01*
G01X416663Y231413D02*
X416659Y231511D01*
G01X416668Y231260D02*
X416663Y231413D01*
G01X418697Y214866D02*
X418702Y214824D01*
G01X418693Y214965D02*
X418697Y214866D01*
G01X418689Y215117D02*
X418693Y214965D01*
G01X420601Y231511D02*
X420596Y231553D01*
G01X420605Y231413D02*
X420601Y231511D01*
G01X420609Y231260D02*
X420605Y231413D01*
G01X422630Y214866D02*
X422634Y214824D01*
G01X422625Y214965D02*
X422630Y214866D01*
G01X422621Y215117D02*
X422625Y214965D01*
G01X405110Y215645D02*
X405114Y215615D01*
G01X405106Y215841D02*
X405110Y215645D01*
G01X405103Y216168D02*
X405106Y215841D01*
G01X405102Y216570D02*
X405103Y216168D01*
G01X406625Y230733D02*
X406620Y230762D01*
G01X406629Y230537D02*
X406625Y230733D01*
G01X406631Y230209D02*
X406629Y230537D01*
G01X406632Y229807D02*
X406631Y230209D01*
G01X412984Y215645D02*
X412988Y215615D01*
G01X412980Y215841D02*
X412984Y215645D01*
G01X412977Y216168D02*
X412980Y215841D01*
G01X412976Y216570D02*
X412977Y216168D01*
G01X414499Y230733D02*
X414494Y230762D01*
G01X414503Y230537D02*
X414499Y230733D01*
G01X414505Y230209D02*
X414503Y230537D01*
G01X414507Y229807D02*
X414505Y230209D01*
G01X420858Y215645D02*
X420862Y215615D01*
G01X420854Y215841D02*
X420858Y215645D01*
G01X420851Y216168D02*
X420854Y215841D01*
G01X420850Y216570D02*
X420851Y216168D01*
G01X422373Y230733D02*
X422368Y230762D01*
G01X422377Y230537D02*
X422373Y230733D01*
G01X422379Y230209D02*
X422377Y230537D01*
G01X422381Y229807D02*
X422379Y230209D01*
G01X409046Y214770D02*
X409054Y214621D01*
G01X409039Y215184D02*
X409046Y214770D01*
G01X409034Y215804D02*
X409039Y215184D01*
G01X409032Y216551D02*
X409034Y215804D01*
G01X409050Y215678D02*
X409054Y215605D01*
G01X409047Y215887D02*
X409050Y215678D01*
G01X409044Y216200D02*
X409047Y215887D01*
G01X409043Y216570D02*
X409044Y216200D01*
G01X410558Y230699D02*
X410554Y230772D01*
G01X410562Y230490D02*
X410558Y230699D01*
G01X410564Y230178D02*
X410562Y230490D01*
G01X410565Y229807D02*
X410564Y230178D01*
G01X410562Y231608D02*
X410554Y231756D01*
G01X410569Y231193D02*
X410562Y231608D01*
G01X410574Y230573D02*
X410569Y231193D01*
G01X410576Y229826D02*
X410574Y230573D01*
G01X416920Y214770D02*
X416928Y214621D01*
G01X416913Y215184D02*
X416920Y214770D01*
G01X416908Y215804D02*
X416913Y215184D01*
G01X416906Y216551D02*
X416908Y215804D01*
G01X416924Y215678D02*
X416928Y215605D01*
G01X416921Y215887D02*
X416924Y215678D01*
G01X416918Y216200D02*
X416921Y215887D01*
G01X416917Y216570D02*
X416918Y216200D01*
G01X418432Y230699D02*
X418428Y230772D01*
G01X418436Y230490D02*
X418432Y230699D01*
G01X418438Y230178D02*
X418436Y230490D01*
G01X418439Y229807D02*
X418438Y230178D01*
G01X418436Y231608D02*
X418428Y231756D01*
G01X418443Y231193D02*
X418436Y231608D01*
G01X418448Y230573D02*
X418443Y231193D01*
G01X418450Y229826D02*
X418448Y230573D01*
G01X424794Y214770D02*
X424802Y214621D01*
G01X424787Y215184D02*
X424794Y214770D01*
G01X424782Y215804D02*
X424787Y215184D01*
G01X424780Y216551D02*
X424782Y215804D01*
G01X424798Y215678D02*
X424802Y215605D01*
G01X424795Y215887D02*
X424798Y215678D01*
G01X424792Y216200D02*
X424795Y215887D01*
G01X424791Y216570D02*
X424792Y216200D01*
G01X426306Y230699D02*
X426302Y230772D01*
G01X426310Y230490D02*
X426306Y230699D01*
G01X426312Y230178D02*
X426310Y230490D01*
G01X426313Y229807D02*
X426312Y230178D01*
G01X426310Y231608D02*
X426302Y231756D01*
G01X426317Y231193D02*
X426310Y231608D01*
G01X426322Y230573D02*
X426317Y231193D01*
G01X426324Y229826D02*
X426322Y230573D01*
G01X416908D02*
X416906Y229826D01*
G01X416913Y231193D02*
X416908Y230573D01*
G01X416920Y231608D02*
X416913Y231193D01*
G01X416928Y231756D02*
X416920Y231608D01*
G01X418448Y215804D02*
X418450Y216551D01*
G01X418443Y215184D02*
X418448Y215804D01*
G01X418436Y214770D02*
X418443Y215184D01*
G01X418428Y214621D02*
X418436Y214770D01*
G01X424782Y230573D02*
X424780Y229826D01*
G01X424787Y231193D02*
X424782Y230573D01*
G01X424794Y231608D02*
X424787Y231193D01*
G01X424802Y231756D02*
X424794Y231608D01*
G01X426322Y215804D02*
X426324Y216551D01*
G01X426317Y215184D02*
X426322Y215804D01*
G01X426310Y214770D02*
X426317Y215184D01*
G01X426302Y214621D02*
X426310Y214770D01*
G01X416918Y230178D02*
X416917Y229807D01*
G01X416921Y230490D02*
X416918Y230178D01*
G01X416924Y230699D02*
X416921Y230490D01*
G01X416928Y230772D02*
X416924Y230699D01*
G01X418438Y216200D02*
X418439Y216570D01*
G01X418436Y215887D02*
X418438Y216200D01*
G01X418432Y215678D02*
X418436Y215887D01*
G01X418428Y215605D02*
X418432Y215678D01*
G01X424792Y230178D02*
X424791Y229807D01*
G01X424795Y230490D02*
X424792Y230178D01*
G01X424798Y230699D02*
X424795Y230490D01*
G01X424802Y230772D02*
X424798Y230699D01*
G01X426312Y216200D02*
X426313Y216570D01*
G01X426310Y215887D02*
X426312Y216200D01*
G01X426306Y215678D02*
X426310Y215887D01*
G01X426302Y215605D02*
X426306Y215678D01*
G01X420596Y214965D02*
X420600Y215117D01*
G01X420591Y214866D02*
X420596Y214965D01*
G01X420587Y214824D02*
X420591Y214866D01*
G01X422634Y231413D02*
X422630Y231260D01*
G01X422639Y231511D02*
X422634Y231413D01*
G01X422643Y231553D02*
X422639Y231511D01*
G01X424537Y214965D02*
X424542Y215117D01*
G01X424533Y214866D02*
X424537Y214965D01*
G01X424529Y214824D02*
X424533Y214866D01*
G01X426567Y231413D02*
X426563Y231260D01*
G01X426571Y231511D02*
X426567Y231413D01*
G01X426576Y231553D02*
X426571Y231511D01*
G01X422631Y232353D02*
X422625Y232147D01*
G01X422637Y232484D02*
X422631Y232353D01*
G01X422643Y232538D02*
X422637Y232484D01*
G01X420599Y214024D02*
X420605Y214231D01*
G01X420593Y213893D02*
X420599Y214024D01*
G01X420587Y213840D02*
X420593Y213893D01*
G01X426564Y232353D02*
X426558Y232147D01*
G01X426570Y232484D02*
X426564Y232353D01*
G01X426576Y232538D02*
X426570Y232484D01*
G01X424541Y214024D02*
X424547Y214231D01*
G01X424535Y213893D02*
X424541Y214024D01*
G01X424529Y213840D02*
X424535Y213893D01*
G01X386931Y214622D02*
X386932Y214621D01*
G01X386931Y214624D02*
Y214622D01*
G01X386930Y214627D02*
X386931Y214624D01*
G01X385433Y231756D02*
X385432D01*
G01X385433Y231754D02*
Y231756D01*
G01X385434Y231750D02*
X385433Y231754D01*
G01X394805Y214622D02*
X394806Y214621D01*
G01X394805Y214624D02*
Y214622D01*
G01X394804Y214627D02*
X394805Y214624D01*
G01X393307Y231756D02*
X393306D01*
G01X393307Y231754D02*
Y231756D01*
G01X393308Y231750D02*
X393307Y231754D01*
G01X402679Y214622D02*
X402680Y214621D01*
G01X402679Y214624D02*
Y214622D01*
G01X402678Y214627D02*
X402679Y214624D01*
G01X401181Y231756D02*
X401180D01*
G01X401181Y231754D02*
Y231756D01*
G01X401182Y231750D02*
X401181Y231754D01*
G01X416929Y230771D02*
X416928Y230772D01*
G01X416929Y230768D02*
Y230771D01*
G01X416930Y230762D02*
X416929Y230768D01*
G01X418427Y215606D02*
X418428Y215605D01*
G01X418427Y215610D02*
Y215606D01*
G01X418426Y215615D02*
X418427Y215610D01*
G01X424803Y230771D02*
X424802Y230772D01*
G01X424803Y230768D02*
Y230771D01*
G01X424804Y230762D02*
X424803Y230768D01*
G01X426301Y215606D02*
X426302Y215605D01*
G01X426301Y215610D02*
Y215606D01*
G01X426300Y215615D02*
X426301Y215610D01*
G01X424535Y232484D02*
X424529Y232538D01*
G01X424541Y232353D02*
X424535Y232484D01*
G01X424547Y232147D02*
X424541Y232353D01*
G01X426570Y213893D02*
X426576Y213840D01*
G01X426564Y214024D02*
X426570Y213893D01*
G01X426558Y214231D02*
X426564Y214024D01*
G01X424533Y231511D02*
X424529Y231553D01*
G01X424537Y231413D02*
X424533Y231511D01*
G01X424542Y231260D02*
X424537Y231413D01*
G01X426571Y214866D02*
X426576Y214824D01*
G01X426567Y214965D02*
X426571Y214866D01*
G01X426563Y215117D02*
X426567Y214965D01*
G01X424499Y214823D02*
X424483Y214822D01*
G01X424514Y214823D02*
X424499D01*
G01X424529Y214824D02*
X424514Y214823D01*
G01X420557D02*
X420542Y214822D01*
G01X420572Y214823D02*
X420557D01*
G01X420587Y214824D02*
X420572Y214823D01*
G01X416624D02*
X416609Y214822D01*
G01X416639Y214823D02*
X416624D01*
G01X416655Y214824D02*
X416639Y214823D01*
G01X412683D02*
X412668Y214822D01*
G01X412698Y214823D02*
X412683D01*
G01X412713Y214824D02*
X412698Y214823D01*
G01X408750D02*
X408735Y214822D01*
G01X408765Y214823D02*
X408750D01*
G01X408780Y214824D02*
X408765Y214823D01*
G01X404809D02*
X404794Y214822D01*
G01X404824Y214823D02*
X404809D01*
G01X404839Y214824D02*
X404824Y214823D01*
G01X400876D02*
X400861Y214822D01*
G01X400891Y214823D02*
X400876D01*
G01X400906Y214824D02*
X400891Y214823D01*
G01X393002D02*
X392987Y214822D01*
G01X393017Y214823D02*
X393002D01*
G01X393032Y214824D02*
X393017Y214823D01*
G01X424499Y213838D02*
X424483D01*
G01X424514Y213839D02*
X424499Y213838D01*
G01X424529Y213840D02*
X424514Y213839D01*
G01X420557Y213838D02*
X420542D01*
G01X420572Y213839D02*
X420557Y213838D01*
G01X420587Y213840D02*
X420572Y213839D01*
G01X416624Y213838D02*
X416609D01*
G01X416639Y213839D02*
X416624Y213838D01*
G01X416655Y213840D02*
X416639Y213839D01*
G01X412683Y213838D02*
X412668D01*
G01X412698Y213839D02*
X412683Y213838D01*
G01X412713Y213840D02*
X412698Y213839D01*
G01X408750Y213838D02*
X408735D01*
G01X408765Y213839D02*
X408750Y213838D01*
G01X408780Y213840D02*
X408765Y213839D01*
G01X404809Y213838D02*
X404794D01*
G01X404824Y213839D02*
X404809Y213838D01*
G01X404839Y213840D02*
X404824Y213839D01*
G01X396935Y213838D02*
X396920D01*
G01X396950Y213839D02*
X396935Y213838D01*
G01X396965Y213840D02*
X396950Y213839D01*
G01X394805Y215610D02*
X394804Y215617D01*
G01X394805Y215606D02*
Y215610D01*
G01X394806Y215605D02*
X394805Y215606D01*
G01X393307Y230768D02*
X393308Y230760D01*
G01X393307Y230771D02*
Y230768D01*
G01X393306Y230772D02*
X393307Y230771D01*
G01X402679Y215610D02*
X402678Y215617D01*
G01X402679Y215606D02*
Y215610D01*
G01X402680Y215605D02*
X402679Y215606D01*
G01X410553Y214622D02*
X410554Y214621D01*
G01X410553Y214624D02*
Y214622D01*
G01X410552Y214627D02*
X410553Y214624D01*
G01X409055Y231756D02*
X409054D01*
G01X409056Y231754D02*
X409055Y231756D01*
G01X409056Y231750D02*
Y231754D01*
G01X418427Y214622D02*
X418428Y214621D01*
G01X418427Y214624D02*
Y214622D01*
G01X418426Y214627D02*
X418427Y214624D01*
G01X416929Y231756D02*
X416928D01*
G01X416930Y231754D02*
X416929Y231756D01*
G01X416930Y231750D02*
Y231754D01*
G01X426301Y214622D02*
X426302Y214621D01*
G01X426301Y214624D02*
Y214622D01*
G01X426300Y214627D02*
X426301Y214624D01*
G01X424803Y231756D02*
X424802D01*
G01X424804Y231754D02*
X424803Y231756D01*
G01X424804Y231750D02*
Y231754D01*
G01X385128Y214823D02*
X385113Y214822D01*
G01X385143Y214823D02*
X385128D01*
G01X385158Y214824D02*
X385143Y214823D01*
G01X381187D02*
X381172Y214822D01*
G01X381202Y214823D02*
X381187D01*
G01X381217Y214824D02*
X381202Y214823D01*
G01X377254D02*
X377239Y214822D01*
G01X377269Y214823D02*
X377254D01*
G01X377284Y214824D02*
X377269Y214823D01*
G01X373313D02*
X373298Y214822D01*
G01X373328Y214823D02*
X373313D01*
G01X373343Y214824D02*
X373328Y214823D01*
G01X369380D02*
X369365Y214822D01*
G01X369395Y214823D02*
X369380D01*
G01X369410Y214824D02*
X369395Y214823D01*
G01X365439D02*
X365424Y214822D01*
G01X365454Y214823D02*
X365439D01*
G01X365469Y214824D02*
X365454Y214823D01*
G01X361506D02*
X361491Y214822D01*
G01X361521Y214823D02*
X361506D01*
G01X361536Y214824D02*
X361521Y214823D01*
G01X357565D02*
X357550Y214822D01*
G01X357580Y214823D02*
X357565D01*
G01X357595Y214824D02*
X357580Y214823D01*
G01X353632D02*
X353617Y214822D01*
G01X353647Y214823D02*
X353632D01*
G01X353662Y214824D02*
X353647Y214823D01*
G01X349691D02*
X349676Y214822D01*
G01X349706Y214823D02*
X349691D01*
G01X349721Y214824D02*
X349706Y214823D01*
G01X426606Y231555D02*
X426621D01*
G01X426591Y231554D02*
X426606Y231555D01*
G01X426576Y231553D02*
X426591Y231554D01*
G01X422673Y231555D02*
X422688D01*
G01X422658Y231554D02*
X422673Y231555D01*
G01X422643Y231553D02*
X422658Y231554D01*
G01X418732Y231555D02*
X418747D01*
G01X418717Y231554D02*
X418732Y231555D01*
G01X418702Y231553D02*
X418717Y231554D01*
G01X410858Y231555D02*
X410873D01*
G01X410843Y231554D02*
X410858Y231555D01*
G01X410828Y231553D02*
X410843Y231554D01*
G01X402984Y231555D02*
X402999D01*
G01X402969Y231554D02*
X402984Y231555D01*
G01X402954Y231553D02*
X402969Y231554D01*
G01X399051Y231555D02*
X399066D01*
G01X399036Y231554D02*
X399051Y231555D01*
G01X399021Y231553D02*
X399036Y231554D01*
G01X395110Y231555D02*
X395125D01*
G01X395095Y231554D02*
X395110Y231555D01*
G01X395080Y231553D02*
X395095Y231554D01*
G01X391177Y231555D02*
X391192D01*
G01X391162Y231554D02*
X391177Y231555D01*
G01X391147Y231553D02*
X391162Y231554D01*
G01X387236Y231555D02*
X387251D01*
G01X387221Y231554D02*
X387236Y231555D01*
G01X387206Y231553D02*
X387221Y231554D01*
G01X383303Y231555D02*
X383318D01*
G01X383288Y231554D02*
X383303Y231555D01*
G01X383273Y231553D02*
X383288Y231554D01*
G01X379362Y231555D02*
X379377D01*
G01X379347Y231554D02*
X379362Y231555D01*
G01X379332Y231553D02*
X379347Y231554D01*
G01X371488Y231555D02*
X371503D01*
G01X371473Y231554D02*
X371488Y231555D01*
G01X371458Y231553D02*
X371473Y231554D01*
G01X363614Y231555D02*
X363629D01*
G01X363599Y231554D02*
X363614Y231555D01*
G01X363584Y231553D02*
X363599Y231554D01*
G01X359681Y231555D02*
X359696D01*
G01X359666Y231554D02*
X359681Y231555D01*
G01X359651Y231553D02*
X359666Y231554D01*
G01X355740Y231555D02*
X355755D01*
G01X355725Y231554D02*
X355740Y231555D01*
G01X355710Y231553D02*
X355725Y231554D01*
G01X351807Y231555D02*
X351822D01*
G01X351792Y231554D02*
X351807Y231555D01*
G01X351777Y231553D02*
X351792Y231554D01*
G01X347866Y231555D02*
X347881D01*
G01X347851Y231554D02*
X347866Y231555D01*
G01X347836Y231553D02*
X347851Y231554D01*
G01X389061Y213838D02*
X389046D01*
G01X389076Y213839D02*
X389061Y213838D01*
G01X389091Y213840D02*
X389076Y213839D01*
G01X385128Y213838D02*
X385113D01*
G01X385143Y213839D02*
X385128Y213838D01*
G01X385158Y213840D02*
X385143Y213839D01*
G01X381187Y213838D02*
X381172D01*
G01X381202Y213839D02*
X381187Y213838D01*
G01X381217Y213840D02*
X381202Y213839D01*
G01X377254Y213838D02*
X377239D01*
G01X377269Y213839D02*
X377254Y213838D01*
G01X377284Y213840D02*
X377269Y213839D01*
G01X373313Y213838D02*
X373298D01*
G01X373328Y213839D02*
X373313Y213838D01*
G01X373343Y213840D02*
X373328Y213839D01*
G01X369380Y213838D02*
X369365D01*
G01X369395Y213839D02*
X369380Y213838D01*
G01X369410Y213840D02*
X369395Y213839D01*
G01X365439Y213838D02*
X365424D01*
G01X365454Y213839D02*
X365439Y213838D01*
G01X365469Y213840D02*
X365454Y213839D01*
G01X361506Y213838D02*
X361491D01*
G01X361521Y213839D02*
X361506Y213838D01*
G01X361536Y213840D02*
X361521Y213839D01*
G01X357565Y213838D02*
X357550D01*
G01X357580Y213839D02*
X357565Y213838D01*
G01X357595Y213840D02*
X357580Y213839D01*
G01X353632Y213838D02*
X353617D01*
G01X353647Y213839D02*
X353632Y213838D01*
G01X353662Y213840D02*
X353647Y213839D01*
G01X349691Y213838D02*
X349676D01*
G01X349706Y213839D02*
X349691Y213838D01*
G01X349721Y213840D02*
X349706Y213839D01*
G01X426606Y232539D02*
X426621D01*
G01X426591Y232538D02*
X426606Y232539D01*
G01X426576Y232538D02*
X426591D01*
G01X422673Y232539D02*
X422688D01*
G01X422658Y232538D02*
X422673Y232539D01*
G01X422643Y232538D02*
X422658D01*
G01X418732Y232539D02*
X418747D01*
G01X418717Y232538D02*
X418732Y232539D01*
G01X418702Y232538D02*
X418717D01*
G01X414799Y232539D02*
X414814D01*
G01X414784Y232538D02*
X414799Y232539D01*
G01X414769Y232538D02*
X414784D01*
G01X410858Y232539D02*
X410873D01*
G01X410843Y232538D02*
X410858Y232539D01*
G01X410828Y232538D02*
X410843D01*
G01X406925Y232539D02*
X406940D01*
G01X406910Y232538D02*
X406925Y232539D01*
G01X406895Y232538D02*
X406910D01*
G01X391177Y232539D02*
X391192D01*
G01X391162Y232538D02*
X391177Y232539D01*
G01X391147Y232538D02*
X391162D01*
G01X387236Y232539D02*
X387251D01*
G01X387221Y232538D02*
X387236Y232539D01*
G01X387206Y232538D02*
X387221D01*
G01X383303Y232539D02*
X383318D01*
G01X383288Y232538D02*
X383303Y232539D01*
G01X383273Y232538D02*
X383288D01*
G01X379362Y232539D02*
X379377D01*
G01X379347Y232538D02*
X379362Y232539D01*
G01X379332Y232538D02*
X379347D01*
G01X375429Y232539D02*
X375444D01*
G01X375414Y232538D02*
X375429Y232539D01*
G01X375399Y232538D02*
X375414D01*
G01X371488Y232539D02*
X371503D01*
G01X371473Y232538D02*
X371488Y232539D01*
G01X371458Y232538D02*
X371473D01*
G01X367555Y232539D02*
X367570D01*
G01X367540Y232538D02*
X367555Y232539D01*
G01X367525Y232538D02*
X367540D01*
G01X363614Y232539D02*
X363629D01*
G01X363599Y232538D02*
X363614Y232539D01*
G01X363584Y232538D02*
X363599D01*
G01X359681Y232539D02*
X359696D01*
G01X359666Y232538D02*
X359681Y232539D01*
G01X359651Y232538D02*
X359666D01*
G01X355740Y232539D02*
X355755D01*
G01X355725Y232538D02*
X355740Y232539D01*
G01X355710Y232538D02*
X355725D01*
G01X351807Y232539D02*
X351822D01*
G01X351792Y232538D02*
X351807Y232539D01*
G01X351777Y232538D02*
X351792D01*
G01X347866Y232539D02*
X347881D01*
G01X347851Y232538D02*
X347866Y232539D01*
G01X347836Y232538D02*
X347851D01*
G01Y213839D02*
X347836Y213840D01*
G01X347866Y213838D02*
X347851Y213839D01*
G01X347881Y213838D02*
X347866D01*
G01X351783Y213839D02*
X351768Y213840D01*
G01X351798Y213838D02*
X351783Y213839D01*
G01X351813Y213838D02*
X351798D01*
G01X355725Y213839D02*
X355710Y213840D01*
G01X355740Y213838D02*
X355725Y213839D01*
G01X355755Y213838D02*
X355740D01*
G01X359657Y213839D02*
X359642Y213840D01*
G01X359672Y213838D02*
X359657Y213839D01*
G01X359687Y213838D02*
X359672D01*
G01X363599Y213839D02*
X363584Y213840D01*
G01X363614Y213838D02*
X363599Y213839D01*
G01X363629Y213838D02*
X363614D01*
G01X367531Y213839D02*
X367516Y213840D01*
G01X367546Y213838D02*
X367531Y213839D01*
G01X367561Y213838D02*
X367546D01*
G01X371473Y213839D02*
X371458Y213840D01*
G01X371488Y213838D02*
X371473Y213839D01*
G01X371503Y213838D02*
X371488D01*
G01X375405Y213839D02*
X375390Y213840D01*
G01X375420Y213838D02*
X375405Y213839D01*
G01X375435Y213838D02*
X375420D01*
G01X379347Y213839D02*
X379332Y213840D01*
G01X379362Y213838D02*
X379347Y213839D01*
G01X379377Y213838D02*
X379362D01*
G01X383279Y213839D02*
X383264Y213840D01*
G01X383294Y213838D02*
X383279Y213839D01*
G01X383309Y213838D02*
X383294D01*
G01X387221Y213839D02*
X387206Y213840D01*
G01X387236Y213838D02*
X387221Y213839D01*
G01X387251Y213838D02*
X387236D01*
G01X391153Y213839D02*
X391138Y213840D01*
G01X391168Y213838D02*
X391153Y213839D01*
G01X391183Y213838D02*
X391168D01*
G01X395095Y213839D02*
X395080Y213840D01*
G01X395110Y213838D02*
X395095Y213839D01*
G01X395125Y213838D02*
X395110D01*
G01X399027Y213839D02*
X399012Y213840D01*
G01X399042Y213838D02*
X399027Y213839D01*
G01X399057Y213838D02*
X399042D01*
G01X402969Y213839D02*
X402954Y213840D01*
G01X402984Y213838D02*
X402969Y213839D01*
G01X402999Y213838D02*
X402984D01*
G01X406901Y213839D02*
X406886Y213840D01*
G01X406916Y213838D02*
X406901Y213839D01*
G01X406931Y213838D02*
X406916D01*
G01X410843Y213839D02*
X410828Y213840D01*
G01X410858Y213838D02*
X410843Y213839D01*
G01X410873Y213838D02*
X410858D01*
G01X414775Y213839D02*
X414760Y213840D01*
G01X414790Y213838D02*
X414775Y213839D01*
G01X414805Y213838D02*
X414790D01*
G01X418717Y213839D02*
X418702Y213840D01*
G01X418732Y213838D02*
X418717Y213839D01*
G01X418747Y213838D02*
X418732D01*
G01X422649Y213839D02*
X422634Y213840D01*
G01X422664Y213838D02*
X422649Y213839D01*
G01X422679Y213838D02*
X422664D01*
G01X426591Y213839D02*
X426576Y213840D01*
G01X426606Y213838D02*
X426591Y213839D01*
G01X426621Y213838D02*
X426606D01*
G01X349715Y232538D02*
X349730D01*
G01X349700Y232539D02*
X349715Y232538D01*
G01X349685Y232539D02*
X349700D01*
G01X353647Y232538D02*
X353662D01*
G01X353632Y232539D02*
X353647Y232538D01*
G01X353617Y232539D02*
X353632D01*
G01X357589Y232538D02*
X357604D01*
G01X357574Y232539D02*
X357589Y232538D01*
G01X357559Y232539D02*
X357574D01*
G01X361521Y232538D02*
X361536D01*
G01X361506Y232539D02*
X361521Y232538D01*
G01X361491Y232539D02*
X361506D01*
G01X365463Y232538D02*
X365478D01*
G01X365448Y232539D02*
X365463Y232538D01*
G01X365433Y232539D02*
X365448D01*
G01X369395Y232538D02*
X369410D01*
G01X369380Y232539D02*
X369395Y232538D01*
G01X369365Y232539D02*
X369380D01*
G01X373337Y232538D02*
X373352D01*
G01X373322Y232539D02*
X373337Y232538D01*
G01X373307Y232539D02*
X373322D01*
G01X377269Y232538D02*
X377284D01*
G01X377254Y232539D02*
X377269Y232538D01*
G01X377239Y232539D02*
X377254D01*
G01X381211Y232538D02*
X381226D01*
G01X381196Y232539D02*
X381211Y232538D01*
G01X381181Y232539D02*
X381196D01*
G01X385143Y232538D02*
X385158D01*
G01X385128Y232539D02*
X385143Y232538D01*
G01X385113Y232539D02*
X385128D01*
G01X389085Y232538D02*
X389100D01*
G01X389070Y232539D02*
X389085Y232538D01*
G01X389055Y232539D02*
X389070D01*
G01X393017Y232538D02*
X393032D01*
G01X393002Y232539D02*
X393017Y232538D01*
G01X392987Y232539D02*
X393002D01*
G01X396959Y232538D02*
X396974D01*
G01X396944Y232539D02*
X396959Y232538D01*
G01X396929Y232539D02*
X396944D01*
G01X400891Y232538D02*
X400906D01*
G01X400876Y232539D02*
X400891Y232538D01*
G01X400861Y232539D02*
X400876D01*
G01X404833Y232538D02*
X404848D01*
G01X404818Y232539D02*
X404833Y232538D01*
G01X404803Y232539D02*
X404818D01*
G01X408765Y232538D02*
X408780D01*
G01X408750Y232539D02*
X408765Y232538D01*
G01X408735Y232539D02*
X408750D01*
G01X412707Y232538D02*
X412722D01*
G01X412692Y232539D02*
X412707Y232538D01*
G01X412677Y232539D02*
X412692D01*
G01X416639Y232538D02*
X416655D01*
G01X416624Y232539D02*
X416639Y232538D01*
G01X416609Y232539D02*
X416624D01*
G01X420581Y232538D02*
X420596D01*
G01X420566Y232539D02*
X420581Y232538D01*
G01X420551Y232539D02*
X420566D01*
G01X424514Y232538D02*
X424529D01*
G01X424499Y232539D02*
X424514Y232538D01*
G01X424483Y232539D02*
X424499D01*
G01X347851Y214823D02*
X347836Y214824D01*
G01X347866Y214823D02*
X347851D01*
G01X347881Y214822D02*
X347866Y214823D01*
G01X351783D02*
X351768Y214824D01*
G01X351798Y214823D02*
X351783D01*
G01X351813Y214822D02*
X351798Y214823D01*
G01X355725D02*
X355710Y214824D01*
G01X355740Y214823D02*
X355725D01*
G01X355755Y214822D02*
X355740Y214823D01*
G01X359657D02*
X359642Y214824D01*
G01X359672Y214823D02*
X359657D01*
G01X359687Y214822D02*
X359672Y214823D01*
G01X363599D02*
X363584Y214824D01*
G01X363614Y214823D02*
X363599D01*
G01X363629Y214822D02*
X363614Y214823D01*
G01X367531D02*
X367516Y214824D01*
G01X367546Y214823D02*
X367531D01*
G01X367561Y214822D02*
X367546Y214823D01*
G01X371473D02*
X371458Y214824D01*
G01X371488Y214823D02*
X371473D01*
G01X371503Y214822D02*
X371488Y214823D01*
G01X375405D02*
X375390Y214824D01*
G01X375420Y214823D02*
X375405D01*
G01X375435Y214822D02*
X375420Y214823D01*
G01X379347D02*
X379332Y214824D01*
G01X379362Y214823D02*
X379347D01*
G01X379377Y214822D02*
X379362Y214823D01*
G01X383279D02*
X383264Y214824D01*
G01X383294Y214823D02*
X383279D01*
G01X383309Y214822D02*
X383294Y214823D01*
G01X387221D02*
X387206Y214824D01*
G01X387236Y214823D02*
X387221D01*
G01X387251Y214822D02*
X387236Y214823D01*
G01X395095D02*
X395080Y214824D01*
G01X395110Y214823D02*
X395095D01*
G01X395125Y214822D02*
X395110Y214823D01*
G01X402969D02*
X402954Y214824D01*
G01X402984Y214823D02*
X402969D01*
G01X402999Y214822D02*
X402984Y214823D01*
G01X406901D02*
X406886Y214824D01*
G01X406916Y214823D02*
X406901D01*
G01X406931Y214822D02*
X406916Y214823D01*
G01X410843D02*
X410828Y214824D01*
G01X410858Y214823D02*
X410843D01*
G01X410873Y214822D02*
X410858Y214823D01*
G01X414775D02*
X414760Y214824D01*
G01X414790Y214823D02*
X414775D01*
G01X414805Y214822D02*
X414790Y214823D01*
G01X418717D02*
X418702Y214824D01*
G01X418732Y214823D02*
X418717D01*
G01X418747Y214822D02*
X418732Y214823D01*
G01X422649D02*
X422634Y214824D01*
G01X422664Y214823D02*
X422649D01*
G01X422679Y214822D02*
X422664Y214823D01*
G01X426591D02*
X426576Y214824D01*
G01X426606Y214823D02*
X426591D01*
G01X426621Y214822D02*
X426606Y214823D01*
G01X353647Y231554D02*
X353662Y231553D01*
G01X353632Y231555D02*
X353647Y231554D01*
G01X353617Y231555D02*
X353632D01*
G01X361521Y231554D02*
X361536Y231553D01*
G01X361506Y231555D02*
X361521Y231554D01*
G01X361491Y231555D02*
X361506D01*
G01X365463Y231554D02*
X365478Y231553D01*
G01X365448Y231555D02*
X365463Y231554D01*
G01X365433Y231555D02*
X365448D01*
G01X369395Y231554D02*
X369410Y231553D01*
G01X369380Y231555D02*
X369395Y231554D01*
G01X369365Y231555D02*
X369380D01*
G01X373337Y231554D02*
X373352Y231553D01*
G01X373322Y231555D02*
X373337Y231554D01*
G01X373307Y231555D02*
X373322D01*
G01X377269Y231554D02*
X377284Y231553D01*
G01X377254Y231555D02*
X377269Y231554D01*
G01X377239Y231555D02*
X377254D01*
G01X385143Y231554D02*
X385158Y231553D01*
G01X385128Y231555D02*
X385143Y231554D01*
G01X385113Y231555D02*
X385128D01*
G01X389085Y231554D02*
X389100Y231553D01*
G01X389070Y231555D02*
X389085Y231554D01*
G01X389055Y231555D02*
X389070D01*
G01X393017Y231554D02*
X393032Y231553D01*
G01X393002Y231555D02*
X393017Y231554D01*
G01X392987Y231555D02*
X393002D01*
G01X396959Y231554D02*
X396974Y231553D01*
G01X396944Y231555D02*
X396959Y231554D01*
G01X396929Y231555D02*
X396944D01*
G01X400891Y231554D02*
X400906Y231553D01*
G01X400876Y231555D02*
X400891Y231554D01*
G01X400861Y231555D02*
X400876D01*
G01X404833Y231554D02*
X404848Y231553D01*
G01X404818Y231555D02*
X404833Y231554D01*
G01X404803Y231555D02*
X404818D01*
G01X408765Y231554D02*
X408780Y231553D01*
G01X408750Y231555D02*
X408765Y231554D01*
G01X408735Y231555D02*
X408750D01*
G01X412707Y231554D02*
X412722Y231553D01*
G01X412692Y231555D02*
X412707Y231554D01*
G01X412677Y231555D02*
X412692D01*
G01X416639Y231554D02*
X416655Y231553D01*
G01X416624Y231555D02*
X416639Y231554D01*
G01X416609Y231555D02*
X416624D01*
G01X424514Y231554D02*
X424529Y231553D01*
G01X424499Y231555D02*
X424514Y231554D01*
G01X424483Y231555D02*
X424499D01*
G01X391168Y214823D02*
X391183Y214822D01*
G01X391153Y214823D02*
X391168D01*
G01X391138Y214824D02*
X391153Y214823D01*
G01X399042D02*
X399057Y214822D01*
G01X399027Y214823D02*
X399042D01*
G01X399012Y214824D02*
X399027Y214823D01*
G01X349700Y231555D02*
X349685D01*
G01X349715Y231554D02*
X349700Y231555D01*
G01X349730Y231553D02*
X349715Y231554D01*
G01X357574Y231555D02*
X357559D01*
G01X357589Y231554D02*
X357574Y231555D01*
G01X357604Y231553D02*
X357589Y231554D01*
G01X381196Y231555D02*
X381181D01*
G01X381211Y231554D02*
X381196Y231555D01*
G01X381226Y231553D02*
X381211Y231554D01*
G01X401181Y230768D02*
X401182Y230760D01*
G01X401181Y230771D02*
Y230768D01*
G01X401180Y230772D02*
X401181Y230771D01*
G01X420566Y231555D02*
X420551D01*
G01X420581Y231554D02*
X420566Y231555D01*
G01X420596Y231553D02*
X420581Y231554D01*
G01X347481Y209943D02*
X347639Y209981D01*
G01X347481Y210965D02*
X347639Y211039D01*
G01X347548Y214640D02*
X347560Y214627D01*
G01X347639Y236396D02*
X347481Y236434D01*
G01X347639Y235338D02*
X347481Y235412D01*
G01X347560Y231750D02*
X347548Y231737D01*
G01X351481Y214640D02*
X351492Y214627D01*
G01X349996D02*
X350008Y214640D01*
G01X351576Y218680D02*
X351418Y218717D01*
G01X350080D02*
X349922Y218680D01*
G01X351576Y217621D02*
X351418Y217696D01*
G01X350080D02*
X349922Y217621D01*
G01Y227698D02*
X350080Y227660D01*
G01X351418D02*
X351576Y227698D01*
G01X349922Y228756D02*
X350080Y228681D01*
G01X351418D02*
X351576Y228756D01*
G01X350017Y231737D02*
X350006Y231750D01*
G01X351502D02*
X351490Y231737D01*
G01X353859Y209981D02*
X354017Y209943D01*
G01X355355D02*
X355513Y209981D01*
G01X353859Y211039D02*
X354017Y210965D01*
G01X355355D02*
X355513Y211039D01*
G01X353938Y214627D02*
X353950Y214640D01*
G01X355423D02*
X355434Y214627D01*
G01X355513Y236396D02*
X355355Y236434D01*
G01X354017D02*
X353859Y236396D01*
G01X355513Y235338D02*
X355355Y235412D01*
G01X354017D02*
X353859Y235338D01*
G01X353950Y231737D02*
X353938Y231750D01*
G01X355434D02*
X355423Y231737D01*
G01X359355Y214640D02*
X359366Y214627D01*
G01X357870D02*
X357882Y214640D01*
G01X359450Y218680D02*
X359292Y218717D01*
G01X357954D02*
X357796Y218680D01*
G01X359450Y217621D02*
X359292Y217696D01*
G01X357954D02*
X357796Y217621D01*
G01Y227698D02*
X357954Y227660D01*
G01X359292D02*
X359450Y227698D01*
G01X357796Y228756D02*
X357954Y228681D01*
G01X359292D02*
X359450Y228756D01*
G01X357891Y231737D02*
X357880Y231750D01*
G01X359376D02*
X359364Y231737D01*
G01X361733Y209981D02*
X361891Y209943D01*
G01X363229D02*
X363387Y209981D01*
G01X361733Y211039D02*
X361891Y210965D01*
G01X363229D02*
X363387Y211039D01*
G01X361812Y214627D02*
X361824Y214640D01*
G01X363297D02*
X363308Y214627D01*
G01X363387Y236396D02*
X363229Y236434D01*
G01X361891D02*
X361733Y236396D01*
G01X363387Y235338D02*
X363229Y235412D01*
G01X361891D02*
X361733Y235338D01*
G01X361824Y231737D02*
X361812Y231750D01*
G01X363308D02*
X363297Y231737D01*
G01X367229Y214640D02*
X367240Y214627D01*
G01X365744D02*
X365756Y214640D01*
G01X367324Y218680D02*
X367166Y218717D01*
G01X365828D02*
X365670Y218680D01*
G01X367324Y217621D02*
X367166Y217696D01*
G01X365828D02*
X365670Y217621D01*
G01Y227698D02*
X365828Y227660D01*
G01X365670Y228756D02*
X365828Y228681D01*
G01X367166D02*
X367324Y228756D01*
G01X367166Y227660D02*
X367324Y227698D01*
G01X367570Y231555D02*
X367525Y231553D01*
G01X365765Y231737D02*
X365754Y231750D01*
G01X367250D02*
X367238Y231737D01*
G01X369607Y209981D02*
X369765Y209943D01*
G01X371103D02*
X371261Y209981D01*
G01X369607Y211039D02*
X369765Y210965D01*
G01X371103D02*
X371261Y211039D01*
G01X369686Y214627D02*
X369698Y214640D01*
G01X371171D02*
X371182Y214627D01*
G01X371261Y236396D02*
X371103Y236434D01*
G01X369765D02*
X369607Y236396D01*
G01X371261Y235338D02*
X371103Y235412D01*
G01X369765D02*
X369607Y235338D01*
G01X369698Y231737D02*
X369686Y231750D01*
G01X371182D02*
X371171Y231737D01*
G01X375103Y214640D02*
X375114Y214627D01*
G01X373618D02*
X373630Y214640D01*
G01X375198Y218680D02*
X375040Y218717D01*
G01X373702D02*
X373544Y218680D01*
G01X375198Y217621D02*
X375040Y217696D01*
G01X373702D02*
X373544Y217621D01*
G01Y227698D02*
X373702Y227660D01*
G01X373544Y228756D02*
X373702Y228681D01*
G01X375040D02*
X375198Y228756D01*
G01X375040Y227660D02*
X375198Y227698D01*
G01X375444Y231555D02*
X375399Y231553D01*
G01X373639Y231737D02*
X373628Y231750D01*
G01X375124D02*
X375112Y231737D01*
G01X377481Y209981D02*
X377639Y209943D01*
G01X378977D02*
X379135Y209981D01*
G01X377481Y211039D02*
X377639Y210965D01*
G01X378977D02*
X379135Y211039D01*
G01X377560Y214627D02*
X377572Y214640D01*
G01X379045D02*
X379056Y214627D01*
G01X379135Y236396D02*
X378977Y236434D01*
G01X377639D02*
X377481Y236396D01*
G01X379135Y235338D02*
X378977Y235412D01*
G01X377639D02*
X377481Y235338D01*
G01X377572Y231737D02*
X377560Y231750D01*
G01X379056D02*
X379045Y231737D01*
G01X382977Y214640D02*
X382988Y214627D01*
G01X381492D02*
X381504Y214640D01*
G01X383072Y218680D02*
X382914Y218717D01*
G01X381576D02*
X381418Y218680D01*
G01X383072Y217621D02*
X382914Y217696D01*
G01X381576D02*
X381418Y217621D01*
G01Y227698D02*
X381576Y227660D01*
G01X382914D02*
X383072Y227698D01*
G01X381418Y228756D02*
X381576Y228681D01*
G01X382914D02*
X383072Y228756D01*
G01X381513Y231737D02*
X381502Y231750D01*
G01X382998D02*
X382986Y231737D01*
G01X385355Y209981D02*
X385513Y209943D01*
G01X386851D02*
X387009Y209981D01*
G01X385355Y211039D02*
X385513Y210965D01*
G01X386851D02*
X387009Y211039D01*
G01X385434Y214627D02*
X385446Y214640D01*
G01X386919D02*
X386930Y214627D01*
G01X387009Y236396D02*
X386851Y236434D01*
G01X385513D02*
X385355Y236396D01*
G01X387009Y235338D02*
X386851Y235412D01*
G01X385513D02*
X385355Y235338D01*
G01X385446Y231737D02*
X385434Y231750D01*
G01X386930D02*
X386919Y231737D01*
G01X390851Y214640D02*
X390862Y214627D01*
G01X389366D02*
X389378Y214640D01*
G01X389046Y214822D02*
X389091Y214824D01*
G01X389450Y218717D02*
X389292Y218680D01*
G01X390946D02*
X390788Y218717D01*
G01X389450Y217696D02*
X389292Y217621D01*
G01X390946D02*
X390788Y217696D01*
G01X389387Y231737D02*
X389376Y231750D01*
G01X390872D02*
X390860Y231737D01*
G01X390788Y227660D02*
X390946Y227698D01*
G01X389292D02*
X389450Y227660D01*
G01X390788Y228681D02*
X390946Y228756D01*
G01X389292D02*
X389450Y228681D01*
G01X394725Y209943D02*
X394883Y209981D01*
G01X393229D02*
X393387Y209943D01*
G01X394725Y210965D02*
X394883Y211039D01*
G01X393229D02*
X393387Y210965D01*
G01X392987Y213838D02*
X393032Y213840D01*
G01X393308Y214627D02*
X393320Y214640D01*
G01X394793D02*
X394804Y214627D01*
G01X393387Y236434D02*
X393229Y236396D01*
G01X394883D02*
X394725Y236434D01*
G01X393387Y235412D02*
X393229Y235338D01*
G01X394883D02*
X394725Y235412D01*
G01X393320Y231737D02*
X393308Y231750D01*
G01X394804D02*
X394793Y231737D01*
G01X395125Y232539D02*
X395080Y232538D01*
G01X398820Y218680D02*
X398662Y218717D01*
G01X397324D02*
X397166Y218680D01*
G01X397324Y217696D02*
X397166Y217621D01*
G01X398820D02*
X398662Y217696D01*
G01X398725Y214640D02*
X398736Y214627D01*
G01X397240D02*
X397252Y214640D01*
G01X396920Y214822D02*
X396965Y214824D01*
G01X397166Y227698D02*
X397324Y227660D01*
G01X398662Y228681D02*
X398820Y228756D01*
G01X397166D02*
X397324Y228681D01*
G01X398662Y227660D02*
X398820Y227698D01*
G01X397261Y231737D02*
X397250Y231750D01*
G01X398746D02*
X398734Y231737D01*
G01X399066Y232539D02*
X399021Y232538D01*
G01X402599Y209943D02*
X402757Y209981D01*
G01X401103D02*
X401261Y209943D01*
G01X402599Y210965D02*
X402757Y211039D01*
G01X401103D02*
X401261Y210965D01*
G01X400861Y213838D02*
X400906Y213840D01*
G01X401182Y214627D02*
X401194Y214640D01*
G01X402667D02*
X402678Y214627D01*
G01X401261Y236434D02*
X401103Y236396D01*
G01X402757D02*
X402599Y236434D01*
G01X401261Y235412D02*
X401103Y235338D01*
G01X402757D02*
X402599Y235412D01*
G01X401194Y231737D02*
X401182Y231750D01*
G01X402678D02*
X402667Y231737D01*
G01X402999Y232539D02*
X402954Y232538D01*
G01X406599Y214640D02*
X406610Y214627D01*
G01X405114D02*
X405126Y214640D01*
G01X406694Y218680D02*
X406536Y218717D01*
G01X405198D02*
X405040Y218680D01*
G01X406694Y217621D02*
X406536Y217696D01*
G01X405198D02*
X405040Y217621D01*
G01Y227698D02*
X405198Y227660D01*
G01X405040Y228756D02*
X405198Y228681D01*
G01X406536D02*
X406694Y228756D01*
G01X406536Y227660D02*
X406694Y227698D01*
G01X406940Y231555D02*
X406895Y231553D01*
G01X405135Y231737D02*
X405124Y231750D01*
G01X406620D02*
X406608Y231737D01*
G01X410631Y236396D02*
X410473Y236434D01*
G01X409135D02*
X408977Y236396D01*
G01X410631Y235338D02*
X410473Y235412D01*
G01X409135D02*
X408977Y235338D01*
G01X410552Y231750D02*
X410541Y231737D01*
G01X409068D02*
X409056Y231750D01*
G01X408977Y209981D02*
X409135Y209943D01*
G01X410473D02*
X410631Y209981D01*
G01X408977Y211039D02*
X409135Y210965D01*
G01X410473D02*
X410631Y211039D01*
G01X410541Y214640D02*
X410552Y214627D01*
G01X409056D02*
X409068Y214640D01*
G01X414473D02*
X414484Y214627D01*
G01X412988D02*
X413000Y214640D01*
G01X414568Y218680D02*
X414410Y218717D01*
G01X413072D02*
X412914Y218680D01*
G01X414568Y217621D02*
X414410Y217696D01*
G01X413072D02*
X412914Y217621D01*
G01Y227698D02*
X413072Y227660D01*
G01X412914Y228756D02*
X413072Y228681D01*
G01X414410D02*
X414568Y228756D01*
G01X414410Y227660D02*
X414568Y227698D01*
G01X414814Y231555D02*
X414769Y231553D01*
G01X413009Y231737D02*
X412998Y231750D01*
G01X414494D02*
X414482Y231737D01*
G01X416851Y209981D02*
X417009Y209943D01*
G01X418347D02*
X418505Y209981D01*
G01X416851Y211039D02*
X417009Y210965D01*
G01X418347D02*
X418505Y211039D01*
G01X416930Y214627D02*
X416942Y214640D01*
G01X418415D02*
X418426Y214627D01*
G01X418505Y236396D02*
X418347Y236434D01*
G01X417009D02*
X416851Y236396D01*
G01X418505Y235338D02*
X418347Y235412D01*
G01X417009D02*
X416851Y235338D01*
G01X416942Y231737D02*
X416930Y231750D01*
G01X418426D02*
X418415Y231737D01*
G01X422347Y214640D02*
X422359Y214627D01*
G01X420862D02*
X420874Y214640D01*
G01X422442Y218680D02*
X422284Y218717D01*
G01X420946D02*
X420788Y218680D01*
G01X422442Y217621D02*
X422284Y217696D01*
G01X420946D02*
X420788Y217621D01*
G01Y227698D02*
X420946Y227660D01*
G01X422284D02*
X422442Y227698D01*
G01X420788Y228756D02*
X420946Y228681D01*
G01X422284D02*
X422442Y228756D01*
G01X420883Y231737D02*
X420872Y231750D01*
G01X422368D02*
X422356Y231737D01*
G01X424725Y209981D02*
X424883Y209943D01*
G01X426221D02*
X426379Y209981D01*
G01X424725Y211039D02*
X424883Y210965D01*
G01X426221D02*
X426379Y211039D01*
G01X424804Y214627D02*
X424816Y214640D01*
G01X426289D02*
X426300Y214627D01*
G01X426379Y236396D02*
X426221Y236434D01*
G01X424883D02*
X424725Y236396D01*
G01X426379Y235338D02*
X426221Y235412D01*
G01X424883D02*
X424725Y235338D01*
G01X424816Y231737D02*
X424804Y231750D01*
G01X426300D02*
X426289Y231737D01*
G01X424816D02*
X425069Y231368D01*
G01X425024Y230441D02*
X424803Y230762D01*
G01X420883Y231737D02*
X421137Y231368D01*
G01X421092Y230441D02*
X420870Y230762D01*
G01X416942Y231737D02*
X417195Y231368D01*
G01X417150Y230441D02*
X416928Y230762D01*
G01X426080Y215937D02*
X426302Y215615D01*
G01X426289Y214640D02*
X426035Y215009D01*
G01X413009Y231737D02*
X413263Y231368D01*
G01X413217Y230441D02*
X412996Y230762D01*
G01X422139Y215937D02*
X422360Y215615D01*
G01X422347Y214640D02*
X422093Y215009D01*
G01X409068Y231737D02*
X409321Y231368D01*
G01X351930Y236476D02*
X349568D01*
G01X355867D02*
X353505D01*
G01X359804D02*
X357442D01*
G01X363741D02*
X361379D01*
G01X367678D02*
X365316D01*
G01X371615D02*
X369253D01*
G01X375552D02*
X373190D01*
G01X379489D02*
X377127D01*
G01X383426D02*
X381064D01*
G01X387363D02*
X385001D01*
G01X391300D02*
X388938D01*
G01X395237D02*
X392875D01*
G01X399174D02*
X396812D01*
G01X403111D02*
X400749D01*
G01X407048D02*
X404686D01*
G01X410985D02*
X408623D01*
G01X414922D02*
X412560D01*
G01X418859D02*
X416497D01*
G01X422796D02*
X420434D01*
G01X426733D02*
X424371D01*
G01X355355Y235492D02*
X354017D01*
G01X363229D02*
X361891D01*
G01X371103D02*
X369765D01*
G01X378977D02*
X377639D01*
G01X386851D02*
X385513D01*
G01X394725D02*
X393387D01*
G01X402599D02*
X401261D01*
G01X410473D02*
X409135D01*
G01X418347D02*
X417009D01*
G01X426221D02*
X424883D01*
G01X424725Y235393D02*
X426379D01*
G01X416851D02*
X418505D01*
G01X408977D02*
X410631D01*
G01X401103D02*
X402757D01*
G01X393229D02*
X394883D01*
G01X385355D02*
X387009D01*
G01X377481D02*
X379135D01*
G01X369607D02*
X371261D01*
G01X361733D02*
X363387D01*
G01X353859D02*
X355513D01*
G01X351930Y235295D02*
X349568D01*
G01X355867D02*
X353505D01*
G01X359804D02*
X357442D01*
G01X363741D02*
X361379D01*
G01X367678D02*
X365316D01*
G01X371615D02*
X369253D01*
G01X375552D02*
X373190D01*
G01X379489D02*
X377127D01*
G01X383426D02*
X381064D01*
G01X387363D02*
X385001D01*
G01X391300D02*
X388938D01*
G01X395237D02*
X392875D01*
G01X399174D02*
X396812D01*
G01X403111D02*
X400749D01*
G01X407048D02*
X404686D01*
G01X410985D02*
X408623D01*
G01X414922D02*
X412560D01*
G01X418859D02*
X416497D01*
G01X422796D02*
X420434D01*
G01X426733D02*
X424371D01*
G01X409276Y230441D02*
X409054Y230762D01*
G01X418206Y215937D02*
X418428Y215615D01*
G01X418415Y214640D02*
X418161Y215009D01*
G01X405135Y231737D02*
X405389Y231368D01*
G01X405343Y230441D02*
X405122Y230762D01*
G01X414265Y215937D02*
X414486Y215615D01*
G01X414473Y214640D02*
X414219Y215009D01*
G01X401447Y231368D02*
X401194Y231737D01*
G01X401182Y230760D02*
X401402Y230441D01*
G01X410332Y215937D02*
X410554Y215615D01*
G01X410541Y214640D02*
X410287Y215009D01*
G01X397515Y231368D02*
X397261Y231737D01*
G01X397469Y230441D02*
X397248Y230762D01*
G01X406391Y215937D02*
X406612Y215615D01*
G01X406599Y214640D02*
X406345Y215009D01*
G01X393573Y231368D02*
X393320Y231737D01*
G01X393308Y230760D02*
X393528Y230441D01*
G01X402678Y215617D02*
X402458Y215937D01*
G01X402413Y215009D02*
X402667Y214640D01*
G01X389641Y231368D02*
X389387Y231737D01*
G01X389595Y230441D02*
X389374Y230762D01*
G01X398517Y215937D02*
X398738Y215615D01*
G01X398471Y215009D02*
X398725Y214640D01*
G01X385446Y231737D02*
X385699Y231368D01*
G01X385654Y230441D02*
X385432Y230762D01*
G01X394804Y215617D02*
X394584Y215937D01*
G01X394539Y215009D02*
X394793Y214640D01*
G01X381513Y231737D02*
X381767Y231368D01*
G01X381721Y230441D02*
X381500Y230762D01*
G01X390643Y215937D02*
X390864Y215615D01*
G01X390597Y215009D02*
X390851Y214640D01*
G01X355513Y234901D02*
X353859D01*
G01X363387D02*
X361733D01*
G01X371261D02*
X369607D01*
G01X379135D02*
X377481D01*
G01X387009D02*
X385355D01*
G01X394883D02*
X393229D01*
G01X402757D02*
X401103D01*
G01X410631D02*
X408977D01*
G01X418505D02*
X416851D01*
G01X426379D02*
X424725D01*
G01X352166Y234035D02*
X349332D01*
G01X356103D02*
X353269D01*
G01X360040D02*
X357206D01*
G01X363977D02*
X361143D01*
G01X367914D02*
X365080D01*
G01X371851D02*
X369017D01*
G01X375788D02*
X372954D01*
G01X379725D02*
X376891D01*
G01X383662D02*
X380828D01*
G01X387599D02*
X384765D01*
G01X391536D02*
X388702D01*
G01X395473D02*
X392639D01*
G01X399410D02*
X396576D01*
G01X403347D02*
X400513D01*
G01X407284D02*
X404450D01*
G01X411221D02*
X408387D01*
G01X415158D02*
X412324D01*
G01X419095D02*
X416261D01*
G01X423032D02*
X420198D01*
G01X426969D02*
X424135D01*
G01X355513Y233130D02*
X353859D01*
G01X363387D02*
X361733D01*
G01X371261D02*
X369607D01*
G01X379135D02*
X377481D01*
G01X387009D02*
X385355D01*
G01X394883D02*
X393229D01*
G01X402757D02*
X401103D01*
G01X410631D02*
X408977D01*
G01X418505D02*
X416851D01*
G01X426379D02*
X424725D01*
G01Y232637D02*
X426379D01*
G01X416851D02*
X418505D01*
G01X408977D02*
X410631D01*
G01X401103D02*
X402757D01*
G01X393229D02*
X394883D01*
G01X385355D02*
X387009D01*
G01X377481D02*
X379135D01*
G01X369607D02*
X371261D01*
G01X361733D02*
X363387D01*
G01X353859D02*
X355513D01*
G01X352166Y232539D02*
X349332D01*
G01X356103D02*
X353269D01*
G01X360040D02*
X357206D01*
G01X363977D02*
X361143D01*
G01X367914D02*
X365080D01*
G01X371851D02*
X369017D01*
G01X375788D02*
X372954D01*
G01X379725D02*
X376891D01*
G01X383662D02*
X380828D01*
G01X387599D02*
X384765D01*
G01X391536D02*
X388702D01*
G01X395473D02*
X392639D01*
G01X399410D02*
X396576D01*
G01X403347D02*
X400513D01*
G01X407284D02*
X404450D01*
G01X411221D02*
X408387D01*
G01X415158D02*
X412324D01*
G01X419095D02*
X416261D01*
G01X423032D02*
X420198D01*
G01X426969D02*
X424135D01*
G01X426379Y232382D02*
X426969D01*
G01X424135D02*
X424725D01*
G01X422442D02*
X423032D01*
G01X420198D02*
X420788D01*
G01X418505D02*
X419095D01*
G01X416261D02*
X416851D01*
G01X414568D02*
X415158D01*
G01X412324D02*
X412914D01*
G01X410631D02*
X411221D01*
G01X408387D02*
X408977D01*
G01X406694D02*
X407284D01*
G01X404450D02*
X405040D01*
G01X402757D02*
X403347D01*
G01X400513D02*
X401103D01*
G01X398820D02*
X399410D01*
G01X396576D02*
X397166D01*
G01X394883D02*
X395473D01*
G01X392639D02*
X393229D01*
G01X390946D02*
X391536D01*
G01X388702D02*
X389292D01*
G01X387009D02*
X387599D01*
G01X384765D02*
X385355D01*
G01X383072D02*
X383662D01*
G01X380828D02*
X381418D01*
G01X379135D02*
X379725D01*
G01X376891D02*
X377481D01*
G01X375198D02*
X375788D01*
G01X372954D02*
X373544D01*
G01X371261D02*
X371851D01*
G01X369017D02*
X369607D01*
G01X367324D02*
X367914D01*
G01X365080D02*
X365670D01*
G01X363387D02*
X363977D01*
G01X361143D02*
X361733D01*
G01X359450D02*
X360040D01*
G01X357206D02*
X357796D01*
G01X355513D02*
X356103D01*
G01X353269D02*
X353859D01*
G01X351576D02*
X352166D01*
G01X349332D02*
X349922D01*
G01X347639D02*
X348229D01*
G01X424547Y232147D02*
X426558D01*
G01X420614D02*
X422625D01*
G01X416673D02*
X418684D01*
G01X412740D02*
X414751D01*
G01X408798D02*
X410810D01*
G01X404866D02*
X406877D01*
G01X400924D02*
X402936D01*
G01X396992D02*
X399003D01*
G01X393050D02*
X395062D01*
G01X389118D02*
X391129D01*
G01X385176D02*
X387188D01*
G01X381244D02*
X383255D01*
G01X377302D02*
X379314D01*
G01X373370D02*
X375381D01*
G01X369428D02*
X371440D01*
G01X365496D02*
X367507D01*
G01X361554D02*
X363566D01*
G01X357622D02*
X359633D01*
G01X353680D02*
X355692D01*
G01X349748D02*
X351759D01*
G01X351503Y231756D02*
X350004D01*
G01X355436D02*
X353936D01*
G01X359377D02*
X357878D01*
G01X363310D02*
X361810D01*
G01X367251D02*
X365752D01*
G01X371184D02*
X369684D01*
G01X375125D02*
X373626D01*
G01X379058D02*
X377558D01*
G01X382999D02*
X381500D01*
G01X386932D02*
X385432D01*
G01X390873D02*
X389374D01*
G01X394806D02*
X393306D01*
G01X398747D02*
X397248D01*
G01X402680D02*
X401180D01*
G01X406621D02*
X405122D01*
G01X410554D02*
X409054D01*
G01X414496D02*
X412996D01*
G01X418428D02*
X416928D01*
G01X422370D02*
X420870D01*
G01X426302D02*
X424802D01*
G01X424816Y231737D02*
X426289D01*
G01X420883D02*
X422356D01*
G01X416942D02*
X418415D01*
G01X413009D02*
X414482D01*
G01X409068D02*
X410541D01*
G01X405135D02*
X406608D01*
G01X401194D02*
X402667D01*
G01X397261D02*
X398734D01*
G01X393320D02*
X394793D01*
G01X389387D02*
X390860D01*
G01X385446D02*
X386919D01*
G01X381513D02*
X382986D01*
G01X377572D02*
X379045D01*
G01X373639D02*
X375112D01*
G01X369698D02*
X371171D01*
G01X365765D02*
X367238D01*
G01X361824D02*
X363297D01*
G01X357891D02*
X359364D01*
G01X353950D02*
X355423D01*
G01X350017D02*
X351490D01*
G01X348229Y231712D02*
X347639D01*
G01X349922D02*
X349332D01*
G01X352166D02*
X351576D01*
G01X353859D02*
X353269D01*
G01X356103D02*
X355513D01*
G01X357796D02*
X357206D01*
G01X360040D02*
X359450D01*
G01X361733D02*
X361143D01*
G01X363977D02*
X363387D01*
G01X365670D02*
X365080D01*
G01X367914D02*
X367324D01*
G01X369607D02*
X369017D01*
G01X371851D02*
X371261D01*
G01X373544D02*
X372954D01*
G01X375788D02*
X375198D01*
G01X377481D02*
X376891D01*
G01X379725D02*
X379135D01*
G01X381418D02*
X380828D01*
G01X383662D02*
X383072D01*
G01X385355D02*
X384765D01*
G01X387599D02*
X387009D01*
G01X389292D02*
X388702D01*
G01X391536D02*
X390946D01*
G01X393229D02*
X392639D01*
G01X395473D02*
X394883D01*
G01X397166D02*
X396576D01*
G01X399410D02*
X398820D01*
G01X401103D02*
X400513D01*
G01X403347D02*
X402757D01*
G01X405040D02*
X404450D01*
G01X407284D02*
X406694D01*
G01X408977D02*
X408387D01*
G01X411221D02*
X410631D01*
G01X412914D02*
X412324D01*
G01X415158D02*
X414568D01*
G01X416851D02*
X416261D01*
G01X419095D02*
X418505D01*
G01X420788D02*
X420198D01*
G01X423032D02*
X422442D01*
G01X424725D02*
X424135D01*
G01X426969D02*
X426379D01*
G01X424135Y231555D02*
X426969D01*
G01X420198D02*
X423032D01*
G01X416261D02*
X419095D01*
G01X412324D02*
X415158D01*
G01X408387D02*
X411221D01*
G01X404450D02*
X407284D01*
G01X400513D02*
X403347D01*
G01X396576D02*
X399410D01*
G01X392639D02*
X395473D01*
G01X388702D02*
X391536D01*
G01X384765D02*
X387599D01*
G01X376891D02*
X379725D01*
G01X372954D02*
X375788D01*
G01X369017D02*
X371851D01*
G01X365080D02*
X367914D01*
G01X361143D02*
X363977D01*
G01X357206D02*
X360040D01*
G01X353269D02*
X356103D01*
G01X352166D02*
X349332D01*
G01X383662D02*
X380828D01*
G01X351576Y231456D02*
X349922D01*
G01X359450D02*
X357796D01*
G01X367324D02*
X365670D01*
G01X375198D02*
X373544D01*
G01X383072D02*
X381418D01*
G01X390946D02*
X389292D01*
G01X398820D02*
X397166D01*
G01X406694D02*
X405040D01*
G01X414568D02*
X412914D01*
G01X422442D02*
X420788D01*
G01X351236Y231368D02*
X350271D01*
G01X355169D02*
X354203D01*
G01X359110D02*
X358145D01*
G01X363043D02*
X362077D01*
G01X366984D02*
X366019D01*
G01X370917D02*
X369951D01*
G01X374858D02*
X373893D01*
G01X378791D02*
X377825D01*
G01X382732D02*
X381767D01*
G01X386665D02*
X385699D01*
G01X390606D02*
X389641D01*
G01X394539D02*
X393573D01*
G01X398480D02*
X397515D01*
G01X402413D02*
X401447D01*
G01X406354D02*
X405389D01*
G01X410287D02*
X409321D01*
G01X414228D02*
X413263D01*
G01X418161D02*
X417195D01*
G01X422102D02*
X421137D01*
G01X426035D02*
X425069D01*
G01X424135Y231358D02*
X424450D01*
G01X420198D02*
X420513D01*
G01X416261D02*
X416576D01*
G01X412324D02*
X412639D01*
G01X408387D02*
X408702D01*
G01X404450D02*
X404765D01*
G01X396576D02*
X396891D01*
G01X388702D02*
X389017D01*
G01X384765D02*
X385080D01*
G01X380828D02*
X381143D01*
G01X376891D02*
X377206D01*
G01X372954D02*
X373269D01*
G01X369017D02*
X369332D01*
G01X365080D02*
X365395D01*
G01X361143D02*
X361458D01*
G01X357206D02*
X357521D01*
G01X353269D02*
X353584D01*
G01X349332D02*
X349647D01*
G01X348229D02*
X347914D01*
G01X352166D02*
X351851D01*
G01X356103D02*
X355788D01*
G01X360040D02*
X359725D01*
G01X363977D02*
X363662D01*
G01X367914D02*
X367599D01*
G01X371851D02*
X371536D01*
G01X375788D02*
X375473D01*
G01X379725D02*
X379410D01*
G01X383662D02*
X383347D01*
G01X387599D02*
X387284D01*
G01X391536D02*
X391221D01*
G01X392954D02*
X392639D01*
G01X395473D02*
X395158D01*
G01X399410D02*
X399095D01*
G01X400828D02*
X400513D01*
G01X403347D02*
X403032D01*
G01X407284D02*
X406969D01*
G01X411221D02*
X410906D01*
G01X415158D02*
X414843D01*
G01X419095D02*
X418780D01*
G01X423032D02*
X422717D01*
G01X426969D02*
X426655D01*
G01X351764Y231260D02*
X349743D01*
G01X355696D02*
X353676D01*
G01X359638D02*
X357617D01*
G01X363570D02*
X361550D01*
G01X367512D02*
X365491D01*
G01X371444D02*
X369424D01*
G01X375386D02*
X373365D01*
G01X379318D02*
X377298D01*
G01X383260D02*
X381239D01*
G01X387192D02*
X385172D01*
G01X391134D02*
X389113D01*
G01X395066D02*
X393046D01*
G01X399008D02*
X396987D01*
G01X402941D02*
X400920D01*
G01X406882D02*
X404861D01*
G01X410815D02*
X408794D01*
G01X414756D02*
X412735D01*
G01X418689D02*
X416668D01*
G01X422630D02*
X420609D01*
G01X426563D02*
X424542D01*
G01X420788Y230964D02*
X422442D01*
G01X412914D02*
X414568D01*
G01X405040D02*
X406694D01*
G01X397166D02*
X398820D01*
G01X389292D02*
X390946D01*
G01X381418D02*
X383072D01*
G01X373544D02*
X375198D01*
G01X365670D02*
X367324D01*
G01X357796D02*
X359450D01*
G01X349922D02*
X351576D01*
G01X351503Y230772D02*
X350004D01*
G01X355436D02*
X353936D01*
G01X359377D02*
X357878D01*
G01X363310D02*
X361810D01*
G01X367251D02*
X365752D01*
G01X371184D02*
X369684D01*
G01X375125D02*
X373626D01*
G01X379058D02*
X377558D01*
G01X382999D02*
X381500D01*
G01X386932D02*
X385432D01*
G01X390873D02*
X389374D01*
G01X394806D02*
X393306D01*
G01X398747D02*
X397248D01*
G01X402680D02*
X401180D01*
G01X406621D02*
X405122D01*
G01X410554D02*
X409054D01*
G01X414496D02*
X412996D01*
G01X418428D02*
X416928D01*
G01X422370D02*
X420870D01*
G01X426302D02*
X424802D01*
G01X351502Y230762D02*
X350005D01*
G01X355434D02*
X353938D01*
G01X359376D02*
X357879D01*
G01X363308D02*
X361812D01*
G01X367250D02*
X365753D01*
G01X371182D02*
X369686D01*
G01X375124D02*
X373627D01*
G01X379056D02*
X377560D01*
G01X382998D02*
X381502D01*
G01X386930D02*
X385434D01*
G01X390872D02*
X389376D01*
G01X394804D02*
X393308D01*
G01X398746D02*
X397250D01*
G01X402678D02*
X401182D01*
G01X406620D02*
X405124D01*
G01X410552D02*
X409056D01*
G01X414494D02*
X412998D01*
G01X418426D02*
X416930D01*
G01X422368D02*
X420872D01*
G01X426300D02*
X424804D01*
G01X425024Y230441D02*
X426080D01*
G01X421092D02*
X422148D01*
G01X417150D02*
X418206D01*
G01X413217D02*
X414274D01*
G01X409276D02*
X410332D01*
G01X405343D02*
X406400D01*
G01X401402D02*
X402458D01*
G01X397469D02*
X398526D01*
G01X393528D02*
X394584D01*
G01X389595D02*
X390652D01*
G01X385654D02*
X386710D01*
G01X381721D02*
X382778D01*
G01X377780D02*
X378836D01*
G01X373847D02*
X374904D01*
G01X369906D02*
X370962D01*
G01X365973D02*
X367030D01*
G01X362032D02*
X363088D01*
G01X358099D02*
X359156D01*
G01X354158D02*
X355214D01*
G01X350225D02*
X351282D01*
G01X400749Y230393D02*
X403111D01*
G01X396812D02*
X399174D01*
G01X392875D02*
X395237D01*
G01X351930D02*
X349568D01*
G01X355867D02*
X353505D01*
G01X359804D02*
X357442D01*
G01X363741D02*
X361379D01*
G01X367678D02*
X365316D01*
G01X371615D02*
X369253D01*
G01X375552D02*
X373190D01*
G01X379489D02*
X377127D01*
G01X383426D02*
X381064D01*
G01X387363D02*
X385001D01*
G01X391300D02*
X388938D01*
G01X407048D02*
X404686D01*
G01X410985D02*
X408623D01*
G01X414922D02*
X412560D01*
G01X418859D02*
X416497D01*
G01X422796D02*
X420434D01*
G01X426733D02*
X424371D01*
G01X426655Y229862D02*
X426969D01*
G01X424135D02*
X424450D01*
G01X422717D02*
X423032D01*
G01X420198D02*
X420513D01*
G01X418780D02*
X419095D01*
G01X416261D02*
X416576D01*
G01X414843D02*
X415158D01*
G01X412324D02*
X412639D01*
G01X410906D02*
X411221D01*
G01X408387D02*
X408702D01*
G01X406969D02*
X407284D01*
G01X403032D02*
X403347D01*
G01X404450D02*
X404765D01*
G01X400513D02*
X400828D01*
G01X399095D02*
X399410D01*
G01X396576D02*
X396891D01*
G01X395158D02*
X395473D01*
G01X392639D02*
X392954D01*
G01X391221D02*
X391536D01*
G01X388702D02*
X389017D01*
G01X387284D02*
X387599D01*
G01X384765D02*
X385080D01*
G01X383347D02*
X383662D01*
G01X380828D02*
X381143D01*
G01X379410D02*
X379725D01*
G01X376891D02*
X377206D01*
G01X375473D02*
X375788D01*
G01X372954D02*
X373269D01*
G01X371536D02*
X371851D01*
G01X369017D02*
X369332D01*
G01X367599D02*
X367914D01*
G01X365080D02*
X365395D01*
G01X363662D02*
X363977D01*
G01X361143D02*
X361458D01*
G01X359725D02*
X360040D01*
G01X357206D02*
X357521D01*
G01X355788D02*
X356103D01*
G01X353269D02*
X353584D01*
G01X351851D02*
X352166D01*
G01X349332D02*
X349647D01*
G01X347914D02*
X348229D01*
G01X424780Y229826D02*
X426324D01*
G01X420848D02*
X422391D01*
G01X416906D02*
X418450D01*
G01X412974D02*
X414517D01*
G01X409032D02*
X410576D01*
G01X405100D02*
X406643D01*
G01X401158D02*
X402702D01*
G01X397226D02*
X398769D01*
G01X393284D02*
X394828D01*
G01X389352D02*
X390895D01*
G01X385410D02*
X386954D01*
G01X381478D02*
X383021D01*
G01X377536D02*
X379080D01*
G01X373604D02*
X375147D01*
G01X369662D02*
X371206D01*
G01X365730D02*
X367273D01*
G01X361788D02*
X363332D01*
G01X357856D02*
X359399D01*
G01X353914D02*
X355458D01*
G01X349982D02*
X351525D01*
G01X424791Y229807D02*
X426313D01*
G01X420859D02*
X422381D01*
G01X416917D02*
X418439D01*
G01X412985D02*
X414507D01*
G01X409043D02*
X410565D01*
G01X405111D02*
X406632D01*
G01X401169D02*
X402691D01*
G01X397237D02*
X398758D01*
G01X393295D02*
X394817D01*
G01X389363D02*
X390884D01*
G01X385421D02*
X386943D01*
G01X381489D02*
X383010D01*
G01X377547D02*
X379069D01*
G01X373615D02*
X375136D01*
G01X369673D02*
X371195D01*
G01X365741D02*
X367262D01*
G01X361799D02*
X363321D01*
G01X357867D02*
X359388D01*
G01X353925D02*
X355447D01*
G01X349993D02*
X351514D01*
G01X420788Y229193D02*
X422442D01*
G01X412914D02*
X414568D01*
G01X405040D02*
X406694D01*
G01X397166D02*
X398820D01*
G01X389292D02*
X390946D01*
G01X381418D02*
X383072D01*
G01X373544D02*
X375198D01*
G01X365670D02*
X367324D01*
G01X357796D02*
X359450D01*
G01X349922D02*
X351576D01*
G01Y228700D02*
X349922D01*
G01X359450D02*
X357796D01*
G01X367324D02*
X365670D01*
G01X375198D02*
X373544D01*
G01X383072D02*
X381418D01*
G01X390946D02*
X389292D01*
G01X398820D02*
X397166D01*
G01X406694D02*
X405040D01*
G01X414568D02*
X412914D01*
G01X422442D02*
X420788D01*
G01X351418Y228602D02*
X350080D01*
G01X359292D02*
X357954D01*
G01X367166D02*
X365828D01*
G01X375040D02*
X373702D01*
G01X382914D02*
X381576D01*
G01X390788D02*
X389450D01*
G01X398662D02*
X397324D01*
G01X406536D02*
X405198D01*
G01X414410D02*
X413072D01*
G01X422284D02*
X420946D01*
G01Y227618D02*
X422284D01*
G01X413072D02*
X414410D01*
G01X405198D02*
X406536D01*
G01X397324D02*
X398662D01*
G01X389450D02*
X390788D01*
G01X381576D02*
X382914D01*
G01X373702D02*
X375040D01*
G01X365828D02*
X367166D01*
G01X357954D02*
X359292D01*
G01X350080D02*
X351418D01*
G01X351551Y226999D02*
X349956D01*
G01X355484D02*
X353888D01*
G01X359425D02*
X357830D01*
G01X363358D02*
X361762D01*
G01X367299D02*
X365704D01*
G01X371232D02*
X369636D01*
G01X375173D02*
X373578D01*
G01X379106D02*
X377510D01*
G01X383047D02*
X381452D01*
G01X386980D02*
X385384D01*
G01X390921D02*
X389326D01*
G01X394854D02*
X393258D01*
G01X398795D02*
X397200D01*
G01X402728D02*
X401133D01*
G01X406669D02*
X405074D01*
G01X410602D02*
X409007D01*
G01X414543D02*
X412948D01*
G01X418476D02*
X416881D01*
G01X422417D02*
X420822D01*
G01X426350D02*
X424755D01*
G01X351851Y226889D02*
X349647D01*
G01X355788D02*
X353584D01*
G01X359725D02*
X357521D01*
G01X363662D02*
X361458D01*
G01X367599D02*
X365395D01*
G01X371536D02*
X369332D01*
G01X375473D02*
X373269D01*
G01X379410D02*
X377206D01*
G01X383347D02*
X381143D01*
G01X387284D02*
X385080D01*
G01X391221D02*
X389017D01*
G01X395158D02*
X392954D01*
G01X399095D02*
X396891D01*
G01X403032D02*
X400828D01*
G01X406969D02*
X404765D01*
G01X410906D02*
X408702D01*
G01X414843D02*
X412639D01*
G01X418780D02*
X416576D01*
G01X422717D02*
X420513D01*
G01X426655D02*
X424450D01*
G01X351623Y226239D02*
X349884D01*
G01X355555D02*
X353817D01*
G01X359497D02*
X357758D01*
G01X363429D02*
X361691D01*
G01X367371D02*
X365632D01*
G01X371303D02*
X369565D01*
G01X375245D02*
X373506D01*
G01X379177D02*
X377439D01*
G01X383119D02*
X381380D01*
G01X387051D02*
X385313D01*
G01X390993D02*
X389254D01*
G01X394925D02*
X393187D01*
G01X398867D02*
X397128D01*
G01X402799D02*
X401061D01*
G01X406741D02*
X405002D01*
G01X410674D02*
X408935D01*
G01X414615D02*
X412876D01*
G01X418548D02*
X416809D01*
G01X422489D02*
X420750D01*
G01X426422D02*
X424683D01*
G01X424757Y226037D02*
X426347D01*
G01X420825D02*
X422415D01*
G01X416883D02*
X418473D01*
G01X412951D02*
X414541D01*
G01X409009D02*
X410599D01*
G01X405077D02*
X406667D01*
G01X401135D02*
X402725D01*
G01X397203D02*
X398793D01*
G01X393261D02*
X394851D01*
G01X389328D02*
X390919D01*
G01X385387D02*
X386977D01*
G01X381454D02*
X383045D01*
G01X377513D02*
X379103D01*
G01X373580D02*
X375171D01*
G01X369639D02*
X371229D01*
G01X365706D02*
X367297D01*
G01X361765D02*
X363355D01*
G01X357832D02*
X359423D01*
G01X353891D02*
X355481D01*
G01X349958D02*
X351549D01*
G01X424704Y226012D02*
X426400D01*
G01X420772D02*
X422468D01*
G01X416830D02*
X418526D01*
G01X412898D02*
X414594D01*
G01X408956D02*
X410652D01*
G01X405024D02*
X406720D01*
G01X401082D02*
X402778D01*
G01X397150D02*
X398846D01*
G01X393208D02*
X394904D01*
G01X389276D02*
X390972D01*
G01X385334D02*
X387030D01*
G01X381402D02*
X383098D01*
G01X377460D02*
X379156D01*
G01X373528D02*
X375224D01*
G01X369586D02*
X371282D01*
G01X365654D02*
X367350D01*
G01X361712D02*
X363408D01*
G01X357780D02*
X359476D01*
G01X353838D02*
X355534D01*
G01X349906D02*
X351602D01*
G01X351609Y225945D02*
X349899D01*
G01X355541D02*
X353831D01*
G01X359483D02*
X357773D01*
G01X363415D02*
X361705D01*
G01X367357D02*
X365647D01*
G01X371289D02*
X369579D01*
G01X375231D02*
X373521D01*
G01X379163D02*
X377453D01*
G01X383105D02*
X381395D01*
G01X387037D02*
X385327D01*
G01X390979D02*
X389269D01*
G01X394911D02*
X393201D01*
G01X398853D02*
X397143D01*
G01X402785D02*
X401075D01*
G01X406727D02*
X405017D01*
G01X410659D02*
X408949D01*
G01X414601D02*
X412891D01*
G01X418533D02*
X416823D01*
G01X422475D02*
X420765D01*
G01X426407D02*
X424697D01*
G01X424678Y225353D02*
X426426D01*
G01X420746D02*
X422494D01*
G01X416804D02*
X418552D01*
G01X412872D02*
X414620D01*
G01X408930D02*
X410678D01*
G01X404998D02*
X406746D01*
G01X401056D02*
X402804D01*
G01X397124D02*
X398872D01*
G01X393182D02*
X394930D01*
G01X389250D02*
X390998D01*
G01X385308D02*
X387056D01*
G01X381376D02*
X383124D01*
G01X377434D02*
X379182D01*
G01X373502D02*
X375250D01*
G01X369560D02*
X371308D01*
G01X365628D02*
X367376D01*
G01X361686D02*
X363434D01*
G01X357753D02*
X359502D01*
G01X353812D02*
X355560D01*
G01X349879D02*
X351628D01*
G01X351599Y225050D02*
X349908D01*
G01X355532D02*
X353840D01*
G01X359473D02*
X357782D01*
G01X363406D02*
X361714D01*
G01X367347D02*
X365656D01*
G01X371280D02*
X369588D01*
G01X375221D02*
X373530D01*
G01X379154D02*
X377462D01*
G01X383095D02*
X381404D01*
G01X387028D02*
X385336D01*
G01X390969D02*
X389278D01*
G01X394902D02*
X393210D01*
G01X398843D02*
X397152D01*
G01X402776D02*
X401084D01*
G01X406718D02*
X405026D01*
G01X410650D02*
X408958D01*
G01X414592D02*
X412900D01*
G01X418524D02*
X416832D01*
G01X422466D02*
X420774D01*
G01X426398D02*
X424706D01*
G01X351609Y224960D02*
X349899D01*
G01X355541D02*
X353831D01*
G01X359483D02*
X357773D01*
G01X363415D02*
X361705D01*
G01X367357D02*
X365647D01*
G01X371289D02*
X369579D01*
G01X375231D02*
X373521D01*
G01X379163D02*
X377453D01*
G01X383105D02*
X381395D01*
G01X387037D02*
X385327D01*
G01X390979D02*
X389269D01*
G01X394911D02*
X393201D01*
G01X398853D02*
X397143D01*
G01X402785D02*
X401075D01*
G01X406727D02*
X405017D01*
G01X410659D02*
X408949D01*
G01X414601D02*
X412891D01*
G01X418533D02*
X416823D01*
G01X422475D02*
X420765D01*
G01X426407D02*
X424697D01*
G01X424450Y224634D02*
X426655D01*
G01X420513D02*
X422717D01*
G01X416576D02*
X418780D01*
G01X412639D02*
X414843D01*
G01X408702D02*
X410906D01*
G01X404765D02*
X406969D01*
G01X400828D02*
X403032D01*
G01X396891D02*
X399095D01*
G01X392954D02*
X395158D01*
G01X389017D02*
X391221D01*
G01X385080D02*
X387284D01*
G01X381143D02*
X383347D01*
G01X377206D02*
X379410D01*
G01X373269D02*
X375473D01*
G01X369332D02*
X371536D01*
G01X365395D02*
X367599D01*
G01X361458D02*
X363662D01*
G01X357521D02*
X359725D01*
G01X353584D02*
X355788D01*
G01X349647D02*
X351851D01*
G01X424450Y224467D02*
X426655D01*
G01X420513D02*
X422717D01*
G01X416576D02*
X418780D01*
G01X412639D02*
X414843D01*
G01X408702D02*
X410906D01*
G01X404765D02*
X406969D01*
G01X400828D02*
X403032D01*
G01X396891D02*
X399095D01*
G01X392954D02*
X395158D01*
G01X389017D02*
X391221D01*
G01X385080D02*
X387284D01*
G01X381143D02*
X383347D01*
G01X377206D02*
X379410D01*
G01X373269D02*
X375473D01*
G01X369332D02*
X371536D01*
G01X365395D02*
X367599D01*
G01X361458D02*
X363662D01*
G01X357521D02*
X359725D01*
G01X353584D02*
X355788D01*
G01X349647D02*
X351851D01*
G01Y221910D02*
X349647D01*
G01X355788D02*
X353584D01*
G01X359725D02*
X357521D01*
G01X363662D02*
X361458D01*
G01X367599D02*
X365395D01*
G01X371536D02*
X369332D01*
G01X375473D02*
X373269D01*
G01X379410D02*
X377206D01*
G01X383347D02*
X381143D01*
G01X387284D02*
X385080D01*
G01X391221D02*
X389017D01*
G01X395158D02*
X392954D01*
G01X399095D02*
X396891D01*
G01X403032D02*
X400828D01*
G01X406969D02*
X404765D01*
G01X410906D02*
X408702D01*
G01X414843D02*
X412639D01*
G01X418780D02*
X416576D01*
G01X422717D02*
X420513D01*
G01X426655D02*
X424450D01*
G01X351851Y221743D02*
X349647D01*
G01X355788D02*
X353584D01*
G01X359725D02*
X357521D01*
G01X363662D02*
X361458D01*
G01X367599D02*
X365395D01*
G01X371536D02*
X369332D01*
G01X375473D02*
X373269D01*
G01X379410D02*
X377206D01*
G01X383347D02*
X381143D01*
G01X387284D02*
X385080D01*
G01X391221D02*
X389017D01*
G01X395158D02*
X392954D01*
G01X399095D02*
X396891D01*
G01X403032D02*
X400828D01*
G01X406969D02*
X404765D01*
G01X410906D02*
X408702D01*
G01X414843D02*
X412639D01*
G01X418780D02*
X416576D01*
G01X422717D02*
X420513D01*
G01X426655D02*
X424450D01*
G01X424697Y221417D02*
X426407D01*
G01X420755D02*
X422466D01*
G01X416823D02*
X418533D01*
G01X412881D02*
X414592D01*
G01X408949D02*
X410659D01*
G01X405007D02*
X406718D01*
G01X401075D02*
X402785D01*
G01X397133D02*
X398843D01*
G01X393201D02*
X394911D01*
G01X389259D02*
X390969D01*
G01X385327D02*
X387037D01*
G01X381385D02*
X383095D01*
G01X377453D02*
X379163D01*
G01X373511D02*
X375221D01*
G01X369579D02*
X371289D01*
G01X365637D02*
X367347D01*
G01X361705D02*
X363415D01*
G01X357763D02*
X359473D01*
G01X353831D02*
X355541D01*
G01X349889D02*
X351599D01*
G01X424706Y221327D02*
X426398D01*
G01X420765D02*
X422456D01*
G01X416832D02*
X418524D01*
G01X412891D02*
X414582D01*
G01X408958D02*
X410650D01*
G01X405017D02*
X406708D01*
G01X401084D02*
X402776D01*
G01X397143D02*
X398834D01*
G01X393210D02*
X394902D01*
G01X389269D02*
X390960D01*
G01X385336D02*
X387028D01*
G01X381395D02*
X383086D01*
G01X377462D02*
X379154D01*
G01X373521D02*
X375212D01*
G01X369588D02*
X371280D01*
G01X365647D02*
X367338D01*
G01X361714D02*
X363406D01*
G01X357773D02*
X359464D01*
G01X353840D02*
X355532D01*
G01X349899D02*
X351590D01*
G01X351619Y221024D02*
X349870D01*
G01X355560D02*
X353812D01*
G01X359493D02*
X357744D01*
G01X363434D02*
X361686D01*
G01X367367D02*
X365618D01*
G01X371308D02*
X369560D01*
G01X375241D02*
X373492D01*
G01X379182D02*
X377434D01*
G01X383115D02*
X381366D01*
G01X387056D02*
X385308D01*
G01X390989D02*
X389240D01*
G01X394930D02*
X393182D01*
G01X398863D02*
X397114D01*
G01X402804D02*
X401056D01*
G01X406737D02*
X404988D01*
G01X410678D02*
X408930D01*
G01X414611D02*
X412862D01*
G01X418552D02*
X416804D01*
G01X422485D02*
X420736D01*
G01X426426D02*
X424678D01*
G01X424697Y220433D02*
X426407D01*
G01X420755D02*
X422466D01*
G01X416823D02*
X418533D01*
G01X412881D02*
X414592D01*
G01X408949D02*
X410659D01*
G01X405007D02*
X406718D01*
G01X401075D02*
X402785D01*
G01X397133D02*
X398843D01*
G01X393201D02*
X394911D01*
G01X389259D02*
X390969D01*
G01X385327D02*
X387037D01*
G01X381385D02*
X383095D01*
G01X377453D02*
X379163D01*
G01X373511D02*
X375221D01*
G01X369579D02*
X371289D01*
G01X365637D02*
X367347D01*
G01X361705D02*
X363415D01*
G01X357763D02*
X359473D01*
G01X353831D02*
X355541D01*
G01X349889D02*
X351599D01*
G01X351592Y220365D02*
X349896D01*
G01X355534D02*
X353838D01*
G01X359466D02*
X357770D01*
G01X363408D02*
X361712D01*
G01X367340D02*
X365644D01*
G01X371282D02*
X369586D01*
G01X375214D02*
X373518D01*
G01X379156D02*
X377460D01*
G01X383088D02*
X381392D01*
G01X387030D02*
X385334D01*
G01X390962D02*
X389266D01*
G01X394904D02*
X393208D01*
G01X398836D02*
X397140D01*
G01X402778D02*
X401082D01*
G01X406711D02*
X405014D01*
G01X410652D02*
X408956D01*
G01X414585D02*
X412888D01*
G01X418526D02*
X416830D01*
G01X422459D02*
X420762D01*
G01X426400D02*
X424704D01*
G01X351540Y220340D02*
X349949D01*
G01X355481D02*
X353891D01*
G01X359414D02*
X357823D01*
G01X363355D02*
X361765D01*
G01X367288D02*
X365697D01*
G01X371229D02*
X369639D01*
G01X375162D02*
X373571D01*
G01X379103D02*
X377513D01*
G01X383036D02*
X381445D01*
G01X386977D02*
X385387D01*
G01X390910D02*
X389319D01*
G01X394851D02*
X393261D01*
G01X398784D02*
X397193D01*
G01X402725D02*
X401135D01*
G01X406658D02*
X405067D01*
G01X410599D02*
X409009D01*
G01X414532D02*
X412941D01*
G01X418473D02*
X416883D01*
G01X422406D02*
X420815D01*
G01X426347D02*
X424757D01*
G01X424683Y220138D02*
X426422D01*
G01X420741D02*
X422480D01*
G01X416809D02*
X418548D01*
G01X412867D02*
X414606D01*
G01X408935D02*
X410674D01*
G01X404993D02*
X406732D01*
G01X401061D02*
X402799D01*
G01X397119D02*
X398858D01*
G01X393187D02*
X394925D01*
G01X389245D02*
X390984D01*
G01X385313D02*
X387051D01*
G01X381371D02*
X383110D01*
G01X377439D02*
X379177D01*
G01X373497D02*
X375236D01*
G01X369565D02*
X371303D01*
G01X365623D02*
X367362D01*
G01X361691D02*
X363429D01*
G01X357749D02*
X359488D01*
G01X353817D02*
X355555D01*
G01X349875D02*
X351614D01*
G01X424450Y219488D02*
X426655D01*
G01X420513D02*
X422717D01*
G01X416576D02*
X418780D01*
G01X412639D02*
X414843D01*
G01X408702D02*
X410906D01*
G01X404765D02*
X406969D01*
G01X400828D02*
X403032D01*
G01X396891D02*
X399095D01*
G01X392954D02*
X395158D01*
G01X389017D02*
X391221D01*
G01X385080D02*
X387284D01*
G01X381143D02*
X383347D01*
G01X377206D02*
X379410D01*
G01X373269D02*
X375473D01*
G01X369332D02*
X371536D01*
G01X365395D02*
X367599D01*
G01X361458D02*
X363662D01*
G01X357521D02*
X359725D01*
G01X353584D02*
X355788D01*
G01X349647D02*
X351851D01*
G01X424755Y219379D02*
X426350D01*
G01X420813D02*
X422408D01*
G01X416881D02*
X418476D01*
G01X412939D02*
X414534D01*
G01X409007D02*
X410602D01*
G01X405065D02*
X406660D01*
G01X401133D02*
X402728D01*
G01X397191D02*
X398786D01*
G01X393258D02*
X394854D01*
G01X389317D02*
X390912D01*
G01X385384D02*
X386980D01*
G01X381443D02*
X383038D01*
G01X377510D02*
X379106D01*
G01X373569D02*
X375164D01*
G01X369636D02*
X371232D01*
G01X365695D02*
X367290D01*
G01X361762D02*
X363358D01*
G01X357821D02*
X359416D01*
G01X353888D02*
X355484D01*
G01X349947D02*
X351542D01*
G01X351418Y218760D02*
X350080D01*
G01X359292D02*
X357954D01*
G01X367166D02*
X365828D01*
G01X375040D02*
X373702D01*
G01X382914D02*
X381576D01*
G01X390788D02*
X389450D01*
G01X398662D02*
X397324D01*
G01X406536D02*
X405198D01*
G01X414410D02*
X413072D01*
G01X422284D02*
X420946D01*
G01X351418Y217775D02*
X350080D01*
G01X359292D02*
X357954D01*
G01X367166D02*
X365828D01*
G01X375040D02*
X373702D01*
G01X382914D02*
X381576D01*
G01X390788D02*
X389450D01*
G01X398662D02*
X397324D01*
G01X406536D02*
X405198D01*
G01X414410D02*
X413072D01*
G01X422284D02*
X420946D01*
G01X420788Y217677D02*
X422442D01*
G01X412914D02*
X414568D01*
G01X405040D02*
X406694D01*
G01X397166D02*
X398820D01*
G01X389292D02*
X390946D01*
G01X381418D02*
X383072D01*
G01X373544D02*
X375198D01*
G01X365670D02*
X367324D01*
G01X357796D02*
X359450D01*
G01X349922D02*
X351576D01*
G01Y217185D02*
X349922D01*
G01X359450D02*
X357796D01*
G01X367324D02*
X365670D01*
G01X375198D02*
X373544D01*
G01X383072D02*
X381418D01*
G01X390946D02*
X389292D01*
G01X398820D02*
X397166D01*
G01X406694D02*
X405040D01*
G01X414568D02*
X412914D01*
G01X422442D02*
X420788D01*
G01X351505Y216570D02*
X349984D01*
G01X355447D02*
X353925D01*
G01X359379D02*
X357858D01*
G01X363321D02*
X361799D01*
G01X367253D02*
X365732D01*
G01X371195D02*
X369673D01*
G01X375127D02*
X373606D01*
G01X379069D02*
X377547D01*
G01X383001D02*
X381480D01*
G01X386943D02*
X385421D01*
G01X390875D02*
X389354D01*
G01X394817D02*
X393295D01*
G01X398749D02*
X397228D01*
G01X402691D02*
X401169D01*
G01X406623D02*
X405102D01*
G01X410565D02*
X409043D01*
G01X414497D02*
X412976D01*
G01X418439D02*
X416917D01*
G01X422371D02*
X420850D01*
G01X426313D02*
X424791D01*
G01X351516Y216551D02*
X349973D01*
G01X355458D02*
X353914D01*
G01X359390D02*
X357847D01*
G01X363332D02*
X361788D01*
G01X367264D02*
X365721D01*
G01X371206D02*
X369662D01*
G01X375138D02*
X373595D01*
G01X379080D02*
X377536D01*
G01X383012D02*
X381469D01*
G01X386954D02*
X385410D01*
G01X390886D02*
X389343D01*
G01X394828D02*
X393284D01*
G01X398760D02*
X397217D01*
G01X402702D02*
X401158D01*
G01X406634D02*
X405091D01*
G01X410576D02*
X409032D01*
G01X414508D02*
X412965D01*
G01X418450D02*
X416906D01*
G01X422382D02*
X420839D01*
G01X426324D02*
X424780D01*
G01X348229Y216515D02*
X347914D01*
G01X349647D02*
X349332D01*
G01X353584D02*
X353269D01*
G01X352166D02*
X351851D01*
G01X356103D02*
X355788D01*
G01X357521D02*
X357206D01*
G01X360040D02*
X359725D01*
G01X361458D02*
X361143D01*
G01X363977D02*
X363662D01*
G01X365395D02*
X365080D01*
G01X367914D02*
X367599D01*
G01X369332D02*
X369017D01*
G01X371851D02*
X371536D01*
G01X373269D02*
X372954D01*
G01X375788D02*
X375473D01*
G01X377206D02*
X376891D01*
G01X379725D02*
X379410D01*
G01X381143D02*
X380828D01*
G01X385080D02*
X384765D01*
G01X383662D02*
X383347D01*
G01X387599D02*
X387284D01*
G01X389017D02*
X388702D01*
G01X391536D02*
X391221D01*
G01X392954D02*
X392639D01*
G01X395473D02*
X395158D01*
G01X396891D02*
X396576D01*
G01X399410D02*
X399095D01*
G01X400828D02*
X400513D01*
G01X403347D02*
X403032D01*
G01X404765D02*
X404450D01*
G01X407284D02*
X406969D01*
G01X408702D02*
X408387D01*
G01X411221D02*
X410906D01*
G01X412639D02*
X412324D01*
G01X415158D02*
X414843D01*
G01X416576D02*
X416261D01*
G01X419095D02*
X418780D01*
G01X420513D02*
X420198D01*
G01X423032D02*
X422717D01*
G01X424450D02*
X424135D01*
G01X426969D02*
X426655D01*
G01X351930Y215984D02*
X349568D01*
G01X355867D02*
X353505D01*
G01X359804D02*
X357442D01*
G01X363741D02*
X361379D01*
G01X367678D02*
X365316D01*
G01X371615D02*
X369253D01*
G01X375552D02*
X373190D01*
G01X379489D02*
X377127D01*
G01X383426D02*
X381064D01*
G01X387363D02*
X385001D01*
G01X391300D02*
X388938D01*
G01X395237D02*
X392875D01*
G01X399174D02*
X396812D01*
G01X403111D02*
X400749D01*
G01X407048D02*
X404686D01*
G01X410985D02*
X408623D01*
G01X414922D02*
X412560D01*
G01X418859D02*
X416497D01*
G01X422796D02*
X420434D01*
G01X426733D02*
X424371D01*
G01X351273Y215937D02*
X350216D01*
G01X355214D02*
X354158D01*
G01X359147D02*
X358090D01*
G01X363088D02*
X362032D01*
G01X367021D02*
X365964D01*
G01X370962D02*
X369906D01*
G01X374895D02*
X373838D01*
G01X378836D02*
X377780D01*
G01X382769D02*
X381712D01*
G01X386710D02*
X385654D01*
G01X390643D02*
X389586D01*
G01X394584D02*
X393528D01*
G01X398517D02*
X397460D01*
G01X402458D02*
X401402D01*
G01X406391D02*
X405334D01*
G01X410332D02*
X409276D01*
G01X414265D02*
X413208D01*
G01X418206D02*
X417150D01*
G01X422139D02*
X421082D01*
G01X426080D02*
X425024D01*
G01X424804Y215615D02*
X426300D01*
G01X420862D02*
X422359D01*
G01X416930D02*
X418426D01*
G01X412988D02*
X414485D01*
G01X409056D02*
X410552D01*
G01X405114D02*
X406611D01*
G01X401182D02*
X402678D01*
G01X397240D02*
X398737D01*
G01X393308D02*
X394804D01*
G01X389366D02*
X390863D01*
G01X385434D02*
X386930D01*
G01X381492D02*
X382989D01*
G01X377560D02*
X379056D01*
G01X373618D02*
X375115D01*
G01X369686D02*
X371182D01*
G01X365744D02*
X367241D01*
G01X361812D02*
X363308D01*
G01X357870D02*
X359367D01*
G01X353938D02*
X355434D01*
G01X349996D02*
X351493D01*
G01X424802Y215605D02*
X426302D01*
G01X420861D02*
X422360D01*
G01X416928D02*
X418428D01*
G01X412987D02*
X414486D01*
G01X409054D02*
X410554D01*
G01X405113D02*
X406612D01*
G01X401180D02*
X402680D01*
G01X397239D02*
X398738D01*
G01X393306D02*
X394806D01*
G01X389365D02*
X390864D01*
G01X385432D02*
X386932D01*
G01X381491D02*
X382990D01*
G01X377558D02*
X379058D01*
G01X373617D02*
X375116D01*
G01X369684D02*
X371184D01*
G01X365743D02*
X367242D01*
G01X361810D02*
X363310D01*
G01X357869D02*
X359368D01*
G01X353936D02*
X355436D01*
G01X349995D02*
X351494D01*
G01X351576Y215413D02*
X349922D01*
G01X359450D02*
X357796D01*
G01X367324D02*
X365670D01*
G01X375198D02*
X373544D01*
G01X383072D02*
X381418D01*
G01X390946D02*
X389292D01*
G01X398820D02*
X397166D01*
G01X406694D02*
X405040D01*
G01X414568D02*
X412914D01*
G01X422442D02*
X420788D01*
G01X424542Y215117D02*
X426563D01*
G01X420600D02*
X422621D01*
G01X416668D02*
X418689D01*
G01X412726D02*
X414747D01*
G01X408794D02*
X410815D01*
G01X404852D02*
X406873D01*
G01X400920D02*
X402941D01*
G01X396978D02*
X398999D01*
G01X393046D02*
X395066D01*
G01X389104D02*
X391125D01*
G01X385172D02*
X387192D01*
G01X381230D02*
X383251D01*
G01X377298D02*
X379318D01*
G01X373356D02*
X375377D01*
G01X369424D02*
X371444D01*
G01X365482D02*
X367503D01*
G01X361550D02*
X363570D01*
G01X357608D02*
X359629D01*
G01X353676D02*
X355696D01*
G01X349734D02*
X351755D01*
G01X426655Y215019D02*
X426969D01*
G01X422717D02*
X423032D01*
G01X418780D02*
X419095D01*
G01X414843D02*
X415158D01*
G01X410906D02*
X411221D01*
G01X406969D02*
X407284D01*
G01X399095D02*
X399410D01*
G01X391221D02*
X391536D01*
G01X387284D02*
X387599D01*
G01X383347D02*
X383662D01*
G01X379410D02*
X379725D01*
G01X375473D02*
X375788D01*
G01X371536D02*
X371851D01*
G01X367599D02*
X367914D01*
G01X363662D02*
X363977D01*
G01X359725D02*
X360040D01*
G01X355788D02*
X356103D01*
G01X351851D02*
X352166D01*
G01X347914D02*
X348229D01*
G01X349647D02*
X349332D01*
G01X353584D02*
X353269D01*
G01X357521D02*
X357206D01*
G01X361458D02*
X361143D01*
G01X365395D02*
X365080D01*
G01X369332D02*
X369017D01*
G01X373269D02*
X372954D01*
G01X377206D02*
X376891D01*
G01X381143D02*
X380828D01*
G01X385080D02*
X384765D01*
G01X389017D02*
X388702D01*
G01X392954D02*
X392639D01*
G01X395473D02*
X395158D01*
G01X396891D02*
X396576D01*
G01X400828D02*
X400513D01*
G01X403347D02*
X403032D01*
G01X404765D02*
X404450D01*
G01X408702D02*
X408387D01*
G01X412639D02*
X412324D01*
G01X416576D02*
X416261D01*
G01X420513D02*
X420198D01*
G01X424450D02*
X424135D01*
G01X425069Y215009D02*
X426035D01*
G01X421128D02*
X422093D01*
G01X417195D02*
X418161D01*
G01X413254D02*
X414219D01*
G01X409321D02*
X410287D01*
G01X405380D02*
X406345D01*
G01X401447D02*
X402413D01*
G01X397506D02*
X398471D01*
G01X393573D02*
X394539D01*
G01X389632D02*
X390597D01*
G01X385699D02*
X386665D01*
G01X381758D02*
X382723D01*
G01X377825D02*
X378791D01*
G01X373884D02*
X374849D01*
G01X369951D02*
X370917D01*
G01X366010D02*
X366975D01*
G01X362077D02*
X363043D01*
G01X358136D02*
X359101D01*
G01X354203D02*
X355169D01*
G01X350262D02*
X351227D01*
G01X420788Y214921D02*
X422442D01*
G01X412914D02*
X414568D01*
G01X405040D02*
X406694D01*
G01X397166D02*
X398820D01*
G01X389292D02*
X390946D01*
G01X381418D02*
X383072D01*
G01X373544D02*
X375198D01*
G01X365670D02*
X367324D01*
G01X357796D02*
X359450D01*
G01X349922D02*
X351576D01*
G01X424135Y214822D02*
X426969D01*
G01X420198D02*
X423032D01*
G01X416261D02*
X419095D01*
G01X412324D02*
X415158D01*
G01X408387D02*
X411221D01*
G01X404450D02*
X407284D01*
G01X400513D02*
X403347D01*
G01X396576D02*
X399410D01*
G01X392639D02*
X395473D01*
G01X388702D02*
X391536D01*
G01X384765D02*
X387599D01*
G01X380828D02*
X383662D01*
G01X376891D02*
X379725D01*
G01X372954D02*
X375788D01*
G01X369017D02*
X371851D01*
G01X365080D02*
X367914D01*
G01X361143D02*
X363977D01*
G01X357206D02*
X360040D01*
G01X353269D02*
X356103D01*
G01X349332D02*
X352166D01*
G01X426379Y214665D02*
X426969D01*
G01X424135D02*
X424725D01*
G01X422442D02*
X423032D01*
G01X420198D02*
X420788D01*
G01X418505D02*
X419095D01*
G01X416261D02*
X416851D01*
G01X414568D02*
X415158D01*
G01X412324D02*
X412914D01*
G01X410631D02*
X411221D01*
G01X408387D02*
X408977D01*
G01X406694D02*
X407284D01*
G01X404450D02*
X405040D01*
G01X402757D02*
X403347D01*
G01X400513D02*
X401103D01*
G01X398820D02*
X399410D01*
G01X396576D02*
X397166D01*
G01X394883D02*
X395473D01*
G01X392639D02*
X393229D01*
G01X390946D02*
X391536D01*
G01X388702D02*
X389292D01*
G01X387009D02*
X387599D01*
G01X384765D02*
X385355D01*
G01X383072D02*
X383662D01*
G01X380828D02*
X381418D01*
G01X379135D02*
X379725D01*
G01X376891D02*
X377481D01*
G01X375198D02*
X375788D01*
G01X372954D02*
X373544D01*
G01X371261D02*
X371851D01*
G01X369017D02*
X369607D01*
G01X367324D02*
X367914D01*
G01X365080D02*
X365670D01*
G01X363387D02*
X363977D01*
G01X361143D02*
X361733D01*
G01X359450D02*
X360040D01*
G01X357206D02*
X357796D01*
G01X355513D02*
X356103D01*
G01X353269D02*
X353859D01*
G01X351576D02*
X352166D01*
G01X349332D02*
X349922D01*
G01X347639D02*
X348229D01*
G01X351481Y214640D02*
X350008D01*
G01X355423D02*
X353950D01*
G01X359355D02*
X357882D01*
G01X363297D02*
X361824D01*
G01X367229D02*
X365756D01*
G01X371171D02*
X369698D01*
G01X375103D02*
X373630D01*
G01X379045D02*
X377572D01*
G01X382977D02*
X381504D01*
G01X386919D02*
X385446D01*
G01X390851D02*
X389378D01*
G01X394793D02*
X393320D01*
G01X398725D02*
X397252D01*
G01X402667D02*
X401194D01*
G01X406599D02*
X405126D01*
G01X410541D02*
X409068D01*
G01X414473D02*
X413000D01*
G01X418415D02*
X416942D01*
G01X422347D02*
X420874D01*
G01X426289D02*
X424816D01*
G01X424802Y214621D02*
X426302D01*
G01X420861D02*
X422360D01*
G01X416928D02*
X418428D01*
G01X412987D02*
X414486D01*
G01X409054D02*
X410554D01*
G01X405113D02*
X406612D01*
G01X401180D02*
X402680D01*
G01X397239D02*
X398738D01*
G01X393306D02*
X394806D01*
G01X389365D02*
X390864D01*
G01X385432D02*
X386932D01*
G01X381491D02*
X382990D01*
G01X377558D02*
X379058D01*
G01X373617D02*
X375116D01*
G01X369684D02*
X371184D01*
G01X365743D02*
X367242D01*
G01X361810D02*
X363310D01*
G01X357869D02*
X359368D01*
G01X353936D02*
X355436D01*
G01X349995D02*
X351494D01*
G01X351750Y214231D02*
X349739D01*
G01X355692D02*
X353680D01*
G01X359624D02*
X357613D01*
G01X363566D02*
X361554D01*
G01X367498D02*
X365487D01*
G01X371440D02*
X369428D01*
G01X375372D02*
X373361D01*
G01X379314D02*
X377302D01*
G01X383246D02*
X381235D01*
G01X387188D02*
X385176D01*
G01X391120D02*
X389109D01*
G01X395062D02*
X393050D01*
G01X398994D02*
X396983D01*
G01X402936D02*
X400924D01*
G01X406868D02*
X404857D01*
G01X410810D02*
X408798D01*
G01X414742D02*
X412731D01*
G01X418684D02*
X416673D01*
G01X422616D02*
X420605D01*
G01X426558D02*
X424547D01*
G01X348229Y213996D02*
X347639D01*
G01X349922D02*
X349332D01*
G01X352166D02*
X351576D01*
G01X353859D02*
X353269D01*
G01X356103D02*
X355513D01*
G01X357796D02*
X357206D01*
G01X360040D02*
X359450D01*
G01X361733D02*
X361143D01*
G01X363977D02*
X363387D01*
G01X365670D02*
X365080D01*
G01X367914D02*
X367324D01*
G01X369607D02*
X369017D01*
G01X371851D02*
X371261D01*
G01X373544D02*
X372954D01*
G01X375788D02*
X375198D01*
G01X377481D02*
X376891D01*
G01X379725D02*
X379135D01*
G01X381418D02*
X380828D01*
G01X383662D02*
X383072D01*
G01X385355D02*
X384765D01*
G01X387599D02*
X387009D01*
G01X389292D02*
X388702D01*
G01X391536D02*
X390946D01*
G01X393229D02*
X392639D01*
G01X395473D02*
X394883D01*
G01X397166D02*
X396576D01*
G01X399410D02*
X398820D01*
G01X401103D02*
X400513D01*
G01X403347D02*
X402757D01*
G01X405040D02*
X404450D01*
G01X407284D02*
X406694D01*
G01X408977D02*
X408387D01*
G01X411221D02*
X410631D01*
G01X412914D02*
X412324D01*
G01X415158D02*
X414568D01*
G01X416851D02*
X416261D01*
G01X419095D02*
X418505D01*
G01X420788D02*
X420198D01*
G01X423032D02*
X422442D01*
G01X424725D02*
X424135D01*
G01X426969D02*
X426379D01*
G01X352166Y213838D02*
X349332D01*
G01X356103D02*
X353269D01*
G01X360040D02*
X357206D01*
G01X363977D02*
X361143D01*
G01X367914D02*
X365080D01*
G01X371851D02*
X369017D01*
G01X375788D02*
X372954D01*
G01X379725D02*
X376891D01*
G01X383662D02*
X380828D01*
G01X387599D02*
X384765D01*
G01X391536D02*
X388702D01*
G01X395473D02*
X392639D01*
G01X399410D02*
X396576D01*
G01X403347D02*
X400513D01*
G01X407284D02*
X404450D01*
G01X411221D02*
X408387D01*
G01X415158D02*
X412324D01*
G01X419095D02*
X416261D01*
G01X423032D02*
X420198D01*
G01X426969D02*
X424135D01*
G01X355513Y213740D02*
X353859D01*
G01X363387D02*
X361733D01*
G01X371261D02*
X369607D01*
G01X379135D02*
X377481D01*
G01X387009D02*
X385355D01*
G01X394883D02*
X393229D01*
G01X402757D02*
X401103D01*
G01X410631D02*
X408977D01*
G01X418505D02*
X416851D01*
G01X426379D02*
X424725D01*
G01Y213248D02*
X426379D01*
G01X416851D02*
X418505D01*
G01X408977D02*
X410631D01*
G01X401103D02*
X402757D01*
G01X393229D02*
X394883D01*
G01X385355D02*
X387009D01*
G01X377481D02*
X379135D01*
G01X369607D02*
X371261D01*
G01X361733D02*
X363387D01*
G01X353859D02*
X355513D01*
G01X424135Y212342D02*
X426969D01*
G01X420198D02*
X423032D01*
G01X416261D02*
X419095D01*
G01X412324D02*
X415158D01*
G01X408387D02*
X411221D01*
G01X404450D02*
X407284D01*
G01X400513D02*
X403347D01*
G01X396576D02*
X399410D01*
G01X392639D02*
X395473D01*
G01X388702D02*
X391536D01*
G01X384765D02*
X387599D01*
G01X380828D02*
X383662D01*
G01X376891D02*
X379725D01*
G01X372954D02*
X375788D01*
G01X369017D02*
X371851D01*
G01X365080D02*
X367914D01*
G01X361143D02*
X363977D01*
G01X357206D02*
X360040D01*
G01X353269D02*
X356103D01*
G01X349332D02*
X352166D01*
G01X424725Y211476D02*
X426379D01*
G01X416851D02*
X418505D01*
G01X408977D02*
X410631D01*
G01X401103D02*
X402757D01*
G01X393229D02*
X394883D01*
G01X385355D02*
X387009D01*
G01X377481D02*
X379135D01*
G01X369607D02*
X371261D01*
G01X361733D02*
X363387D01*
G01X353859D02*
X355513D01*
G01X400749Y211082D02*
X403111D01*
G01X396812D02*
X399174D01*
G01X392875D02*
X395237D01*
G01X388938D02*
X391300D01*
G01X351930D02*
X349568D01*
G01X355867D02*
X353505D01*
G01X359804D02*
X357442D01*
G01X363741D02*
X361379D01*
G01X367678D02*
X365316D01*
G01X371615D02*
X369253D01*
G01X375552D02*
X373190D01*
G01X379489D02*
X377127D01*
G01X383426D02*
X381064D01*
G01X387363D02*
X385001D01*
G01X407048D02*
X404686D01*
G01X410985D02*
X408623D01*
G01X414922D02*
X412560D01*
G01X418859D02*
X416497D01*
G01X422796D02*
X420434D01*
G01X426733D02*
X424371D01*
G01X355513Y210984D02*
X353859D01*
G01X363387D02*
X361733D01*
G01X371261D02*
X369607D01*
G01X379135D02*
X377481D01*
G01X387009D02*
X385355D01*
G01X394883D02*
X393229D01*
G01X402757D02*
X401103D01*
G01X410631D02*
X408977D01*
G01X418505D02*
X416851D01*
G01X426379D02*
X424725D01*
G01X355355Y210885D02*
X354017D01*
G01X363229D02*
X361891D01*
G01X371103D02*
X369765D01*
G01X378977D02*
X377639D01*
G01X386851D02*
X385513D01*
G01X394725D02*
X393387D01*
G01X402599D02*
X401261D01*
G01X410473D02*
X409135D01*
G01X418347D02*
X417009D01*
G01X426221D02*
X424883D01*
G01X425024Y230441D02*
X425033Y230393D01*
G01X426080Y215937D02*
X426071Y215984D01*
G01X421092Y230441D02*
X421101Y230393D01*
G01X422139Y215937D02*
X422129Y215984D01*
G01X417150Y230441D02*
X417159Y230393D01*
G01X418206Y215937D02*
X418197Y215984D01*
G01X413217Y230441D02*
X413227Y230393D01*
G01X414265Y215937D02*
X414255Y215984D01*
G01X409276Y230441D02*
X409285Y230393D01*
G01X410332Y215937D02*
X410323Y215984D01*
G01X405343Y230441D02*
X405353Y230393D01*
G01X406391Y215937D02*
X406381Y215984D01*
G01X401411Y230393D02*
X401402Y230441D01*
G01X377572Y231737D02*
X377825Y231368D01*
G01X377780Y230441D02*
X377558Y230762D01*
G01X386710Y215937D02*
X386932Y215615D01*
G01X386919Y214640D02*
X386665Y215009D01*
G01X373639Y231737D02*
X373893Y231368D01*
G01X373847Y230441D02*
X373626Y230762D01*
G01X382769Y215937D02*
X382990Y215615D01*
G01X382977Y214640D02*
X382723Y215009D01*
G01X369698Y231737D02*
X369951Y231368D01*
G01X369906Y230441D02*
X369684Y230762D01*
G01X378836Y215937D02*
X379058Y215615D01*
G01X379045Y214640D02*
X378791Y215009D01*
G01X365765Y231737D02*
X366019Y231368D01*
G01X365973Y230441D02*
X365752Y230762D01*
G01X374895Y215937D02*
X375116Y215615D01*
G01X375103Y214640D02*
X374849Y215009D01*
G01X361824Y231737D02*
X362077Y231368D01*
G01X362032Y230441D02*
X361810Y230762D01*
G01X370962Y215937D02*
X371184Y215615D01*
G01X371171Y214640D02*
X370917Y215009D01*
G01X357891Y231737D02*
X358145Y231368D01*
G01X358099Y230441D02*
X357878Y230762D01*
G01X367021Y215937D02*
X367242Y215615D01*
G01X367229Y214640D02*
X366975Y215009D01*
G01X353950Y231737D02*
X354203Y231368D01*
G01X354158Y230441D02*
X353936Y230762D01*
G01X363088Y215937D02*
X363310Y215615D01*
G01X363297Y214640D02*
X363043Y215009D01*
G01X350017Y231737D02*
X350271Y231368D01*
G01X350225Y230441D02*
X350004Y230762D01*
G01X424371Y209901D02*
X426733D01*
G01X420434D02*
X422796D01*
G01X416497D02*
X418859D01*
G01X412560D02*
X414922D01*
G01X408623D02*
X410985D01*
G01X404686D02*
X407048D01*
G01X400749D02*
X403111D01*
G01X396812D02*
X399174D01*
G01X392875D02*
X395237D01*
G01X388938D02*
X391300D01*
G01X385001D02*
X387363D01*
G01X381064D02*
X383426D01*
G01X377127D02*
X379489D01*
G01X373190D02*
X375552D01*
G01X369253D02*
X371615D01*
G01X365316D02*
X367678D01*
G01X361379D02*
X363741D01*
G01X357442D02*
X359804D01*
G01X353505D02*
X355867D01*
G01X349568D02*
X351930D01*
G01X417678Y203011D02*
X437363D01*
G01X394056D02*
X413741D01*
G01X370434D02*
X390119D01*
G01X426563Y215117D02*
X426426Y221024D01*
G01X426422Y220138D02*
X426558Y214231D01*
G01X426400Y226012D02*
X426350Y226999D01*
G01X426347Y226037D02*
X426398Y225050D01*
G01X424757Y220340D02*
X424706Y221327D01*
G01X424704Y220365D02*
X424755Y219379D01*
G01X422468Y226012D02*
X422417Y226999D01*
G01X422415Y226037D02*
X422466Y225050D01*
G01X402449Y215984D02*
X402458Y215937D01*
G01X397469Y230441D02*
X397479Y230393D01*
G01X398517Y215937D02*
X398507Y215984D01*
G01X393537Y230393D02*
X393528Y230441D01*
G01X394575Y215984D02*
X394584Y215937D01*
G01X389595Y230441D02*
X389605Y230393D01*
G01X390643Y215937D02*
X390633Y215984D01*
G01X385654Y230441D02*
X385663Y230393D01*
G01X386710Y215937D02*
X386701Y215984D01*
G01X381721Y230441D02*
X381731Y230393D01*
G01X382769Y215937D02*
X382759Y215984D01*
G01X377780Y230441D02*
X377789Y230393D01*
G01X359147Y215937D02*
X359368Y215615D01*
G01X359355Y214640D02*
X359101Y215009D01*
G01X355214Y215937D02*
X355436Y215615D01*
G01X355423Y214640D02*
X355169Y215009D01*
G01X351273Y215937D02*
X351494Y215615D01*
G01X351481Y214640D02*
X351227Y215009D01*
G01X347340Y215937D02*
X347562Y215615D01*
G01X347548Y214640D02*
X347295Y215009D01*
G01X426350Y219379D02*
X426400Y220365D01*
G01X426398Y221327D02*
X426347Y220340D01*
G01X424706Y225050D02*
X424757Y226037D01*
G01X424755Y226999D02*
X424704Y226012D01*
G01X422408Y219379D02*
X422459Y220365D01*
G01X422456Y221327D02*
X422406Y220340D01*
G01X420774Y225050D02*
X420825Y226037D01*
G01X420822Y226999D02*
X420772Y226012D01*
G01X418476Y219379D02*
X418526Y220365D01*
G01X418524Y221327D02*
X418473Y220340D01*
G01X416832Y225050D02*
X416883Y226037D01*
G01X416881Y226999D02*
X416830Y226012D01*
G01X414534Y219379D02*
X414585Y220365D01*
G01X414582Y221327D02*
X414532Y220340D01*
G01X412900Y225050D02*
X412951Y226037D01*
G01X412948Y226999D02*
X412898Y226012D01*
G01X426426Y225353D02*
X426563Y231260D01*
G01X426558Y232147D02*
X426422Y226239D01*
G01X424547Y214231D02*
X424683Y220138D01*
G01X424678Y221024D02*
X424542Y215117D01*
G01X422494Y225353D02*
X422630Y231260D01*
G01X422625Y232147D02*
X422489Y226239D01*
G01X420605Y214231D02*
X420741Y220138D01*
G01X420736Y221024D02*
X420600Y215117D01*
G01X418552Y225353D02*
X418689Y231260D01*
G01X418684Y232147D02*
X418548Y226239D01*
G01X416673Y214231D02*
X416809Y220138D01*
G01X416804Y221024D02*
X416668Y215117D01*
G01X414620Y225353D02*
X414756Y231260D01*
G01X414751Y232147D02*
X414615Y226239D01*
G01X412731Y214231D02*
X412867Y220138D01*
G01X412862Y221024D02*
X412726Y215117D01*
G01X410678Y225353D02*
X410815Y231260D01*
G01X410810Y232147D02*
X410674Y226239D01*
G01X408798Y214231D02*
X408935Y220138D01*
G01X408930Y221024D02*
X408794Y215117D01*
G01X426048Y215984D02*
X426035Y215009D01*
G01X425056Y230393D02*
X425069Y231368D01*
G01X422106Y215984D02*
X422093Y215009D01*
G01X421124Y230393D02*
X421137Y231368D01*
G01X418174Y215984D02*
X418161Y215009D01*
G01X417182Y230393D02*
X417195Y231368D01*
G01X414232Y215984D02*
X414219Y215009D01*
G01X413250Y230393D02*
X413263Y231368D01*
G01X410300Y215984D02*
X410287Y215009D01*
G01X409308Y230393D02*
X409321Y231368D01*
G01X406358Y215984D02*
X406345Y215009D01*
G01X426969Y229862D02*
Y234035D01*
G01Y212342D02*
Y216515D01*
G01X426935Y214822D02*
Y213838D01*
G01X426930Y214822D02*
Y213838D01*
G01Y232539D02*
Y231555D01*
G01X426733Y215984D02*
Y209901D01*
G01Y236476D02*
Y230393D01*
G01X426655Y213838D02*
Y232539D01*
G01X426576Y214824D02*
Y213840D01*
G01Y232538D02*
Y231553D01*
G01X426379Y231555D02*
Y236396D01*
G01Y209981D02*
Y214822D01*
G01X426300Y230760D02*
Y231750D01*
G01Y214627D02*
Y215617D01*
G01X426221Y210965D02*
Y209901D01*
G01Y236476D02*
Y235412D01*
G01X425946Y210885D02*
Y209901D01*
G01Y236476D02*
Y235492D01*
G01X425158D02*
Y236476D01*
G01Y210885D02*
Y209901D01*
G01X424883Y210965D02*
Y209901D01*
G01Y236476D02*
Y235412D01*
G01X424804Y215617D02*
Y214627D01*
G01Y231750D02*
Y230760D01*
G01X424725Y231555D02*
Y236396D01*
G01Y209981D02*
Y214822D01*
G01X424529Y213840D02*
Y214824D01*
G01Y231553D02*
Y232538D01*
G01X424450Y232539D02*
Y213838D01*
G01X424371Y215984D02*
Y209901D01*
G01Y236476D02*
Y230393D01*
G01X424174Y214822D02*
Y213838D01*
G01Y232539D02*
Y231555D01*
G01X424170Y232539D02*
Y231555D01*
G01X424135Y216515D02*
Y212342D01*
G01Y234035D02*
Y229862D01*
G01X423032D02*
Y234035D01*
G01Y212342D02*
Y216515D01*
G01X422998Y232539D02*
Y231555D01*
G01X422993Y214822D02*
Y213838D01*
G01X422988Y214822D02*
Y213838D01*
G01X422796Y215984D02*
Y209901D01*
G01Y236476D02*
Y230393D01*
G01X422717Y213838D02*
Y232539D01*
G01X422643Y232538D02*
Y231553D01*
G01X422634Y214824D02*
Y213840D01*
G01X422442Y227698D02*
Y232539D01*
G01Y213838D02*
Y218680D01*
G01X422368Y230760D02*
Y231750D01*
G01X422359Y214627D02*
Y215617D01*
G01X422284Y218760D02*
Y217696D01*
G01Y228681D02*
Y227618D01*
G01X422009Y218760D02*
Y217775D01*
G01Y228602D02*
Y227618D01*
G01X421221Y218760D02*
Y217775D01*
G01Y228602D02*
Y227618D01*
G01X420946Y218760D02*
Y217696D01*
G01Y228681D02*
Y227618D01*
G01X420872Y231750D02*
Y230760D01*
G01X420862Y215617D02*
Y214627D01*
G01X420828Y208523D02*
Y203011D01*
G01X420788Y227698D02*
Y232539D01*
G01Y213838D02*
Y218680D01*
G01X420596Y231553D02*
Y232538D01*
G01X420587Y213840D02*
Y214824D01*
G01X420513Y232539D02*
Y213838D01*
G01X420434Y215984D02*
Y209901D01*
G01Y236476D02*
Y230393D01*
G01X420242Y232539D02*
Y231555D01*
G01X420237Y232539D02*
Y231555D01*
G01X420233Y214822D02*
Y213838D01*
G01X420198Y216515D02*
Y212342D01*
G01Y234035D02*
Y229862D01*
G01X419095D02*
Y234035D01*
G01Y212342D02*
Y216515D01*
G01X419061Y214822D02*
Y213838D01*
G01X419056Y214822D02*
Y213838D01*
G01Y232539D02*
Y231555D01*
G01X418859Y215984D02*
Y209901D01*
G01Y236476D02*
Y230393D01*
G01X418780Y213838D02*
Y232539D01*
G01X418702Y214824D02*
Y213840D01*
G01Y232538D02*
Y231553D01*
G01X418505Y231555D02*
Y236396D01*
G01Y209981D02*
Y214822D01*
G01X418426Y230760D02*
Y231750D01*
G01Y214627D02*
Y215617D01*
G01X418347Y210965D02*
Y209901D01*
G01Y236476D02*
Y235412D01*
G01X418072Y210885D02*
Y209901D01*
G01Y236476D02*
Y235492D01*
G01X417678Y208523D02*
Y203011D01*
G01X417284Y235492D02*
Y236476D01*
G01Y210885D02*
Y209901D01*
G01X417009Y210965D02*
Y209901D01*
G01Y236476D02*
Y235412D01*
G01X416930Y215617D02*
Y214627D01*
G01Y231750D02*
Y230760D01*
G01X416851Y231555D02*
Y236396D01*
G01Y209981D02*
Y214822D01*
G01X416655Y231553D02*
Y232538D01*
G01Y213840D02*
Y214824D01*
G01X416576Y232539D02*
Y213838D01*
G01X416497Y215984D02*
Y209901D01*
G01Y236476D02*
Y230393D01*
G01X416300Y214822D02*
Y213838D01*
G01Y232539D02*
Y231555D01*
G01X416295Y232539D02*
Y231555D01*
G01X416261Y216515D02*
Y212342D01*
G01Y234035D02*
Y229862D01*
G01X415158D02*
Y234035D01*
G01Y212342D02*
Y216515D01*
G01X415124Y232539D02*
Y231555D01*
G01X415119Y214822D02*
Y213838D01*
G01X415114Y214822D02*
Y213838D01*
G01X414922Y215984D02*
Y209901D01*
G01Y236476D02*
Y230393D01*
G01X414843Y213838D02*
Y232539D01*
G01X414769Y232538D02*
Y231553D01*
G01X414760Y214824D02*
Y213840D01*
G01X414568Y227698D02*
Y232539D01*
G01Y213838D02*
Y218680D01*
G01X414494Y230760D02*
Y231750D01*
G01X414484Y214627D02*
Y215617D01*
G01X414410Y218760D02*
Y217696D01*
G01Y228681D02*
Y227618D01*
G01X414135D02*
Y228602D01*
G01Y218760D02*
Y217775D01*
G01X413741Y208523D02*
Y203011D01*
G01X413347Y227618D02*
Y228602D01*
G01Y217775D02*
Y218760D01*
G01X413072D02*
Y217696D01*
G01Y228681D02*
Y227618D01*
G01X412998Y231750D02*
Y230760D01*
G01X412988Y215617D02*
Y214627D01*
G01X412914Y227698D02*
Y232539D01*
G01Y213838D02*
Y218680D01*
G01X412722Y231553D02*
Y232538D01*
G01X412713Y213840D02*
Y214824D01*
G01X412639Y232539D02*
Y213838D01*
G01X412560Y215984D02*
Y209901D01*
G01Y236476D02*
Y230393D01*
G01X412368Y232539D02*
Y231555D01*
G01X412363Y232539D02*
Y231555D01*
G01X412359Y214822D02*
Y213838D01*
G01X412324Y216515D02*
Y212342D01*
G01Y234035D02*
Y229862D01*
G01X411221D02*
Y234035D01*
G01Y212342D02*
Y216515D01*
G01X411187Y214822D02*
Y213838D01*
G01X411182Y214822D02*
Y213838D01*
G01Y232539D02*
Y231555D01*
G01X410985Y215984D02*
Y209901D01*
G01Y236476D02*
Y230393D01*
G01X410906Y213838D02*
Y232539D01*
G01X410828Y214824D02*
Y213840D01*
G01Y232538D02*
Y231553D01*
G01X410631Y231555D02*
Y236396D01*
G01Y209981D02*
Y214822D01*
G01X410592Y208523D02*
Y203011D01*
G01X410552Y230760D02*
Y231750D01*
G01Y214627D02*
Y215617D01*
G01X410473Y210965D02*
Y209901D01*
G01Y236476D02*
Y235412D01*
G01X410198Y210885D02*
Y209901D01*
G01Y236476D02*
Y235492D01*
G01X409410D02*
Y236476D01*
G01Y210885D02*
Y209901D01*
G01X409135Y210965D02*
Y209901D01*
G01Y236476D02*
Y235412D01*
G01X409056Y215617D02*
Y214627D01*
G01Y231750D02*
Y230760D01*
G01X408977Y231555D02*
Y236396D01*
G01Y209981D02*
Y214822D01*
G01X408780Y231553D02*
Y232538D01*
G01Y213840D02*
Y214824D01*
G01X408702Y232539D02*
Y213838D01*
G01X408623Y215984D02*
Y209901D01*
G01Y236476D02*
Y230393D01*
G01X408426Y214822D02*
Y213838D01*
G01Y232539D02*
Y231555D01*
G01X408421Y232539D02*
Y231555D01*
G01X408387Y216515D02*
Y212342D01*
G01Y234035D02*
Y229862D01*
G01X407284D02*
Y234035D01*
G01Y212342D02*
Y216515D01*
G01X407250Y232539D02*
Y231555D01*
G01X407245Y214822D02*
Y213838D01*
G01X407240Y214822D02*
Y213838D01*
G01X407048Y215984D02*
Y209901D01*
G01Y236476D02*
Y230393D01*
G01X406969Y213838D02*
Y232539D01*
G01X406895Y232538D02*
Y231553D01*
G01X406886Y214824D02*
Y213840D01*
G01X406694Y227698D02*
Y232539D01*
G01Y213838D02*
Y218680D01*
G01X406620Y230760D02*
Y231750D01*
G01X406610Y214627D02*
Y215617D01*
G01X406536Y218760D02*
Y217696D01*
G01Y228681D02*
Y227618D01*
G01X406261D02*
Y228602D01*
G01Y218760D02*
Y217775D01*
G01X405473Y227618D02*
Y228602D01*
G01Y217775D02*
Y218760D01*
G01X405198D02*
Y217696D01*
G01Y228681D02*
Y227618D01*
G01X405124Y231750D02*
Y230760D01*
G01X405114Y215617D02*
Y214627D01*
G01X405040Y227698D02*
Y232539D01*
G01Y213838D02*
Y218680D01*
G01X404848Y231553D02*
Y232538D01*
G01X404839Y213840D02*
Y214824D01*
G01X404765Y232539D02*
Y213838D01*
G01X404686Y215984D02*
Y209901D01*
G01Y236476D02*
Y230393D01*
G01X404494Y232539D02*
Y231555D01*
G01X404489Y232539D02*
Y231555D01*
G01X404484Y214822D02*
Y213838D01*
G01X404450Y216515D02*
Y212342D01*
G01Y234035D02*
Y229862D01*
G01X426035Y231368D02*
X426048Y230393D01*
G01X425069Y215009D02*
X425056Y215984D01*
G01X422102Y231368D02*
X422116Y230393D01*
G01X421128Y215009D02*
X421115Y215984D01*
G01X418161Y231368D02*
X418174Y230393D01*
G01X417195Y215009D02*
X417182Y215984D01*
G01X414228Y231368D02*
X414242Y230393D01*
G01X413254Y215009D02*
X413241Y215984D01*
G01X410287Y231368D02*
X410300Y230393D01*
G01X409321Y215009D02*
X409308Y215984D01*
G01X406354Y231368D02*
X406368Y230393D01*
G01X405380Y215009D02*
X405367Y215984D01*
G01X402413Y231368D02*
X402426Y230393D01*
G01X424683Y226239D02*
X424547Y232147D01*
G01X424542Y231260D02*
X424678Y225353D01*
G01X422621Y215117D02*
X422485Y221024D01*
G01X422480Y220138D02*
X422616Y214231D01*
G01X420750Y226239D02*
X420614Y232147D01*
G01X420609Y231260D02*
X420746Y225353D01*
G01X418689Y215117D02*
X418552Y221024D01*
G01X418548Y220138D02*
X418684Y214231D01*
G01X416809Y226239D02*
X416673Y232147D01*
G01X416668Y231260D02*
X416804Y225353D01*
G01X414747Y215117D02*
X414611Y221024D01*
G01X414606Y220138D02*
X414742Y214231D01*
G01X412876Y226239D02*
X412740Y232147D01*
G01X412735Y231260D02*
X412872Y225353D01*
G01X410815Y215117D02*
X410678Y221024D01*
G01X410674Y220138D02*
X410810Y214231D01*
G01X408935Y226239D02*
X408798Y232147D01*
G01X408794Y231260D02*
X408930Y225353D01*
G01X406873Y215117D02*
X406737Y221024D01*
G01X406732Y220138D02*
X406868Y214231D01*
G01X405002Y226239D02*
X404866Y232147D01*
G01X404861Y231260D02*
X404998Y225353D01*
G01X402941Y215117D02*
X402804Y221024D01*
G01X402799Y220138D02*
X402936Y214231D01*
G01X401061Y226239D02*
X400924Y232147D01*
G01X400920Y231260D02*
X401056Y225353D01*
G01X420815Y220340D02*
X420765Y221327D01*
G01X420762Y220365D02*
X420813Y219379D01*
G01X418526Y226012D02*
X418476Y226999D01*
G01X418473Y226037D02*
X418524Y225050D01*
G01X416883Y220340D02*
X416832Y221327D01*
G01X416830Y220365D02*
X416881Y219379D01*
G01X414594Y226012D02*
X414543Y226999D01*
G01X414541Y226037D02*
X414592Y225050D01*
G01X412941Y220340D02*
X412891Y221327D01*
G01X412888Y220365D02*
X412939Y219379D01*
G01X410652Y226012D02*
X410602Y226999D01*
G01X410599Y226037D02*
X410650Y225050D01*
G01X409009Y220340D02*
X408958Y221327D01*
G01X408956Y220365D02*
X409007Y219379D01*
G01X406720Y226012D02*
X406669Y226999D01*
G01X406667Y226037D02*
X406718Y225050D01*
G01X405067Y220340D02*
X405017Y221327D01*
G01X405014Y220365D02*
X405065Y219379D01*
G01X402778Y226012D02*
X402728Y226999D01*
G01X402725Y226037D02*
X402776Y225050D01*
G01X401135Y220340D02*
X401084Y221327D01*
G01X401082Y220365D02*
X401133Y219379D01*
G01X398846Y226012D02*
X398795Y226999D01*
G01X398793Y226037D02*
X398843Y225050D01*
G01X378836Y215937D02*
X378827Y215984D01*
G01X373847Y230441D02*
X373857Y230393D01*
G01X374895Y215937D02*
X374885Y215984D01*
G01X369906Y230441D02*
X369915Y230393D01*
G01X370962Y215937D02*
X370953Y215984D01*
G01X365973Y230441D02*
X365983Y230393D01*
G01X367021Y215937D02*
X367011Y215984D01*
G01X362032Y230441D02*
X362041Y230393D01*
G01X363088Y215937D02*
X363079Y215984D01*
G01X358099Y230441D02*
X358109Y230393D01*
G01X359147Y215937D02*
X359137Y215984D01*
G01X354158Y230441D02*
X354167Y230393D01*
G01X355214Y215937D02*
X355205Y215984D01*
G01X425033D02*
X425024Y215937D01*
G01X426071Y230393D02*
X426080Y230441D01*
G01X421092Y215984D02*
X421082Y215937D01*
G01X422139Y230393D02*
X422148Y230441D01*
G01X417159Y215984D02*
X417150Y215937D01*
G01X418197Y230393D02*
X418206Y230441D01*
G01X413218Y215984D02*
X413208Y215937D01*
G01X414264Y230393D02*
X414274Y230441D01*
G01X409285Y215984D02*
X409276Y215937D01*
G01X410323Y230393D02*
X410332Y230441D01*
G01X410602Y219379D02*
X410652Y220365D01*
G01X410650Y221327D02*
X410599Y220340D01*
G01X408958Y225050D02*
X409009Y226037D01*
G01X409007Y226999D02*
X408956Y226012D01*
G01X406660Y219379D02*
X406711Y220365D01*
G01X406708Y221327D02*
X406658Y220340D01*
G01X405026Y225050D02*
X405077Y226037D01*
G01X405074Y226999D02*
X405024Y226012D01*
G01X402728Y219379D02*
X402778Y220365D01*
G01X402776Y221327D02*
X402725Y220340D01*
G01X401084Y225050D02*
X401135Y226037D01*
G01X401133Y226999D02*
X401082Y226012D01*
G01X398786Y219379D02*
X398836Y220365D01*
G01X398834Y221327D02*
X398784Y220340D01*
G01X397152Y225050D02*
X397203Y226037D01*
G01X397200Y226999D02*
X397150Y226012D01*
G01X394854Y219379D02*
X394904Y220365D01*
G01X394902Y221327D02*
X394851Y220340D01*
G01X393210Y225050D02*
X393261Y226037D01*
G01X393258Y226999D02*
X393208Y226012D01*
G01X390912Y219379D02*
X390962Y220365D01*
G01X390960Y221327D02*
X390910Y220340D01*
G01X389278Y225050D02*
X389328Y226037D01*
G01X389326Y226999D02*
X389276Y226012D01*
G01X386980Y219379D02*
X387030Y220365D01*
G01X387028Y221327D02*
X386977Y220340D01*
G01X406746Y225353D02*
X406882Y231260D01*
G01X406877Y232147D02*
X406741Y226239D01*
G01X404857Y214231D02*
X404993Y220138D01*
G01X404988Y221024D02*
X404852Y215117D01*
G01X402804Y225353D02*
X402941Y231260D01*
G01X402936Y232147D02*
X402799Y226239D01*
G01X400924Y214231D02*
X401061Y220138D01*
G01X401056Y221024D02*
X400920Y215117D01*
G01X398872Y225353D02*
X399008Y231260D01*
G01X399003Y232147D02*
X398867Y226239D01*
G01X396983Y214231D02*
X397119Y220138D01*
G01X397114Y221024D02*
X396978Y215117D01*
G01X394930Y225353D02*
X395066Y231260D01*
G01X395062Y232147D02*
X394925Y226239D01*
G01X393050Y214231D02*
X393187Y220138D01*
G01X393182Y221024D02*
X393046Y215117D01*
G01X390998Y225353D02*
X391134Y231260D01*
G01X391129Y232147D02*
X390993Y226239D01*
G01X389109Y214231D02*
X389245Y220138D01*
G01X389240Y221024D02*
X389104Y215117D01*
G01X387056Y225353D02*
X387192Y231260D01*
G01X387188Y232147D02*
X387051Y226239D01*
G01X385176Y214231D02*
X385313Y220138D01*
G01X385308Y221024D02*
X385172Y215117D01*
G01X383124Y225353D02*
X383260Y231260D01*
G01X383255Y232147D02*
X383119Y226239D01*
G01X405376Y230393D02*
X405389Y231368D01*
G01X402426Y215984D02*
X402413Y215009D01*
G01X401434Y230393D02*
X401447Y231368D01*
G01X398484Y215984D02*
X398471Y215009D01*
G01X397502Y230393D02*
X397515Y231368D01*
G01X394552Y215984D02*
X394539Y215009D01*
G01X393560Y230393D02*
X393573Y231368D01*
G01X390610Y215984D02*
X390597Y215009D01*
G01X389628Y230393D02*
X389641Y231368D01*
G01X386678Y215984D02*
X386665Y215009D01*
G01X385686Y230393D02*
X385699Y231368D01*
G01X382736Y215984D02*
X382723Y215009D01*
G01X381754Y230393D02*
X381767Y231368D01*
G01X403347Y229862D02*
Y234035D01*
G01Y212342D02*
Y216515D01*
G01X403313Y214822D02*
Y213838D01*
G01X403308Y214822D02*
Y213838D01*
G01Y232539D02*
Y231555D01*
G01X403111Y215984D02*
Y209901D01*
G01Y236476D02*
Y230393D01*
G01X403032Y213838D02*
Y232539D01*
G01X402954Y214824D02*
Y213840D01*
G01Y232538D02*
Y231553D01*
G01X402757Y231555D02*
Y236396D01*
G01Y209981D02*
Y214822D01*
G01X402678Y230760D02*
Y231750D01*
G01Y214627D02*
Y215617D01*
G01X402599Y210965D02*
Y209901D01*
G01Y236476D02*
Y235412D01*
G01X402324Y209901D02*
Y210885D01*
G01Y236476D02*
Y235492D01*
G01X401536Y210885D02*
Y209901D01*
G01Y236476D02*
Y235492D01*
G01X401261Y210965D02*
Y209901D01*
G01Y236476D02*
Y235412D01*
G01X401182Y215617D02*
Y214627D01*
G01Y231750D02*
Y230760D01*
G01X401103Y231555D02*
Y236396D01*
G01Y209981D02*
Y214822D01*
G01X400906Y213840D02*
Y214824D01*
G01Y231553D02*
Y232538D01*
G01X400828Y232539D02*
Y213838D01*
G01X400749Y215984D02*
Y209901D01*
G01Y236476D02*
Y230393D01*
G01X400552Y214822D02*
Y213838D01*
G01Y232539D02*
Y231555D01*
G01X400547Y232539D02*
Y231555D01*
G01X400513Y216515D02*
Y212342D01*
G01Y234035D02*
Y229862D01*
G01X399410D02*
Y234035D01*
G01Y212342D02*
Y216515D01*
G01X399376Y232539D02*
Y231555D01*
G01X399371Y214822D02*
Y213838D01*
G01X399366Y214822D02*
Y213838D01*
G01X399174Y215984D02*
Y209901D01*
G01Y236476D02*
Y230393D01*
G01X399095Y213838D02*
Y232539D01*
G01X399021Y232538D02*
Y231553D01*
G01X399012Y214824D02*
Y213840D01*
G01X398820Y227698D02*
Y232539D01*
G01Y213838D02*
Y218680D01*
G01X398746Y230760D02*
Y231750D01*
G01X398736Y214627D02*
Y215617D01*
G01X398662Y218760D02*
Y217696D01*
G01Y228681D02*
Y227618D01*
G01X398387D02*
Y228602D01*
G01Y218760D02*
Y217775D01*
G01X397599Y227618D02*
Y228602D01*
G01Y218760D02*
Y217775D01*
G01X397324Y218760D02*
Y217696D01*
G01Y228681D02*
Y227618D01*
G01X397250Y231750D02*
Y230760D01*
G01X397240Y215617D02*
Y214627D01*
G01X397206Y208523D02*
Y203011D01*
G01X397166Y227698D02*
Y232539D01*
G01Y213838D02*
Y218680D01*
G01X396974Y231553D02*
Y232538D01*
G01X396965Y213840D02*
Y214824D01*
G01X396891Y232539D02*
Y213838D01*
G01X396812Y215984D02*
Y209901D01*
G01Y236476D02*
Y230393D01*
G01X396620Y232539D02*
Y231555D01*
G01X396615Y232539D02*
Y231555D01*
G01X396610Y214822D02*
Y213838D01*
G01X396576Y216515D02*
Y212342D01*
G01Y234035D02*
Y229862D01*
G01X395473D02*
Y234035D01*
G01Y212342D02*
Y216515D01*
G01X395439Y214822D02*
Y213838D01*
G01X395434Y214822D02*
Y213838D01*
G01Y232539D02*
Y231555D01*
G01X395237Y215984D02*
Y209901D01*
G01Y236476D02*
Y230393D01*
G01X395158Y213838D02*
Y232539D01*
G01X395080Y214824D02*
Y213840D01*
G01Y232538D02*
Y231553D01*
G01X394883Y231555D02*
Y236396D01*
G01Y209981D02*
Y214822D01*
G01X394804Y230760D02*
Y231750D01*
G01Y214627D02*
Y215617D01*
G01X394725Y210965D02*
Y209901D01*
G01Y236476D02*
Y235412D01*
G01X394450Y209901D02*
Y210885D01*
G01Y236476D02*
Y235492D01*
G01X394056Y208523D02*
Y203011D01*
G01X393662Y210885D02*
Y209901D01*
G01Y236476D02*
Y235492D01*
G01X393387Y210965D02*
Y209901D01*
G01Y236476D02*
Y235412D01*
G01X393308Y215617D02*
Y214627D01*
G01Y231750D02*
Y230760D01*
G01X393229Y231555D02*
Y236396D01*
G01Y209981D02*
Y214822D01*
G01X393032Y213840D02*
Y214824D01*
G01Y231553D02*
Y232538D01*
G01X392954Y232539D02*
Y213838D01*
G01X392875Y215984D02*
Y209901D01*
G01Y236476D02*
Y230393D01*
G01X392678Y214822D02*
Y213838D01*
G01Y232539D02*
Y231555D01*
G01X392673Y232539D02*
Y231555D01*
G01X392639Y216515D02*
Y212342D01*
G01Y234035D02*
Y229862D01*
G01X391536D02*
Y234035D01*
G01Y212342D02*
Y216515D01*
G01X391502Y232539D02*
Y231555D01*
G01X391497Y214822D02*
Y213838D01*
G01X391492Y214822D02*
Y213838D01*
G01X391300Y215984D02*
Y209901D01*
G01Y236476D02*
Y230393D01*
G01X391221Y213838D02*
Y232539D01*
G01X391147Y232538D02*
Y231553D01*
G01X391138Y214824D02*
Y213840D01*
G01X390946Y227698D02*
Y232539D01*
G01Y213838D02*
Y218680D01*
G01X390872Y230760D02*
Y231750D01*
G01X390862Y214627D02*
Y215617D01*
G01X390788Y218760D02*
Y217696D01*
G01Y228681D02*
Y227618D01*
G01X390513D02*
Y228602D01*
G01Y218760D02*
Y217775D01*
G01X390119Y208523D02*
Y203011D01*
G01X389725Y227618D02*
Y228602D01*
G01Y218760D02*
Y217775D01*
G01X389450Y218760D02*
Y217696D01*
G01Y228681D02*
Y227618D01*
G01X389376Y231750D02*
Y230760D01*
G01X389366Y215617D02*
Y214627D01*
G01X389292Y227698D02*
Y232539D01*
G01Y213838D02*
Y218680D01*
G01X389100Y231553D02*
Y232538D01*
G01X389091Y213840D02*
Y214824D01*
G01X389017Y232539D02*
Y213838D01*
G01X388938Y215984D02*
Y209901D01*
G01Y236476D02*
Y230393D01*
G01X388746Y232539D02*
Y231555D01*
G01X388741Y232539D02*
Y231555D01*
G01X388736Y214822D02*
Y213838D01*
G01X388702Y216515D02*
Y212342D01*
G01Y234035D02*
Y229862D01*
G01X387599D02*
Y234035D01*
G01Y212342D02*
Y216515D01*
G01X387565Y214822D02*
Y213838D01*
G01X387560Y214822D02*
Y213838D01*
G01Y232539D02*
Y231555D01*
G01X387363Y215984D02*
Y209901D01*
G01Y236476D02*
Y230393D01*
G01X387284Y213838D02*
Y232539D01*
G01X387206Y214824D02*
Y213840D01*
G01Y232538D02*
Y231553D01*
G01X387009Y231555D02*
Y236396D01*
G01Y209981D02*
Y214822D01*
G01X386969Y208523D02*
Y203011D01*
G01X386930Y230760D02*
Y231750D01*
G01Y214627D02*
Y215617D01*
G01X386851Y210965D02*
Y209901D01*
G01Y236476D02*
Y235412D01*
G01X386576Y210885D02*
Y209901D01*
G01Y236476D02*
Y235492D01*
G01X385788D02*
Y236476D01*
G01Y210885D02*
Y209901D01*
G01X385513Y210965D02*
Y209901D01*
G01Y236476D02*
Y235412D01*
G01X385434Y215617D02*
Y214627D01*
G01Y231750D02*
Y230760D01*
G01X385355Y231555D02*
Y236396D01*
G01Y209981D02*
Y214822D01*
G01X385158Y231553D02*
Y232538D01*
G01Y213840D02*
Y214824D01*
G01X385080Y232539D02*
Y213838D01*
G01X385001Y215984D02*
Y209901D01*
G01Y236476D02*
Y230393D01*
G01X384804Y214822D02*
Y213838D01*
G01Y232539D02*
Y231555D01*
G01X384799Y232539D02*
Y231555D01*
G01X384765Y216515D02*
Y212342D01*
G01Y234035D02*
Y229862D01*
G01X383662D02*
Y234035D01*
G01Y212342D02*
Y216515D01*
G01X383628Y232539D02*
Y231555D01*
G01X383623Y214822D02*
Y213838D01*
G01X383618Y214822D02*
Y213838D01*
G01X383426Y215984D02*
Y209901D01*
G01Y236476D02*
Y230393D01*
G01X383347Y213838D02*
Y232539D01*
G01X383273Y232538D02*
Y231553D01*
G01X383264Y214824D02*
Y213840D01*
G01X383072Y227698D02*
Y232539D01*
G01Y213838D02*
Y218680D01*
G01X382998Y230760D02*
Y231750D01*
G01X382988Y214627D02*
Y215617D01*
G01X382914Y218760D02*
Y217696D01*
G01Y228681D02*
Y227618D01*
G01X382639Y218760D02*
Y217775D01*
G01Y228602D02*
Y227618D01*
G01X381851Y218760D02*
Y217775D01*
G01Y228602D02*
Y227618D01*
G01X381576Y218760D02*
Y217696D01*
G01Y228681D02*
Y227618D01*
G01X381502Y231750D02*
Y230760D01*
G01X381492Y215617D02*
Y214627D01*
G01X381418Y227698D02*
Y232539D01*
G01Y213838D02*
Y218680D01*
G01X381226Y231553D02*
Y232538D01*
G01X381217Y213840D02*
Y214824D01*
G01X381143Y232539D02*
Y213838D01*
G01X381064Y215984D02*
Y209901D01*
G01Y236476D02*
Y230393D01*
G01X380872Y232539D02*
Y231555D01*
G01X380867Y232539D02*
Y231555D01*
G01X380862Y214822D02*
Y213838D01*
G01X380828Y216515D02*
Y212342D01*
G01Y234035D02*
Y229862D01*
G01X379725D02*
Y234035D01*
G01Y212342D02*
Y216515D01*
G01X379691Y214822D02*
Y213838D01*
G01X379686Y214822D02*
Y213838D01*
G01Y232539D02*
Y231555D01*
G01X401447Y215009D02*
X401434Y215984D01*
G01X398480Y231368D02*
X398494Y230393D01*
G01X397506Y215009D02*
X397493Y215984D01*
G01X394539Y231368D02*
X394552Y230393D01*
G01X393573Y215009D02*
X393560Y215984D01*
G01X390606Y231368D02*
X390620Y230393D01*
G01X389632Y215009D02*
X389619Y215984D01*
G01X386665Y231368D02*
X386678Y230393D01*
G01X385699Y215009D02*
X385686Y215984D01*
G01X382732Y231368D02*
X382746Y230393D01*
G01X381758Y215009D02*
X381745Y215984D01*
G01X378791Y231368D02*
X378804Y230393D01*
G01X398999Y215117D02*
X398863Y221024D01*
G01X398858Y220138D02*
X398994Y214231D01*
G01X397128Y226239D02*
X396992Y232147D01*
G01X396987Y231260D02*
X397124Y225353D01*
G01X395066Y215117D02*
X394930Y221024D01*
G01X394925Y220138D02*
X395062Y214231D01*
G01X393187Y226239D02*
X393050Y232147D01*
G01X393046Y231260D02*
X393182Y225353D01*
G01X391125Y215117D02*
X390989Y221024D01*
G01X390984Y220138D02*
X391120Y214231D01*
G01X389254Y226239D02*
X389118Y232147D01*
G01X389113Y231260D02*
X389250Y225353D01*
G01X387192Y215117D02*
X387056Y221024D01*
G01X387051Y220138D02*
X387188Y214231D01*
G01X385313Y226239D02*
X385176Y232147D01*
G01X385172Y231260D02*
X385308Y225353D01*
G01X383251Y215117D02*
X383115Y221024D01*
G01X383110Y220138D02*
X383246Y214231D01*
G01X381380Y226239D02*
X381244Y232147D01*
G01X381239Y231260D02*
X381376Y225353D01*
G01X379318Y215117D02*
X379182Y221024D01*
G01X379177Y220138D02*
X379314Y214231D01*
G01X377439Y226239D02*
X377302Y232147D01*
G01X377298Y231260D02*
X377434Y225353D01*
G01X397193Y220340D02*
X397143Y221327D01*
G01X397140Y220365D02*
X397191Y219379D01*
G01X394904Y226012D02*
X394854Y226999D01*
G01X394851Y226037D02*
X394902Y225050D01*
G01X393261Y220340D02*
X393210Y221327D01*
G01X393208Y220365D02*
X393258Y219379D01*
G01X390972Y226012D02*
X390921Y226999D01*
G01X390919Y226037D02*
X390969Y225050D01*
G01X389319Y220340D02*
X389269Y221327D01*
G01X389266Y220365D02*
X389317Y219379D01*
G01X387030Y226012D02*
X386980Y226999D01*
G01X386977Y226037D02*
X387028Y225050D01*
G01X385387Y220340D02*
X385336Y221327D01*
G01X385334Y220365D02*
X385384Y219379D01*
G01X383098Y226012D02*
X383047Y226999D01*
G01X383045Y226037D02*
X383095Y225050D01*
G01X381445Y220340D02*
X381395Y221327D01*
G01X381392Y220365D02*
X381443Y219379D01*
G01X379156Y226012D02*
X379106Y226999D01*
G01X379103Y226037D02*
X379154Y225050D01*
G01X377513Y220340D02*
X377462Y221327D01*
G01X377460Y220365D02*
X377510Y219379D01*
G01X375224Y226012D02*
X375173Y226999D01*
G01X375171Y226037D02*
X375221Y225050D01*
G01X373571Y220340D02*
X373521Y221327D01*
G01X373518Y220365D02*
X373569Y219379D01*
G01X350225Y230441D02*
X350235Y230393D01*
G01X351273Y215937D02*
X351263Y215984D01*
G01X347340Y215937D02*
X347331Y215984D01*
G01X405344D02*
X405334Y215937D01*
G01X406390Y230393D02*
X406400Y230441D01*
G01X401402Y215937D02*
X401411Y215984D01*
G01X402458Y230441D02*
X402449Y230393D01*
G01X397470Y215984D02*
X397460Y215937D01*
G01X398516Y230393D02*
X398526Y230441D01*
G01X393528Y215937D02*
X393537Y215984D01*
G01X394584Y230441D02*
X394575Y230393D01*
G01X389596Y215984D02*
X389586Y215937D01*
G01X390642Y230393D02*
X390652Y230441D01*
G01X385663Y215984D02*
X385654Y215937D01*
G01X386701Y230393D02*
X386710Y230441D01*
G01X385336Y225050D02*
X385387Y226037D01*
G01X385384Y226999D02*
X385334Y226012D01*
G01X383038Y219379D02*
X383088Y220365D01*
G01X383086Y221327D02*
X383036Y220340D01*
G01X381404Y225050D02*
X381454Y226037D01*
G01X381452Y226999D02*
X381402Y226012D01*
G01X379106Y219379D02*
X379156Y220365D01*
G01X379154Y221327D02*
X379103Y220340D01*
G01X377462Y225050D02*
X377513Y226037D01*
G01X377510Y226999D02*
X377460Y226012D01*
G01X375164Y219379D02*
X375214Y220365D01*
G01X375212Y221327D02*
X375162Y220340D01*
G01X373530Y225050D02*
X373580Y226037D01*
G01X373578Y226999D02*
X373528Y226012D01*
G01X371232Y219379D02*
X371282Y220365D01*
G01X371280Y221327D02*
X371229Y220340D01*
G01X369588Y225050D02*
X369639Y226037D01*
G01X369636Y226999D02*
X369586Y226012D01*
G01X367290Y219379D02*
X367340Y220365D01*
G01X367338Y221327D02*
X367288Y220340D01*
G01X365656Y225050D02*
X365706Y226037D01*
G01X365704Y226999D02*
X365654Y226012D01*
G01X363358Y219379D02*
X363408Y220365D01*
G01X363406Y221327D02*
X363355Y220340D01*
G01X381235Y214231D02*
X381371Y220138D01*
G01X381366Y221024D02*
X381230Y215117D01*
G01X379182Y225353D02*
X379318Y231260D01*
G01X379314Y232147D02*
X379177Y226239D01*
G01X377302Y214231D02*
X377439Y220138D01*
G01X377434Y221024D02*
X377298Y215117D01*
G01X375250Y225353D02*
X375386Y231260D01*
G01X375381Y232147D02*
X375245Y226239D01*
G01X373361Y214231D02*
X373497Y220138D01*
G01X373492Y221024D02*
X373356Y215117D01*
G01X371308Y225353D02*
X371444Y231260D01*
G01X371440Y232147D02*
X371303Y226239D01*
G01X369428Y214231D02*
X369565Y220138D01*
G01X369560Y221024D02*
X369424Y215117D01*
G01X367376Y225353D02*
X367512Y231260D01*
G01X367507Y232147D02*
X367371Y226239D01*
G01X365487Y214231D02*
X365623Y220138D01*
G01X365618Y221024D02*
X365482Y215117D01*
G01X363434Y225353D02*
X363570Y231260D01*
G01X363566Y232147D02*
X363429Y226239D01*
G01X361554Y214231D02*
X361691Y220138D01*
G01X361686Y221024D02*
X361550Y215117D01*
G01X359502Y225353D02*
X359638Y231260D01*
G01X359633Y232147D02*
X359497Y226239D01*
G01X378804Y215984D02*
X378791Y215009D01*
G01X377812Y230393D02*
X377825Y231368D01*
G01X374862Y215984D02*
X374849Y215009D01*
G01X373880Y230393D02*
X373893Y231368D01*
G01X370930Y215984D02*
X370917Y215009D01*
G01X369938Y230393D02*
X369951Y231368D01*
G01X366988Y215984D02*
X366975Y215009D01*
G01X366006Y230393D02*
X366019Y231368D01*
G01X363056Y215984D02*
X363043Y215009D01*
G01X362064Y230393D02*
X362077Y231368D01*
G01X359114Y215984D02*
X359101Y215009D01*
G01X358132Y230393D02*
X358145Y231368D01*
G01X379489Y215984D02*
Y209901D01*
G01Y236476D02*
Y230393D01*
G01X379410Y213838D02*
Y232539D01*
G01X379332Y214824D02*
Y213840D01*
G01Y232538D02*
Y231553D01*
G01X379135Y231555D02*
Y236396D01*
G01Y209981D02*
Y214822D01*
G01X379056Y230760D02*
Y231750D01*
G01Y214627D02*
Y215617D01*
G01X378977Y210965D02*
Y209901D01*
G01Y236476D02*
Y235412D01*
G01X378702Y210885D02*
Y209901D01*
G01Y236476D02*
Y235492D01*
G01X377914D02*
Y236476D01*
G01Y210885D02*
Y209901D01*
G01X377639Y210965D02*
Y209901D01*
G01Y236476D02*
Y235412D01*
G01X377560Y215617D02*
Y214627D01*
G01Y231750D02*
Y230760D01*
G01X377481Y231555D02*
Y236396D01*
G01Y209981D02*
Y214822D01*
G01X377284Y231553D02*
Y232538D01*
G01Y213840D02*
Y214824D01*
G01X377206Y232539D02*
Y213838D01*
G01X377127Y215984D02*
Y209901D01*
G01Y236476D02*
Y230393D01*
G01X376930Y214822D02*
Y213838D01*
G01Y232539D02*
Y231555D01*
G01X376925Y232539D02*
Y231555D01*
G01X376891Y216515D02*
Y212342D01*
G01Y234035D02*
Y229862D01*
G01X375788D02*
Y234035D01*
G01Y212342D02*
Y216515D01*
G01X375754Y232539D02*
Y231555D01*
G01X375749Y214822D02*
Y213838D01*
G01X375744Y214822D02*
Y213838D01*
G01X375552Y215984D02*
Y209901D01*
G01Y236476D02*
Y230393D01*
G01X375473Y213838D02*
Y232539D01*
G01X375399Y232538D02*
Y231553D01*
G01X375390Y214824D02*
Y213840D01*
G01X375198Y227698D02*
Y232539D01*
G01Y213838D02*
Y218680D01*
G01X375124Y230760D02*
Y231750D01*
G01X375114Y214627D02*
Y215617D01*
G01X375040Y218760D02*
Y217696D01*
G01Y228681D02*
Y227618D01*
G01X374765D02*
Y228602D01*
G01Y218760D02*
Y217775D01*
G01X373977Y227618D02*
Y228602D01*
G01Y217775D02*
Y218760D01*
G01X373702D02*
Y217696D01*
G01Y228681D02*
Y227618D01*
G01X373628Y231750D02*
Y230760D01*
G01X373618Y215617D02*
Y214627D01*
G01X373584Y208523D02*
Y203011D01*
G01X373544Y227698D02*
Y232539D01*
G01Y213838D02*
Y218680D01*
G01X373352Y231553D02*
Y232538D01*
G01X373343Y213840D02*
Y214824D01*
G01X373269Y232539D02*
Y213838D01*
G01X373190Y215984D02*
Y209901D01*
G01Y236476D02*
Y230393D01*
G01X372998Y232539D02*
Y231555D01*
G01X372993Y232539D02*
Y231555D01*
G01X372988Y214822D02*
Y213838D01*
G01X372954Y216515D02*
Y212342D01*
G01Y234035D02*
Y229862D01*
G01X371851D02*
Y234035D01*
G01Y212342D02*
Y216515D01*
G01X371817Y214822D02*
Y213838D01*
G01X371812Y214822D02*
Y213838D01*
G01Y232539D02*
Y231555D01*
G01X371615Y215984D02*
Y209901D01*
G01Y236476D02*
Y230393D01*
G01X371536Y213838D02*
Y232539D01*
G01X371458Y214824D02*
Y213840D01*
G01Y232538D02*
Y231553D01*
G01X371261Y231555D02*
Y236396D01*
G01Y209981D02*
Y214822D01*
G01X371182Y230760D02*
Y231750D01*
G01Y214627D02*
Y215617D01*
G01X371103Y210965D02*
Y209901D01*
G01Y236476D02*
Y235412D01*
G01X370828Y210885D02*
Y209901D01*
G01Y236476D02*
Y235492D01*
G01X370434Y208523D02*
Y203011D01*
G01X370040Y235492D02*
Y236476D01*
G01Y210885D02*
Y209901D01*
G01X369765Y210965D02*
Y209901D01*
G01Y236476D02*
Y235412D01*
G01X369686Y215617D02*
Y214627D01*
G01Y231750D02*
Y230760D01*
G01X369607Y231555D02*
Y236396D01*
G01Y209981D02*
Y214822D01*
G01X369410Y231553D02*
Y232538D01*
G01Y213840D02*
Y214824D01*
G01X369332Y232539D02*
Y213838D01*
G01X369253Y215984D02*
Y209901D01*
G01Y236476D02*
Y230393D01*
G01X369056Y214822D02*
Y213838D01*
G01Y232539D02*
Y231555D01*
G01X369051Y232539D02*
Y231555D01*
G01X369017Y216515D02*
Y212342D01*
G01Y234035D02*
Y229862D01*
G01X367914D02*
Y234035D01*
G01Y212342D02*
Y216515D01*
G01X367880Y232539D02*
Y231555D01*
G01X367875Y214822D02*
Y213838D01*
G01X367870Y214822D02*
Y213838D01*
G01X367678Y215984D02*
Y209901D01*
G01Y236476D02*
Y230393D01*
G01X367599Y213838D02*
Y232539D01*
G01X367525Y232538D02*
Y231553D01*
G01X367516Y214824D02*
Y213840D01*
G01X367324Y227698D02*
Y232539D01*
G01Y213838D02*
Y218680D01*
G01X367250Y230760D02*
Y231750D01*
G01X367240Y214627D02*
Y215617D01*
G01X367166Y218760D02*
Y217696D01*
G01Y228681D02*
Y227618D01*
G01X366891D02*
Y228602D01*
G01Y218760D02*
Y217775D01*
G01X366497Y208523D02*
Y203011D01*
G01X366103Y227618D02*
Y228602D01*
G01Y217775D02*
Y218760D01*
G01X365828D02*
Y217696D01*
G01Y228681D02*
Y227618D01*
G01X365754Y231750D02*
Y230760D01*
G01X365744Y215617D02*
Y214627D01*
G01X365670Y227698D02*
Y232539D01*
G01Y213838D02*
Y218680D01*
G01X365478Y231553D02*
Y232538D01*
G01X365469Y213840D02*
Y214824D01*
G01X365395Y232539D02*
Y213838D01*
G01X365316Y215984D02*
Y209901D01*
G01Y236476D02*
Y230393D01*
G01X365124Y232539D02*
Y231555D01*
G01X365119Y232539D02*
Y231555D01*
G01X365114Y214822D02*
Y213838D01*
G01X365080Y216515D02*
Y212342D01*
G01Y234035D02*
Y229862D01*
G01X363977D02*
Y234035D01*
G01Y212342D02*
Y216515D01*
G01X363943Y214822D02*
Y213838D01*
G01X363938Y214822D02*
Y213838D01*
G01Y232539D02*
Y231555D01*
G01X363741Y215984D02*
Y209901D01*
G01Y236476D02*
Y230393D01*
G01X363662Y213838D02*
Y232539D01*
G01X363584Y214824D02*
Y213840D01*
G01Y232538D02*
Y231553D01*
G01X363387Y231555D02*
Y236396D01*
G01Y209981D02*
Y214822D01*
G01X363347Y208523D02*
Y203011D01*
G01X363308Y230760D02*
Y231750D01*
G01Y214627D02*
Y215617D01*
G01X363229Y210965D02*
Y209901D01*
G01Y236476D02*
Y235412D01*
G01X362954Y210885D02*
Y209901D01*
G01Y236476D02*
Y235492D01*
G01X362166D02*
Y236476D01*
G01Y210885D02*
Y209901D01*
G01X361891Y210965D02*
Y209901D01*
G01Y236476D02*
Y235412D01*
G01X361812Y215617D02*
Y214627D01*
G01Y231750D02*
Y230760D01*
G01X361733Y231555D02*
Y236396D01*
G01Y209981D02*
Y214822D01*
G01X361536Y213840D02*
Y214824D01*
G01Y231553D02*
Y232538D01*
G01X361458Y232539D02*
Y213838D01*
G01X361379Y215984D02*
Y209901D01*
G01Y236476D02*
Y230393D01*
G01X361182Y214822D02*
Y213838D01*
G01Y232539D02*
Y231555D01*
G01X361177Y232539D02*
Y231555D01*
G01X361143Y216515D02*
Y212342D01*
G01Y234035D02*
Y229862D01*
G01X360040D02*
Y234035D01*
G01Y212342D02*
Y216515D01*
G01X360006Y232539D02*
Y231555D01*
G01X360001Y214822D02*
Y213838D01*
G01X359996Y214822D02*
Y213838D01*
G01X359804Y215984D02*
Y209901D01*
G01Y236476D02*
Y230393D01*
G01X359725Y213838D02*
Y232539D01*
G01X359651Y232538D02*
Y231553D01*
G01X359642Y214824D02*
Y213840D01*
G01X359450Y227698D02*
Y232539D01*
G01Y213838D02*
Y218680D01*
G01X359376Y230760D02*
Y231750D01*
G01X359366Y214627D02*
Y215617D01*
G01X359292Y218760D02*
Y217696D01*
G01Y228681D02*
Y227618D01*
G01X359017Y218760D02*
Y217775D01*
G01Y228602D02*
Y227618D01*
G01X358229Y218760D02*
Y217775D01*
G01Y228602D02*
Y227618D01*
G01X357954Y218760D02*
Y217696D01*
G01Y228681D02*
Y227618D01*
G01X357880Y231750D02*
Y230760D01*
G01X357870Y215617D02*
Y214627D01*
G01X357796Y227698D02*
Y232539D01*
G01Y213838D02*
Y218680D01*
G01X357604Y231553D02*
Y232538D01*
G01X357595Y213840D02*
Y214824D01*
G01X357521Y232539D02*
Y213838D01*
G01X357442Y215984D02*
Y209901D01*
G01Y236476D02*
Y230393D01*
G01X357250Y232539D02*
Y231555D01*
G01X357245Y232539D02*
Y231555D01*
G01X357240Y214822D02*
Y213838D01*
G01X357206Y216515D02*
Y212342D01*
G01Y234035D02*
Y229862D01*
G01X356103D02*
Y234035D01*
G01Y212342D02*
Y216515D01*
G01X356069Y214822D02*
Y213838D01*
G01X356064Y214822D02*
Y213838D01*
G01Y232539D02*
Y231555D01*
G01X355867Y215984D02*
Y209901D01*
G01Y236476D02*
Y230393D01*
G01X355788Y213838D02*
Y232539D01*
G01X355710Y214824D02*
Y213840D01*
G01Y232538D02*
Y231553D01*
G01X355513Y231555D02*
Y236396D01*
G01Y209981D02*
Y214822D01*
G01X355434Y230760D02*
Y231750D01*
G01Y214627D02*
Y215617D01*
G01X355355Y210965D02*
Y209901D01*
G01Y236476D02*
Y235412D01*
G01X377825Y215009D02*
X377812Y215984D01*
G01X374858Y231368D02*
X374872Y230393D01*
G01X373884Y215009D02*
X373871Y215984D01*
G01X370917Y231368D02*
X370930Y230393D01*
G01X369951Y215009D02*
X369938Y215984D01*
G01X366984Y231368D02*
X366998Y230393D01*
G01X366010Y215009D02*
X365997Y215984D01*
G01X363043Y231368D02*
X363056Y230393D01*
G01X362077Y215009D02*
X362064Y215984D01*
G01X359110Y231368D02*
X359123Y230393D01*
G01X358136Y215009D02*
X358123Y215984D01*
G01X355169Y231368D02*
X355182Y230393D01*
G01X354203Y215009D02*
X354190Y215984D01*
G01X375377Y215117D02*
X375241Y221024D01*
G01X375236Y220138D02*
X375372Y214231D01*
G01X373506Y226239D02*
X373370Y232147D01*
G01X373365Y231260D02*
X373502Y225353D01*
G01X371444Y215117D02*
X371308Y221024D01*
G01X371303Y220138D02*
X371440Y214231D01*
G01X369565Y226239D02*
X369428Y232147D01*
G01X369424Y231260D02*
X369560Y225353D01*
G01X367503Y215117D02*
X367367Y221024D01*
G01X367362Y220138D02*
X367498Y214231D01*
G01X365632Y226239D02*
X365496Y232147D01*
G01X365491Y231260D02*
X365628Y225353D01*
G01X363570Y215117D02*
X363434Y221024D01*
G01X363429Y220138D02*
X363566Y214231D01*
G01X361691Y226239D02*
X361554Y232147D01*
G01X361550Y231260D02*
X361686Y225353D01*
G01X359629Y215117D02*
X359493Y221024D01*
G01X359488Y220138D02*
X359624Y214231D01*
G01X357758Y226239D02*
X357622Y232147D01*
G01X357617Y231260D02*
X357753Y225353D01*
G01X355696Y215117D02*
X355560Y221024D01*
G01X355555Y220138D02*
X355692Y214231D01*
G01X353817Y226239D02*
X353680Y232147D01*
G01X353676Y231260D02*
X353812Y225353D01*
G01X371282Y226012D02*
X371232Y226999D01*
G01X371229Y226037D02*
X371280Y225050D01*
G01X369639Y220340D02*
X369588Y221327D01*
G01X369586Y220365D02*
X369636Y219379D01*
G01X367350Y226012D02*
X367299Y226999D01*
G01X367297Y226037D02*
X367347Y225050D01*
G01X365697Y220340D02*
X365647Y221327D01*
G01X365644Y220365D02*
X365695Y219379D01*
G01X363408Y226012D02*
X363358Y226999D01*
G01X363355Y226037D02*
X363406Y225050D01*
G01X361765Y220340D02*
X361714Y221327D01*
G01X361712Y220365D02*
X361762Y219379D01*
G01X359476Y226012D02*
X359425Y226999D01*
G01X359423Y226037D02*
X359473Y225050D01*
G01X357823Y220340D02*
X357773Y221327D01*
G01X357770Y220365D02*
X357821Y219379D01*
G01X355534Y226012D02*
X355484Y226999D01*
G01X355481Y226037D02*
X355532Y225050D01*
G01X353891Y220340D02*
X353840Y221327D01*
G01X353838Y220365D02*
X353888Y219379D01*
G01X351602Y226012D02*
X351551Y226999D01*
G01X351549Y226037D02*
X351599Y225050D01*
G01X349949Y220340D02*
X349899Y221327D01*
G01X349896Y220365D02*
X349947Y219379D01*
G01X424816Y214640D02*
X425069Y215009D01*
G01X424803Y215615D02*
X425024Y215937D01*
G01X420874Y214640D02*
X421128Y215009D01*
G01X381722Y215984D02*
X381712Y215937D01*
G01X382768Y230393D02*
X382778Y230441D01*
G01X377789Y215984D02*
X377780Y215937D01*
G01X378827Y230393D02*
X378836Y230441D01*
G01X373848Y215984D02*
X373838Y215937D01*
G01X374894Y230393D02*
X374904Y230441D01*
G01X369915Y215984D02*
X369906Y215937D01*
G01X370953Y230393D02*
X370962Y230441D01*
G01X365974Y215984D02*
X365964Y215937D01*
G01X367020Y230393D02*
X367030Y230441D01*
G01X362041Y215984D02*
X362032Y215937D01*
G01X363079Y230393D02*
X363088Y230441D01*
G01X358100Y215984D02*
X358090Y215937D01*
G01X361714Y225050D02*
X361765Y226037D01*
G01X361762Y226999D02*
X361712Y226012D01*
G01X359416Y219379D02*
X359466Y220365D01*
G01X359464Y221327D02*
X359414Y220340D01*
G01X357782Y225050D02*
X357832Y226037D01*
G01X357830Y226999D02*
X357780Y226012D01*
G01X355484Y219379D02*
X355534Y220365D01*
G01X355532Y221327D02*
X355481Y220340D01*
G01X353840Y225050D02*
X353891Y226037D01*
G01X353888Y226999D02*
X353838Y226012D01*
G01X351542Y219379D02*
X351592Y220365D01*
G01X351590Y221327D02*
X351540Y220340D01*
G01X349908Y225050D02*
X349958Y226037D01*
G01X349956Y226999D02*
X349906Y226012D01*
G01X347610Y219379D02*
X347660Y220365D01*
G01X347658Y221327D02*
X347607Y220340D01*
G01X357613Y214231D02*
X357749Y220138D01*
G01X357744Y221024D02*
X357608Y215117D01*
G01X355560Y225353D02*
X355696Y231260D01*
G01X355692Y232147D02*
X355555Y226239D01*
G01X353680Y214231D02*
X353817Y220138D01*
G01X353812Y221024D02*
X353676Y215117D01*
G01X351628Y225353D02*
X351764Y231260D01*
G01X351759Y232147D02*
X351623Y226239D01*
G01X349739Y214231D02*
X349875Y220138D01*
G01X349870Y221024D02*
X349734Y215117D01*
G01X347686Y225353D02*
X347822Y231260D01*
G01X347818Y232147D02*
X347681Y226239D01*
G01X355182Y215984D02*
X355169Y215009D01*
G01X354190Y230393D02*
X354203Y231368D01*
G01X351240Y215984D02*
X351227Y215009D01*
G01X350258Y230393D02*
X350271Y231368D01*
G01X347308Y215984D02*
X347295Y215009D01*
G01X355080Y210885D02*
Y209901D01*
G01Y236476D02*
Y235492D01*
G01X354292D02*
Y236476D01*
G01Y210885D02*
Y209901D01*
G01X354017Y210965D02*
Y209901D01*
G01Y236476D02*
Y235412D01*
G01X353938Y215617D02*
Y214627D01*
G01Y231750D02*
Y230760D01*
G01X353859Y231555D02*
Y236396D01*
G01Y209981D02*
Y214822D01*
G01X353662Y213840D02*
Y214824D01*
G01Y231553D02*
Y232538D01*
G01X353584Y232539D02*
Y213838D01*
G01X353505Y215984D02*
Y209901D01*
G01Y236476D02*
Y230393D01*
G01X353308Y214822D02*
Y213838D01*
G01Y232539D02*
Y231555D01*
G01X353303Y232539D02*
Y231555D01*
G01X353269Y216515D02*
Y212342D01*
G01Y234035D02*
Y229862D01*
G01X352166D02*
Y234035D01*
G01Y212342D02*
Y216515D01*
G01X352132Y232539D02*
Y231555D01*
G01X352127Y214822D02*
Y213838D01*
G01X352122Y214822D02*
Y213838D01*
G01X351930Y215984D02*
Y209901D01*
G01Y236476D02*
Y230393D01*
G01X351851Y213838D02*
Y232539D01*
G01X351777Y232538D02*
Y231553D01*
G01X351768Y214824D02*
Y213840D01*
G01X351576Y227698D02*
Y232539D01*
G01Y213838D02*
Y218680D01*
G01X351502Y230760D02*
Y231750D01*
G01X351492Y214627D02*
Y215617D01*
G01X351418Y218760D02*
Y217696D01*
G01Y228681D02*
Y227618D01*
G01X351143Y218760D02*
Y217775D01*
G01Y228602D02*
Y227618D01*
G01X350355Y218760D02*
Y217775D01*
G01Y228602D02*
Y227618D01*
G01X350080Y218760D02*
Y217696D01*
G01Y228681D02*
Y227618D01*
G01X350006Y231750D02*
Y230760D01*
G01X349996Y215617D02*
Y214627D01*
G01X349962Y208523D02*
Y203011D01*
G01X349922Y227698D02*
Y232539D01*
G01Y213838D02*
Y218680D01*
G01X349730Y231553D02*
Y232538D01*
G01X349721Y213840D02*
Y214824D01*
G01X349647Y232539D02*
Y213838D01*
G01X349568Y215984D02*
Y209901D01*
G01Y236476D02*
Y230393D01*
G01X349376Y232539D02*
Y231555D01*
G01X349371Y232539D02*
Y231555D01*
G01X349366Y214822D02*
Y213838D01*
G01X349332Y216515D02*
Y212342D01*
G01Y234035D02*
Y229862D01*
G01X348229D02*
Y234035D01*
G01Y212342D02*
Y216515D01*
G01X348195Y214822D02*
Y213838D01*
G01X348190Y214822D02*
Y213838D01*
G01Y232539D02*
Y231555D01*
G01X347993Y215984D02*
Y209901D01*
G01Y236476D02*
Y230393D01*
G01X347914Y213838D02*
Y232539D01*
G01X347836Y214824D02*
Y213840D01*
G01Y232538D02*
Y231553D01*
G01X347639Y231555D02*
Y236396D01*
G01Y209981D02*
Y214822D01*
G01X347560Y230760D02*
Y231750D01*
G01Y214627D02*
Y215617D01*
G01X347481Y210965D02*
Y209901D01*
G01Y236476D02*
Y235412D01*
G01X347206Y210885D02*
Y209901D01*
G01Y236476D02*
Y235492D01*
G01X351236Y231368D02*
X351249Y230393D01*
G01X350262Y215009D02*
X350249Y215984D01*
G01X347295Y231368D02*
X347308Y230393D01*
G01X351755Y215117D02*
X351619Y221024D01*
G01X351614Y220138D02*
X351750Y214231D01*
G01X349884Y226239D02*
X349748Y232147D01*
G01X349743Y231260D02*
X349879Y225353D01*
G01X347822Y215117D02*
X347686Y221024D01*
G01X347681Y220138D02*
X347818Y214231D01*
G01X347660Y226012D02*
X347610Y226999D01*
G01X347607Y226037D02*
X347658Y225050D01*
G01X420861Y215615D02*
X421082Y215937D01*
G01X416942Y214640D02*
X417195Y215009D01*
G01X416928Y215615D02*
X417150Y215937D01*
G01X426302Y230762D02*
X426080Y230441D01*
G01X426289Y231737D02*
X426035Y231368D01*
G01X413000Y214640D02*
X413254Y215009D01*
G01X412987Y215615D02*
X413208Y215937D01*
G01X422369Y230762D02*
X422148Y230441D01*
G01X422356Y231737D02*
X422102Y231368D01*
G01X409068Y214640D02*
X409321Y215009D01*
G01X409054Y215615D02*
X409276Y215937D01*
G01X418428Y230762D02*
X418206Y230441D01*
G01X418415Y231737D02*
X418161Y231368D01*
G01X405126Y214640D02*
X405380Y215009D01*
G01X405113Y215615D02*
X405334Y215937D01*
G01X414495Y230762D02*
X414274Y230441D01*
G01X414482Y231737D02*
X414228Y231368D01*
G01X401194Y214640D02*
X401447Y215009D01*
G01X401402Y215937D02*
X401182Y215617D01*
G01X410554Y230762D02*
X410332Y230441D01*
G01X410541Y231737D02*
X410287Y231368D01*
G01X397252Y214640D02*
X397506Y215009D01*
G01X397239Y215615D02*
X397460Y215937D01*
G01X406621Y230762D02*
X406400Y230441D01*
G01X406608Y231737D02*
X406354Y231368D01*
G01X393320Y214640D02*
X393573Y215009D01*
G01X393528Y215937D02*
X393308Y215617D01*
G01X402458Y230441D02*
X402678Y230760D01*
G01X402667Y231737D02*
X402413Y231368D01*
G01X359146Y230393D02*
X359156Y230441D01*
G01X354167Y215984D02*
X354158Y215937D01*
G01X355205Y230393D02*
X355214Y230441D01*
G01X350226Y215984D02*
X350216Y215937D01*
G01X351272Y230393D02*
X351282Y230441D01*
G01X347331Y230393D02*
X347340Y230441D01*
G01X389378Y214640D02*
X389632Y215009D01*
G01X389365Y215615D02*
X389586Y215937D01*
G01X398747Y230762D02*
X398526Y230441D01*
G01X398734Y231737D02*
X398480Y231368D01*
G01X385446Y214640D02*
X385699Y215009D01*
G01X385432Y215615D02*
X385654Y215937D01*
G01X394584Y230441D02*
X394804Y230760D01*
G01X394793Y231737D02*
X394539Y231368D01*
G01X381504Y214640D02*
X381758Y215009D01*
G01X381491Y215615D02*
X381712Y215937D01*
G01X390873Y230762D02*
X390652Y230441D01*
G01X390860Y231737D02*
X390606Y231368D01*
G01X377572Y214640D02*
X377825Y215009D01*
G01X377558Y215615D02*
X377780Y215937D01*
G01X386932Y230762D02*
X386710Y230441D01*
G01X386919Y231737D02*
X386665Y231368D01*
G01X373630Y214640D02*
X373884Y215009D01*
G01X373617Y215615D02*
X373838Y215937D01*
G01X382999Y230762D02*
X382778Y230441D01*
G01X382986Y231737D02*
X382732Y231368D01*
G01X369698Y214640D02*
X369951Y215009D01*
G01X369684Y215615D02*
X369906Y215937D01*
G01X379058Y230762D02*
X378836Y230441D01*
G01X379045Y231737D02*
X378791Y231368D01*
G01X365756Y214640D02*
X366010Y215009D01*
G01X365743Y215615D02*
X365964Y215937D01*
G01X375125Y230762D02*
X374904Y230441D01*
G01X375112Y231737D02*
X374858Y231368D01*
G01X361824Y214640D02*
X362077Y215009D01*
G01X361810Y215615D02*
X362032Y215937D01*
G01X371184Y230762D02*
X370962Y230441D01*
G01X371171Y231737D02*
X370917Y231368D01*
G01X357882Y214640D02*
X358136Y215009D01*
G01X357869Y215615D02*
X358090Y215937D01*
G01X367251Y230762D02*
X367030Y230441D01*
G01X367238Y231737D02*
X366984Y231368D01*
G01X353950Y214640D02*
X354203Y215009D01*
G01X353936Y215615D02*
X354158Y215937D01*
G01X363310Y230762D02*
X363088Y230441D01*
G01X363297Y231737D02*
X363043Y231368D01*
G01X350008Y214640D02*
X350262Y215009D01*
G01X349995Y215615D02*
X350216Y215937D01*
G01X359377Y230762D02*
X359156Y230441D01*
G01X359364Y231737D02*
X359110Y231368D01*
G01X355436Y230762D02*
X355214Y230441D01*
G01X355423Y231737D02*
X355169Y231368D01*
G01X351503Y230762D02*
X351282Y230441D01*
G01X351490Y231737D02*
X351236Y231368D01*
G01X347562Y230762D02*
X347340Y230441D01*
G01X347548Y231737D02*
X347295Y231368D01*
G01X428505Y563228D02*
X426536Y565196D01*
G01X382978Y771135D02*
Y777435D01*
X380080Y772920D01*
X383996D01*
G01X461302Y-578426D02*
Y-595749D01*
G01X483183Y-392704D02*
X491577D01*
G01X462767Y-394790D02*
G03X483183Y-392704I4J100910D01*
G01X462767Y-297817D02*
Y-398728D01*
G01X429182Y-449536D02*
X433080D01*
G01X429182Y-440875D02*
Y-449536D01*
G01X469620Y-448814D02*
X470107Y-449536D01*
G01X469620D02*
Y-448814D01*
G01X470107Y-449536D02*
X469620D01*
G01X436977Y-440875D02*
X440875D01*
G01X436977Y-449536D02*
Y-440875D01*
G01X440875Y-449536D02*
X436977D01*
G01Y-427883D02*
X440875D01*
G01X436977Y-436544D02*
Y-427883D01*
G01X440875Y-436544D02*
X436977D01*
G01X431131Y-427883D02*
X432105Y-428604D01*
G01X429182Y-427883D02*
X431131D01*
G01X478877Y-448814D02*
X477902Y-449536D01*
G01X479364Y-448093D02*
X478877Y-448814D01*
G01X479851Y-446649D02*
X479364Y-448093D01*
G01X479851Y-443762D02*
Y-446649D01*
G01X479364Y-442318D02*
X479851Y-443762D01*
G01X478877Y-441597D02*
X479364Y-442318D01*
G01X477902Y-440875D02*
X478877Y-441597D01*
G01X476928D02*
X477902Y-440875D01*
G01X476441Y-442318D02*
X476928Y-441597D01*
G01X475954Y-443762D02*
X476441Y-442318D01*
G01X475954Y-446649D02*
Y-443762D01*
G01X476441Y-448093D02*
X475954Y-446649D01*
G01X476928Y-448814D02*
X476441Y-448093D01*
G01X477902Y-449536D02*
X476928Y-448814D01*
G01X486672D02*
X485698Y-449536D01*
G01X487159Y-448093D02*
X486672Y-448814D01*
G01X487647Y-446649D02*
X487159Y-448093D01*
G01X487647Y-443762D02*
Y-446649D01*
G01X487159Y-442318D02*
X487647Y-443762D01*
G01X486672Y-441597D02*
X487159Y-442318D01*
G01X485698Y-440875D02*
X486672Y-441597D01*
G01X484723D02*
X485698Y-440875D01*
G01X484236Y-442318D02*
X484723Y-441597D01*
G01X483749Y-443762D02*
X484236Y-442318D01*
G01X483749Y-446649D02*
Y-443762D01*
G01X484236Y-448093D02*
X483749Y-446649D01*
G01X484723Y-448814D02*
X484236Y-448093D01*
G01X485698Y-449536D02*
X484723Y-448814D01*
G01X494467D02*
X493493Y-449536D01*
G01X494955Y-448093D02*
X494467Y-448814D01*
G01X495442Y-446649D02*
X494955Y-448093D01*
G01X495442Y-443762D02*
Y-446649D01*
G01X494955Y-442318D02*
X495442Y-443762D01*
G01X494467Y-441597D02*
X494955Y-442318D01*
G01X493493Y-440875D02*
X494467Y-441597D01*
G01X492519D02*
X493493Y-440875D01*
G01X492031Y-442318D02*
X492519Y-441597D01*
G01X491544Y-443762D02*
X492031Y-442318D01*
G01X491544Y-446649D02*
Y-443762D01*
G01X492031Y-448093D02*
X491544Y-446649D01*
G01X492519Y-448814D02*
X492031Y-448093D01*
G01X493493Y-449536D02*
X492519Y-448814D01*
G01X433567Y-432213D02*
X433080Y-434379D01*
G01Y-430048D02*
X433567Y-432213D01*
G01X432105Y-428604D02*
X433080Y-430048D01*
G01X506573Y-394147D02*
Y-394869D01*
G01X505598Y-392704D02*
X506573Y-394147D01*
G01X468158Y-436544D02*
X472056D01*
G01X468158Y-427883D02*
Y-436544D01*
G01X454517Y-427883D02*
X456953Y-436544D01*
G01X452081D02*
X454517Y-427883D01*
G01X493493D02*
X495929Y-436544D01*
G01X491057D02*
X493493Y-427883D01*
G01X429182Y-436544D02*
Y-427883D01*
G01X431131Y-436544D02*
X429182D01*
G01X432105Y-435822D02*
X431131Y-436544D01*
G01X433080Y-434379D02*
X432105Y-435822D01*
G01X502675Y-396313D02*
X502188Y-395591D01*
G01X503649Y-397034D02*
X502675Y-396313D01*
G01X504624Y-397034D02*
X503649D01*
G01X505598Y-396313D02*
X504624Y-397034D01*
G01X506573Y-394869D02*
X505598Y-396313D01*
G01X504624Y-391982D02*
X505598Y-392704D01*
G01Y-391260D02*
X504624Y-391982D01*
G01X506085Y-390538D02*
X505598Y-391260D01*
G01X506085Y-389817D02*
Y-390538D01*
G01X505598Y-389095D02*
X506085Y-389817D01*
G01X504624Y-388373D02*
X505598Y-389095D01*
G01X503649Y-388373D02*
X504624D01*
G01X502675Y-389095D02*
X503649Y-388373D01*
G01X462312Y-440875D02*
Y-449536D01*
G01Y-427883D02*
Y-436544D01*
G01X503649Y-391982D02*
X504624D01*
G01X444285Y-427883D02*
X449157D01*
G01X436977Y-432213D02*
X439413D01*
G01X492031Y-433657D02*
X494955D01*
G01X453055D02*
X455978D01*
G01X436977Y-445206D02*
X439413D01*
G01X446721Y-427883D02*
Y-436544D01*
G01X441310Y-334670D02*
X461881D01*
G01X460995D02*
X441310D01*
G01X541336D02*
X461881D01*
G01X462767D02*
X541336D01*
G01X460995Y-300886D02*
Y-338607D01*
G01X462767Y-297817D02*
Y-338607D01*
G01X480074Y-331782D02*
X480561Y-332504D01*
G01X480074D02*
Y-331782D01*
G01X480561Y-332504D02*
X480074D01*
G01X494690Y-331782D02*
X494203Y-331061D01*
G01X495665Y-332504D02*
X494690Y-331782D01*
G01X496639Y-332504D02*
X495665D01*
G01X497613Y-331782D02*
X496639Y-332504D01*
G01X498101Y-331061D02*
X497613Y-331782D01*
G01X498588Y-329617D02*
X498101Y-331061D01*
G01Y-328174D02*
X498588Y-329617D01*
G01X497613Y-327452D02*
X498101Y-328174D01*
G01X496639Y-326730D02*
X497613Y-327452D01*
G01X495665Y-326730D02*
X496639D01*
G01X494690Y-327452D02*
X495665Y-326730D01*
G01X495177Y-323843D02*
X494690Y-327452D01*
G01X498101Y-323843D02*
X495177D01*
G01X473740Y-331782D02*
X472766Y-332504D01*
G01X474228Y-331061D02*
X473740Y-331782D01*
G01X474715Y-329617D02*
X474228Y-331061D01*
G01X474715Y-326730D02*
Y-329617D01*
G01X474228Y-325286D02*
X474715Y-326730D01*
G01X473740Y-324565D02*
X474228Y-325286D01*
G01X472766Y-323843D02*
X473740Y-324565D01*
G01X471792D02*
X472766Y-323843D01*
G01X471304Y-325286D02*
X471792Y-324565D01*
G01X470817Y-326730D02*
X471304Y-325286D01*
G01X470817Y-329617D02*
Y-326730D01*
G01X471304Y-331061D02*
X470817Y-329617D01*
G01X471792Y-331782D02*
X471304Y-331061D01*
G01X472766Y-332504D02*
X471792Y-331782D01*
G01X486408Y-330339D02*
X490793D01*
G01X489818Y-323843D02*
X486408Y-330339D01*
G01X489818Y-332504D02*
Y-323843D01*
G01X504380D02*
Y-332504D01*
G01X500050Y-328174D02*
X508711D01*
G01X500050Y-332504D02*
X508711D01*
G01X459251Y-276900D02*
X462767Y-276758D01*
G01X456586Y-281988D02*
X456487D01*
G01X462865D02*
X462767D01*
G01Y-282776D02*
X462865D01*
G01X456586D02*
X456487D01*
G01X462767Y-293880D02*
X460995Y-296949D01*
G01X462865Y-281879D02*
Y-282430D01*
G01Y-280098D02*
Y-281516D01*
G01Y-282430D02*
Y-293012D01*
G01Y-281879D02*
Y-282430D01*
G01Y-280098D02*
Y-281516D01*
G01X462767Y-276758D02*
Y-293880D01*
G01X456586Y-293012D02*
X456487D01*
G01X462865D02*
X462767D01*
G01X462132Y-294980D02*
X457221D01*
G01X456586Y-296949D02*
Y-278014D01*
G01Y-296949D02*
Y-278014D01*
G01X456487Y-281988D02*
Y-293012D01*
G01X460995Y-296949D02*
X458357D01*
G01D02*
X456586Y-293880D01*
G01Y-278014D02*
X459251Y-276900D01*
G01X506615Y-59174D02*
Y-69410D01*
G01X505631Y-59174D02*
Y-69410D01*
G01X503466Y-59174D02*
Y-69410D01*
G01X502481Y-59174D02*
Y-69410D01*
G01X500316Y-59174D02*
Y-69410D01*
G01X499332Y-59174D02*
Y-69410D01*
G01X497166Y-59174D02*
Y-69410D01*
G01X496182Y-59174D02*
Y-69410D01*
G01X494017Y-59174D02*
Y-69410D01*
G01X493032Y-59174D02*
Y-69410D01*
G01X490867Y-59174D02*
Y-69410D01*
G01X489883Y-59174D02*
Y-69410D01*
G01X487717Y-59174D02*
Y-69410D01*
G01X486733Y-59174D02*
Y-69410D01*
G01X484568Y-59174D02*
Y-69410D01*
G01X483584Y-59174D02*
Y-69410D01*
G01X481418Y-59174D02*
Y-69410D01*
G01X480434Y-59174D02*
Y-69410D01*
G01X478269Y-59174D02*
Y-69410D01*
G01X477284Y-59174D02*
Y-69410D01*
G01X475119Y-59174D02*
Y-69410D01*
G01X474135Y-59174D02*
Y-69410D01*
G01X471969Y-59174D02*
Y-69410D01*
G01X470985Y-59174D02*
Y-69410D01*
G01X468820Y-59174D02*
Y-69410D01*
G01X467836Y-59174D02*
Y-69410D01*
G01X465670Y-59174D02*
Y-69410D01*
G01X464686Y-59174D02*
Y-69410D01*
G01X462521Y-59174D02*
Y-69410D01*
G01X461536Y-59174D02*
Y-69410D01*
G01X459371Y-59174D02*
Y-69410D01*
G01X458387Y-59174D02*
Y-69410D01*
G01X456221Y-59174D02*
Y-69410D01*
G01X455237Y-59174D02*
Y-69410D01*
G01X453072Y-59174D02*
Y-69410D01*
G01X452088Y-59174D02*
Y-69410D01*
G01X449922Y-59174D02*
Y-69410D01*
G01X448938Y-59174D02*
Y-69410D01*
G01X446773Y-59174D02*
Y-69410D01*
G01X445788Y-59174D02*
Y-69410D01*
G01X443623Y-59174D02*
Y-69410D01*
G01X440670Y-71378D02*
Y-42638D01*
G01Y-71378D02*
Y-42638D01*
G01X442639Y-73347D02*
X440670Y-71378D01*
G01X442639Y-73347D02*
X440670Y-71378D01*
G01X445788Y-69410D02*
X443623D01*
G01X448938D02*
X446773D01*
G01X452088D02*
X449922D01*
G01X455237D02*
X453072D01*
G01X458387D02*
X456221D01*
G01X461536D02*
X459371D01*
G01X464686D02*
X462521D01*
G01X467836D02*
X465670D01*
G01X470985D02*
X468820D01*
G01X474135D02*
X471969D01*
G01X477284D02*
X475119D01*
G01X480434D02*
X478269D01*
G01X483584D02*
X481418D01*
G01X486733D02*
X484568D01*
G01X489883D02*
X487717D01*
G01X493032D02*
X490867D01*
G01X496182D02*
X494017D01*
G01X499332D02*
X497166D01*
G01X502481D02*
X500316D01*
G01X505631D02*
X503466D01*
G01X508780D02*
X506615D01*
G01X540080Y-70278D02*
X440670D01*
G01X442639Y-73347D02*
X538111D01*
G01X442639D02*
X538111D01*
G01X442639Y-73346D02*
X538111D01*
G01X440670Y-71378D02*
X442639Y-73346D01*
G01X440670Y-42638D02*
Y-71378D01*
G01Y-42638D02*
G03X439883Y-41851I-787J0D01*
G01X440670Y-42638D02*
G03X439883Y-41851I-787J0D01*
G01X444250Y-58535D02*
X444204Y-58570D01*
G01X444192Y-58500D02*
X444215Y-58477D01*
G01X445719Y-58371D02*
X445650Y-58453D01*
G01Y-58359D02*
X445719Y-58277D01*
G01X444284Y-58488D02*
X444250Y-58535D01*
G01X444158Y-58512D02*
X444192Y-58500D01*
G01X444295Y-58453D02*
X444284Y-58488D01*
G01X444215Y-58477D02*
X444227Y-58441D01*
G01X445788Y-58277D02*
Y-58828D01*
G01X445719D02*
Y-58371D01*
G01X445650Y-58453D02*
Y-58359D01*
G01X445007Y-58277D02*
Y-58828D01*
G01X444939Y-58746D02*
Y-58277D01*
G01X444617Y-58348D02*
Y-58828D01*
G01X444548D02*
Y-58277D01*
G01X444456D02*
Y-58828D01*
G01X444387D02*
Y-58277D01*
G01X444295Y-58406D02*
Y-58453D01*
G01X444227Y-58441D02*
Y-58406D01*
G01X443939Y-58336D02*
Y-58512D01*
G01Y-58582D02*
Y-58828D01*
G01X443871D02*
Y-58277D01*
G01X444284Y-58371D02*
X444295Y-58406D01*
G01X444227D02*
X444215Y-58371D01*
G01X444904Y-58828D02*
X444617Y-58348D01*
G01X444651Y-58277D02*
X444939Y-58746D01*
G01X444250Y-58324D02*
X444284Y-58371D01*
G01X444215D02*
X444192Y-58348D01*
G01X444204Y-58289D02*
X444250Y-58324D01*
G01X444192Y-58348D02*
X444158Y-58336D01*
G01X444146Y-58277D02*
X444204Y-58289D01*
G01X445719Y-58277D02*
X445788D01*
G01X444548D02*
X444651D01*
G01X444939D02*
X445007D01*
G01X444387D02*
X444456D01*
G01X443871D02*
X444146D01*
G01X444158Y-58336D02*
X443939D01*
G01Y-58512D02*
X444158D01*
G01X444146Y-58582D02*
X443939D01*
G01Y-58828D02*
X443871D01*
G01X445788D02*
X445719D01*
G01X444617D02*
X444548D01*
G01X445007D02*
X444904D01*
G01X444456D02*
X444387D01*
G01X445788Y-59174D02*
X443623D01*
G01X448938D02*
X446773D01*
G01X452088D02*
X449922D01*
G01X455237D02*
X453072D01*
G01X458387D02*
X456221D01*
G01X461536D02*
X459371D01*
G01X464686D02*
X462521D01*
G01X467836D02*
X465670D01*
G01X470985D02*
X468820D01*
G01X474135D02*
X471969D01*
G01X477284D02*
X475119D01*
G01X480434D02*
X478269D01*
G01X483584D02*
X481418D01*
G01X486733D02*
X484568D01*
G01X489883D02*
X487717D01*
G01X493032D02*
X490867D01*
G01X496182D02*
X494017D01*
G01X499332D02*
X497166D01*
G01X502481D02*
X500316D01*
G01X505631D02*
X503466D01*
G01X508780D02*
X506615D01*
G01X444204Y-58570D02*
X444146Y-58582D01*
G01X440670Y-42638D02*
G03X439883Y-41850I-787J1D01*
G01X450033Y145965D02*
X450044Y146239D01*
G01X450028Y145948D02*
X450033Y145965D01*
G01X450022Y146012D02*
X450028Y145948D01*
G01X450034Y144988D02*
X450048Y145353D01*
G01X450027Y144965D02*
X450034Y144988D01*
G01X450020Y145050D02*
X450027Y144965D01*
G01X449956Y146524D02*
X449969Y146037D01*
G01X449950Y146913D02*
X449956Y146524D01*
G01X449945Y147384D02*
X449950Y146913D01*
G01X449941Y147925D02*
X449945Y147384D01*
G01X449938Y148520D02*
X449941Y147925D01*
G01X449936Y149153D02*
X449938Y148520D01*
G01X449935Y149807D02*
X449936Y149153D01*
G01X449962Y147364D02*
X449972Y146999D01*
G01X449957Y147656D02*
X449962Y147364D01*
G01X449953Y148009D02*
X449957Y147656D01*
G01X449950Y148414D02*
X449953Y148009D01*
G01X449948Y148861D02*
X449950Y148414D01*
G01X449946Y149336D02*
X449948Y148861D01*
G01X449946Y149826D02*
Y149336D01*
G01X448315Y145965D02*
X448326Y146012D01*
G01X448310Y146063D02*
X448315Y145965D01*
G01X448305Y146239D02*
X448310Y146063D01*
G01X448400Y148861D02*
X448403Y149826D01*
G01X448398Y148414D02*
X448400Y148861D01*
G01X448395Y148009D02*
X448398Y148414D01*
G01X448391Y147656D02*
X448395Y148009D01*
G01X448387Y147364D02*
X448391Y147656D01*
G01X448382Y147143D02*
X448387Y147364D01*
G01X448377Y146999D02*
X448382Y147143D01*
G01X448411Y148520D02*
X448413Y149807D01*
G01X448408Y147925D02*
X448411Y148520D01*
G01X448404Y147384D02*
X448408Y147925D01*
G01X448398Y146913D02*
X448404Y147384D01*
G01X448392Y146524D02*
X448398Y146913D01*
G01X448386Y146230D02*
X448392Y146524D01*
G01X448379Y146037D02*
X448386Y146230D01*
G01X448314Y144988D02*
X448328Y145050D01*
G01X448307Y145118D02*
X448314Y144988D01*
G01X448300Y145353D02*
X448307Y145118D01*
G01X448315Y140412D02*
X448305Y140138D01*
G01X448321Y140429D02*
X448315Y140412D01*
G01X448326Y140365D02*
X448321Y140429D01*
G01X448314Y141390D02*
X448300Y141024D01*
G01X448321Y141412D02*
X448314Y141390D01*
G01X448328Y141327D02*
X448321Y141412D01*
G01X448392Y139853D02*
X448379Y140340D01*
G01X448398Y139464D02*
X448392Y139853D01*
G01X448404Y138993D02*
X448398Y139464D01*
G01X448408Y138453D02*
X448404Y138993D01*
G01X448411Y137857D02*
X448408Y138453D01*
G01X448413Y137224D02*
X448411Y137857D01*
G01X448413Y136570D02*
Y137224D01*
G01X448387Y139013D02*
X448377Y139379D01*
G01X448391Y138722D02*
X448387Y139013D01*
G01X448395Y138368D02*
X448391Y138722D01*
G01X448398Y137963D02*
X448395Y138368D01*
G01X448400Y137516D02*
X448398Y137963D01*
G01X448402Y137041D02*
X448400Y137516D01*
G01X448403Y136551D02*
X448402Y137041D01*
G01X450033Y140412D02*
X450022Y140365D01*
G01X450039Y140314D02*
X450033Y140412D01*
G01X450044Y140138D02*
X450039Y140314D01*
G01X449948Y137516D02*
X449946Y136551D01*
G01X449950Y137963D02*
X449948Y137516D01*
G01X449953Y138368D02*
X449950Y137963D01*
G01X449957Y138722D02*
X449953Y138368D01*
G01X449962Y139013D02*
X449957Y138722D01*
G01X449967Y139234D02*
X449962Y139013D01*
G01X449972Y139379D02*
X449967Y139234D01*
G01X449938Y137857D02*
X449935Y136570D01*
G01X449941Y138453D02*
X449938Y137857D01*
G01X449945Y138993D02*
X449941Y138453D01*
G01X449950Y139464D02*
X449945Y138993D01*
G01X449956Y139853D02*
X449950Y139464D01*
G01X449962Y140148D02*
X449956Y139853D01*
G01X449969Y140340D02*
X449962Y140148D01*
G01X450034Y141390D02*
X450020Y141327D01*
G01X450042Y141259D02*
X450034Y141390D01*
G01X450048Y141024D02*
X450042Y141259D01*
G01X446101Y145965D02*
X446111Y146239D01*
G01X446095Y145948D02*
X446101Y145965D01*
G01X446090Y146012D02*
X446095Y145948D01*
G01X446102Y144988D02*
X446116Y145353D01*
G01X446095Y144965D02*
X446102Y144988D01*
G01X446088Y145050D02*
X446095Y144965D01*
G01X446024Y146524D02*
X446037Y146037D01*
G01X446018Y146913D02*
X446024Y146524D01*
G01X446013Y147384D02*
X446018Y146913D01*
G01X446008Y147925D02*
X446013Y147384D01*
G01X446005Y148520D02*
X446008Y147925D01*
G01X446003Y149153D02*
X446005Y148520D01*
G01X446003Y149807D02*
Y149153D01*
G01X445998Y151677D02*
X445990Y151750D01*
G01X446001Y151547D02*
X445998Y151677D01*
G01X446005Y151359D02*
X446001Y151547D01*
G01X446008Y151120D02*
X446005Y151359D01*
G01X446010Y150838D02*
X446008Y151120D01*
G01X446012Y150521D02*
X446010Y150838D01*
G01X446013Y150180D02*
X446012Y150521D01*
G01X446014Y149826D02*
X446013Y150180D01*
G01X446029Y147364D02*
X446039Y146999D01*
G01X446025Y147656D02*
X446029Y147364D01*
G01X446021Y148009D02*
X446025Y147656D01*
G01X446018Y148414D02*
X446021Y148009D01*
G01X446016Y148861D02*
X446018Y148414D01*
G01X446014Y149336D02*
X446016Y148861D01*
G01X446014Y149826D02*
Y149336D01*
G01X444383Y145965D02*
X444394Y146012D01*
G01X444378Y146063D02*
X444383Y145965D01*
G01X444372Y146239D02*
X444378Y146063D01*
G01X444468Y148861D02*
X444470Y149826D01*
G01X444466Y148414D02*
X444468Y148861D01*
G01X444463Y148009D02*
X444466Y148414D01*
G01X444459Y147656D02*
X444463Y148009D01*
G01X444454Y147364D02*
X444459Y147656D01*
G01X444450Y147143D02*
X444454Y147364D01*
G01X444444Y146999D02*
X444450Y147143D01*
G01X444472Y150521D02*
X444470Y149826D01*
G01X444474Y150838D02*
X444472Y150521D01*
G01X444476Y151120D02*
X444474Y150838D01*
G01X444479Y151359D02*
X444476Y151120D01*
G01X444482Y151547D02*
X444479Y151359D01*
G01X444486Y151677D02*
X444482Y151547D01*
G01X444490Y151746D02*
X444486Y151677D01*
G01X444494Y151750D02*
X444490Y151746D01*
G01X444478Y148520D02*
X444481Y149807D01*
G01X444475Y147925D02*
X444478Y148520D01*
G01X444471Y147384D02*
X444475Y147925D01*
G01X444466Y146913D02*
X444471Y147384D01*
G01X444460Y146524D02*
X444466Y146913D01*
G01X444454Y146230D02*
X444460Y146524D01*
G01X444447Y146037D02*
X444454Y146230D01*
G01X444382Y144988D02*
X444396Y145050D01*
G01X444374Y145118D02*
X444382Y144988D01*
G01X444368Y145353D02*
X444374Y145118D01*
G01Y140412D02*
X444363Y140138D01*
G01X444379Y140429D02*
X444374Y140412D01*
G01X444384Y140365D02*
X444379Y140429D01*
G01X444372Y141390D02*
X444358Y141024D01*
G01X444380Y141412D02*
X444372Y141390D01*
G01X444387Y141327D02*
X444380Y141412D01*
G01X444451Y139853D02*
X444437Y140340D01*
G01X444457Y139464D02*
X444451Y139853D01*
G01X444462Y138993D02*
X444457Y139464D01*
G01X444466Y138453D02*
X444462Y138993D01*
G01X444469Y137857D02*
X444466Y138453D01*
G01X444471Y137224D02*
X444469Y137857D01*
G01X444472Y136570D02*
X444471Y137224D01*
G01X444477Y134700D02*
X444484Y134627D01*
G01X444473Y134830D02*
X444477Y134700D01*
G01X444470Y135018D02*
X444473Y134830D01*
G01X444467Y135257D02*
X444470Y135018D01*
G01X444464Y135540D02*
X444467Y135257D01*
G01X444462Y135857D02*
X444464Y135540D01*
G01X444461Y136198D02*
X444462Y135857D01*
G01X444461Y136551D02*
Y136198D01*
G01X444445Y139013D02*
X444435Y139379D01*
G01X444450Y138722D02*
X444445Y139013D01*
G01X444453Y138368D02*
X444450Y138722D01*
G01X444456Y137963D02*
X444453Y138368D01*
G01X444459Y137516D02*
X444456Y137963D01*
G01X444460Y137041D02*
X444459Y137516D01*
G01X444461Y136551D02*
X444460Y137041D01*
G01X446091Y140412D02*
X446081Y140365D01*
G01X446097Y140314D02*
X446091Y140412D01*
G01X446102Y140138D02*
X446097Y140314D01*
G01X446006Y137516D02*
X446004Y136551D01*
G01X446009Y137963D02*
X446006Y137516D01*
G01X446012Y138368D02*
X446009Y137963D01*
G01X446015Y138722D02*
X446012Y138368D01*
G01X446020Y139013D02*
X446015Y138722D01*
G01X446025Y139234D02*
X446020Y139013D01*
G01X446030Y139379D02*
X446025Y139234D01*
G01X446003Y135857D02*
X446004Y136551D01*
G01X446001Y135540D02*
X446003Y135857D01*
G01X445998Y135257D02*
X446001Y135540D01*
G01X445995Y135018D02*
X445998Y135257D01*
G01X445992Y134830D02*
X445995Y135018D01*
G01X445988Y134700D02*
X445992Y134830D01*
G01X445985Y134632D02*
X445988Y134700D01*
G01X445981Y134627D02*
X445985Y134632D01*
G01X445996Y137857D02*
X445993Y136570D01*
G01X445999Y138453D02*
X445996Y137857D01*
G01X446003Y138993D02*
X445999Y138453D01*
G01X446008Y139464D02*
X446003Y138993D01*
G01X446014Y139853D02*
X446008Y139464D01*
G01X446021Y140148D02*
X446014Y139853D01*
G01X446028Y140340D02*
X446021Y140148D01*
G01X446093Y141390D02*
X446078Y141327D01*
G01X446100Y141259D02*
X446093Y141390D01*
G01X446107Y141024D02*
X446100Y141259D01*
G01X440441Y145965D02*
X440452Y146012D01*
G01X440436Y146063D02*
X440441Y145965D01*
G01X440431Y146239D02*
X440436Y146063D01*
G01X440526Y148861D02*
X440528Y149826D01*
G01X440524Y148414D02*
X440526Y148861D01*
G01X440521Y148009D02*
X440524Y148414D01*
G01X440517Y147656D02*
X440521Y148009D01*
G01X440513Y147364D02*
X440517Y147656D01*
G01X440508Y147143D02*
X440513Y147364D01*
G01X440503Y146999D02*
X440508Y147143D01*
G01X440537Y148520D02*
X440539Y149807D01*
G01X440534Y147925D02*
X440537Y148520D01*
G01X440529Y147384D02*
X440534Y147925D01*
G01X440524Y146913D02*
X440529Y147384D01*
G01X440518Y146524D02*
X440524Y146913D01*
G01X440512Y146230D02*
X440518Y146524D01*
G01X440505Y146037D02*
X440512Y146230D01*
G01X440440Y144988D02*
X440454Y145050D01*
G01X440433Y145118D02*
X440440Y144988D01*
G01X440426Y145353D02*
X440433Y145118D01*
G01X442159Y145965D02*
X442170Y146239D01*
G01X442154Y145948D02*
X442159Y145965D01*
G01X442148Y146012D02*
X442154Y145948D01*
G01X442160Y144988D02*
X442174Y145353D01*
G01X442153Y144965D02*
X442160Y144988D01*
G01X442146Y145050D02*
X442153Y144965D01*
G01X442082Y146524D02*
X442095Y146037D01*
G01X442076Y146913D02*
X442082Y146524D01*
G01X442071Y147384D02*
X442076Y146913D01*
G01X442067Y147925D02*
X442071Y147384D01*
G01X442064Y148520D02*
X442067Y147925D01*
G01X442062Y149153D02*
X442064Y148520D01*
G01X442061Y149807D02*
X442062Y149153D01*
G01X442088Y147364D02*
X442098Y146999D01*
G01X442083Y147656D02*
X442088Y147364D01*
G01X442079Y148009D02*
X442083Y147656D01*
G01X442076Y148414D02*
X442079Y148009D01*
G01X442074Y148861D02*
X442076Y148414D01*
G01X442072Y149336D02*
X442074Y148861D01*
G01X442072Y149826D02*
Y149336D01*
G01X442159Y140412D02*
X442148Y140365D01*
G01X442164Y140314D02*
X442159Y140412D01*
G01X442170Y140138D02*
X442164Y140314D01*
G01X442074Y137516D02*
X442072Y136551D01*
G01X442076Y137963D02*
X442074Y137516D01*
G01X442079Y138368D02*
X442076Y137963D01*
G01X442083Y138722D02*
X442079Y138368D01*
G01X442088Y139013D02*
X442083Y138722D01*
G01X442093Y139234D02*
X442088Y139013D01*
G01X442098Y139379D02*
X442093Y139234D01*
G01X442064Y137857D02*
X442061Y136570D01*
G01X442067Y138453D02*
X442064Y137857D01*
G01X442071Y138993D02*
X442067Y138453D01*
G01X442076Y139464D02*
X442071Y138993D01*
G01X442082Y139853D02*
X442076Y139464D01*
G01X442088Y140148D02*
X442082Y139853D01*
G01X442095Y140340D02*
X442088Y140148D01*
G01X442160Y141390D02*
X442146Y141327D01*
G01X442168Y141259D02*
X442160Y141390D01*
G01X442174Y141024D02*
X442168Y141259D01*
G01X440441Y140412D02*
X440431Y140138D01*
G01X440447Y140429D02*
X440441Y140412D01*
G01X440452Y140365D02*
X440447Y140429D01*
G01X440440Y141390D02*
X440426Y141024D01*
G01X440447Y141412D02*
X440440Y141390D01*
G01X440454Y141327D02*
X440447Y141412D01*
G01X440518Y139853D02*
X440505Y140340D01*
G01X440524Y139464D02*
X440518Y139853D01*
G01X440529Y138993D02*
X440524Y139464D01*
G01X440534Y138453D02*
X440529Y138993D01*
G01X440537Y137857D02*
X440534Y138453D01*
G01X440539Y137224D02*
X440537Y137857D01*
G01X440539Y136570D02*
Y137224D01*
G01X440513Y139013D02*
X440503Y139379D01*
G01X440517Y138722D02*
X440513Y139013D01*
G01X440521Y138368D02*
X440517Y138722D01*
G01X440524Y137963D02*
X440521Y138368D01*
G01X440526Y137516D02*
X440524Y137963D01*
G01X440528Y137041D02*
X440526Y137516D01*
G01X440528Y136551D02*
Y137041D01*
G01X438227Y145965D02*
X438237Y146239D01*
G01X438221Y145948D02*
X438227Y145965D01*
G01X438216Y146012D02*
X438221Y145948D01*
G01X438228Y144988D02*
X438242Y145353D01*
G01X438221Y144965D02*
X438228Y144988D01*
G01X438214Y145050D02*
X438221Y144965D01*
G01X438150Y146524D02*
X438163Y146037D01*
G01X438144Y146913D02*
X438150Y146524D01*
G01X438139Y147384D02*
X438144Y146913D01*
G01X438134Y147925D02*
X438139Y147384D01*
G01X438131Y148520D02*
X438134Y147925D01*
G01X438129Y149153D02*
X438131Y148520D01*
G01X438129Y149807D02*
Y149153D01*
G01X438124Y151677D02*
X438116Y151750D01*
G01X438127Y151547D02*
X438124Y151677D01*
G01X438131Y151359D02*
X438127Y151547D01*
G01X438134Y151120D02*
X438131Y151359D01*
G01X438136Y150838D02*
X438134Y151120D01*
G01X438138Y150521D02*
X438136Y150838D01*
G01X438139Y150180D02*
X438138Y150521D01*
G01X438140Y149826D02*
X438139Y150180D01*
G01X438155Y147364D02*
X438165Y146999D01*
G01X438151Y147656D02*
X438155Y147364D01*
G01X438147Y148009D02*
X438151Y147656D01*
G01X438144Y148414D02*
X438147Y148009D01*
G01X438142Y148861D02*
X438144Y148414D01*
G01X438140Y149336D02*
X438142Y148861D01*
G01X438140Y149826D02*
Y149336D01*
G01X436509Y145965D02*
X436520Y146012D01*
G01X436504Y146063D02*
X436509Y145965D01*
G01X436498Y146239D02*
X436504Y146063D01*
G01X436594Y148861D02*
X436596Y149826D01*
G01X436592Y148414D02*
X436594Y148861D01*
G01X436589Y148009D02*
X436592Y148414D01*
G01X436585Y147656D02*
X436589Y148009D01*
G01X436580Y147364D02*
X436585Y147656D01*
G01X436575Y147143D02*
X436580Y147364D01*
G01X436570Y146999D02*
X436575Y147143D01*
G01X436598Y150521D02*
X436596Y149826D01*
G01X436600Y150838D02*
X436598Y150521D01*
G01X436602Y151120D02*
X436600Y150838D01*
G01X436605Y151359D02*
X436602Y151120D01*
G01X436608Y151547D02*
X436605Y151359D01*
G01X436612Y151677D02*
X436608Y151547D01*
G01X436616Y151746D02*
X436612Y151677D01*
G01X436620Y151750D02*
X436616Y151746D01*
G01X436604Y148520D02*
X436607Y149807D01*
G01X436601Y147925D02*
X436604Y148520D01*
G01X436597Y147384D02*
X436601Y147925D01*
G01X436592Y146913D02*
X436597Y147384D01*
G01X436586Y146524D02*
X436592Y146913D01*
G01X436580Y146230D02*
X436586Y146524D01*
G01X436573Y146037D02*
X436580Y146230D01*
G01X436508Y144988D02*
X436522Y145050D01*
G01X436500Y145118D02*
X436508Y144988D01*
G01X436494Y145353D02*
X436500Y145118D01*
G01Y140412D02*
X436489Y140138D01*
G01X436505Y140429D02*
X436500Y140412D01*
G01X436510Y140365D02*
X436505Y140429D01*
G01X436498Y141390D02*
X436484Y141024D01*
G01X436506Y141412D02*
X436498Y141390D01*
G01X436513Y141327D02*
X436506Y141412D01*
G01X436577Y139853D02*
X436563Y140340D01*
G01X436583Y139464D02*
X436577Y139853D01*
G01X436588Y138993D02*
X436583Y139464D01*
G01X436592Y138453D02*
X436588Y138993D01*
G01X436595Y137857D02*
X436592Y138453D01*
G01X436597Y137224D02*
X436595Y137857D01*
G01X436598Y136570D02*
X436597Y137224D01*
G01X436603Y134700D02*
X436610Y134627D01*
G01X436599Y134830D02*
X436603Y134700D01*
G01X436596Y135018D02*
X436599Y134830D01*
G01X436593Y135257D02*
X436596Y135018D01*
G01X436590Y135540D02*
X436593Y135257D01*
G01X436588Y135857D02*
X436590Y135540D01*
G01X436587Y136198D02*
X436588Y135857D01*
G01X436587Y136551D02*
Y136198D01*
G01X436571Y139013D02*
X436561Y139379D01*
G01X436575Y138722D02*
X436571Y139013D01*
G01X436579Y138368D02*
X436575Y138722D01*
G01X436582Y137963D02*
X436579Y138368D01*
G01X436585Y137516D02*
X436582Y137963D01*
G01X436586Y137041D02*
X436585Y137516D01*
G01X436587Y136551D02*
X436586Y137041D01*
G01X438217Y140412D02*
X438207Y140365D01*
G01X438223Y140314D02*
X438217Y140412D01*
G01X438228Y140138D02*
X438223Y140314D01*
G01X438132Y137516D02*
X438130Y136551D01*
G01X438135Y137963D02*
X438132Y137516D01*
G01X438138Y138368D02*
X438135Y137963D01*
G01X438141Y138722D02*
X438138Y138368D01*
G01X438146Y139013D02*
X438141Y138722D01*
G01X438151Y139234D02*
X438146Y139013D01*
G01X438156Y139379D02*
X438151Y139234D01*
G01X438129Y135857D02*
X438130Y136551D01*
G01X438127Y135540D02*
X438129Y135857D01*
G01X438124Y135257D02*
X438127Y135540D01*
G01X438121Y135018D02*
X438124Y135257D01*
G01X438118Y134830D02*
X438121Y135018D01*
G01X438114Y134700D02*
X438118Y134830D01*
G01X438111Y134632D02*
X438114Y134700D01*
G01X438107Y134627D02*
X438111Y134632D01*
G01X438122Y137857D02*
X438119Y136570D01*
G01X438125Y138453D02*
X438122Y137857D01*
G01X438129Y138993D02*
X438125Y138453D01*
G01X438134Y139464D02*
X438129Y138993D01*
G01X438140Y139853D02*
X438134Y139464D01*
G01X438147Y140148D02*
X438140Y139853D01*
G01X438154Y140340D02*
X438147Y140148D01*
G01X438219Y141390D02*
X438204Y141327D01*
G01X438226Y141259D02*
X438219Y141390D01*
G01X438233Y141024D02*
X438226Y141259D01*
G01X432567Y145965D02*
X432578Y146012D01*
G01X432562Y146063D02*
X432567Y145965D01*
G01X432557Y146239D02*
X432562Y146063D01*
G01X432652Y148861D02*
X432654Y149826D01*
G01X432650Y148414D02*
X432652Y148861D01*
G01X432647Y148009D02*
X432650Y148414D01*
G01X432643Y147656D02*
X432647Y148009D01*
G01X432639Y147364D02*
X432643Y147656D01*
G01X432634Y147143D02*
X432639Y147364D01*
G01X432629Y146999D02*
X432634Y147143D01*
G01X432663Y148520D02*
X432665Y149807D01*
G01X432660Y147925D02*
X432663Y148520D01*
G01X432655Y147384D02*
X432660Y147925D01*
G01X432650Y146913D02*
X432655Y147384D01*
G01X432644Y146524D02*
X432650Y146913D01*
G01X432638Y146230D02*
X432644Y146524D01*
G01X432631Y146037D02*
X432638Y146230D01*
G01X432566Y144988D02*
X432580Y145050D01*
G01X432559Y145118D02*
X432566Y144988D01*
G01X432552Y145353D02*
X432559Y145118D01*
G01X434285Y145965D02*
X434296Y146239D01*
G01X434280Y145948D02*
X434285Y145965D01*
G01X434274Y146012D02*
X434280Y145948D01*
G01X434286Y144988D02*
X434300Y145353D01*
G01X434279Y144965D02*
X434286Y144988D01*
G01X434272Y145050D02*
X434279Y144965D01*
G01X434208Y146524D02*
X434221Y146037D01*
G01X434202Y146913D02*
X434208Y146524D01*
G01X434197Y147384D02*
X434202Y146913D01*
G01X434193Y147925D02*
X434197Y147384D01*
G01X434190Y148520D02*
X434193Y147925D01*
G01X434188Y149153D02*
X434190Y148520D01*
G01X434187Y149807D02*
X434188Y149153D01*
G01X434214Y147364D02*
X434224Y146999D01*
G01X434209Y147656D02*
X434214Y147364D01*
G01X434205Y148009D02*
X434209Y147656D01*
G01X434202Y148414D02*
X434205Y148009D01*
G01X434200Y148861D02*
X434202Y148414D01*
G01X434198Y149336D02*
X434200Y148861D01*
G01X434198Y149826D02*
Y149336D01*
G01X434285Y140412D02*
X434274Y140365D01*
G01X434290Y140314D02*
X434285Y140412D01*
G01X434296Y140138D02*
X434290Y140314D01*
G01X434200Y137516D02*
X434198Y136551D01*
G01X434202Y137963D02*
X434200Y137516D01*
G01X434205Y138368D02*
X434202Y137963D01*
G01X434209Y138722D02*
X434205Y138368D01*
G01X434214Y139013D02*
X434209Y138722D01*
G01X434218Y139234D02*
X434214Y139013D01*
G01X434224Y139379D02*
X434218Y139234D01*
G01X434190Y137857D02*
X434187Y136570D01*
G01X434193Y138453D02*
X434190Y137857D01*
G01X434197Y138993D02*
X434193Y138453D01*
G01X434202Y139464D02*
X434197Y138993D01*
G01X434208Y139853D02*
X434202Y139464D01*
G01X434214Y140148D02*
X434208Y139853D01*
G01X434221Y140340D02*
X434214Y140148D01*
G01X434286Y141390D02*
X434272Y141327D01*
G01X434294Y141259D02*
X434286Y141390D01*
G01X434300Y141024D02*
X434294Y141259D01*
G01X432567Y140412D02*
X432557Y140138D01*
G01X432573Y140429D02*
X432567Y140412D01*
G01X432578Y140365D02*
X432573Y140429D01*
G01X432566Y141390D02*
X432552Y141024D01*
G01X432573Y141412D02*
X432566Y141390D01*
G01X432580Y141327D02*
X432573Y141412D01*
G01X432644Y139853D02*
X432631Y140340D01*
G01X432650Y139464D02*
X432644Y139853D01*
G01X432655Y138993D02*
X432650Y139464D01*
G01X432660Y138453D02*
X432655Y138993D01*
G01X432663Y137857D02*
X432660Y138453D01*
G01X432665Y137224D02*
X432663Y137857D01*
G01X432665Y136570D02*
Y137224D01*
G01X432639Y139013D02*
X432629Y139379D01*
G01X432643Y138722D02*
X432639Y139013D01*
G01X432647Y138368D02*
X432643Y138722D01*
G01X432650Y137963D02*
X432647Y138368D01*
G01X432652Y137516D02*
X432650Y137963D01*
G01X432654Y137041D02*
X432652Y137516D01*
G01X432654Y136551D02*
Y137041D01*
G01X430353Y145965D02*
X430363Y146239D01*
G01X430347Y145948D02*
X430353Y145965D01*
G01X430342Y146012D02*
X430347Y145948D01*
G01X430354Y144988D02*
X430368Y145353D01*
G01X430347Y144965D02*
X430354Y144988D01*
G01X430340Y145050D02*
X430347Y144965D01*
G01X430276Y146524D02*
X430289Y146037D01*
G01X430270Y146913D02*
X430276Y146524D01*
G01X430265Y147384D02*
X430270Y146913D01*
G01X430260Y147925D02*
X430265Y147384D01*
G01X430257Y148520D02*
X430260Y147925D01*
G01X430255Y149153D02*
X430257Y148520D01*
G01X430255Y149807D02*
Y149153D01*
G01X430250Y151677D02*
X430242Y151750D01*
G01X430253Y151547D02*
X430250Y151677D01*
G01X430257Y151359D02*
X430253Y151547D01*
G01X430260Y151120D02*
X430257Y151359D01*
G01X430262Y150838D02*
X430260Y151120D01*
G01X430264Y150521D02*
X430262Y150838D01*
G01X430265Y150180D02*
X430264Y150521D01*
G01X430265Y149826D02*
Y150180D01*
G01X430281Y147364D02*
X430291Y146999D01*
G01X430277Y147656D02*
X430281Y147364D01*
G01X430273Y148009D02*
X430277Y147656D01*
G01X430270Y148414D02*
X430273Y148009D01*
G01X430268Y148861D02*
X430270Y148414D01*
G01X430266Y149336D02*
X430268Y148861D01*
G01X430265Y149826D02*
X430266Y149336D01*
G01X428635Y145965D02*
X428646Y146012D01*
G01X428630Y146063D02*
X428635Y145965D01*
G01X428624Y146239D02*
X428630Y146063D01*
G01X428720Y148861D02*
X428722Y149826D01*
G01X428718Y148414D02*
X428720Y148861D01*
G01X428715Y148009D02*
X428718Y148414D01*
G01X428711Y147656D02*
X428715Y148009D01*
G01X428706Y147364D02*
X428711Y147656D01*
G01X428701Y147143D02*
X428706Y147364D01*
G01X428696Y146999D02*
X428701Y147143D01*
G01X428724Y150521D02*
X428722Y149826D01*
G01X428726Y150838D02*
X428724Y150521D01*
G01X428728Y151120D02*
X428726Y150838D01*
G01X428731Y151359D02*
X428728Y151120D01*
G01X428734Y151547D02*
X428731Y151359D01*
G01X428738Y151677D02*
X428734Y151547D01*
G01X428742Y151746D02*
X428738Y151677D01*
G01X428746Y151750D02*
X428742Y151746D01*
G01X428730Y148520D02*
X428733Y149807D01*
G01X428727Y147925D02*
X428730Y148520D01*
G01X428723Y147384D02*
X428727Y147925D01*
G01X428718Y146913D02*
X428723Y147384D01*
G01X428712Y146524D02*
X428718Y146913D01*
G01X428706Y146230D02*
X428712Y146524D01*
G01X428699Y146037D02*
X428706Y146230D01*
G01X428634Y144988D02*
X428648Y145050D01*
G01X428626Y145118D02*
X428634Y144988D01*
G01X428620Y145353D02*
X428626Y145118D01*
G01Y140412D02*
X428615Y140138D01*
G01X428631Y140429D02*
X428626Y140412D01*
G01X428636Y140365D02*
X428631Y140429D01*
G01X428624Y141390D02*
X428610Y141024D01*
G01X428632Y141412D02*
X428624Y141390D01*
G01X428639Y141327D02*
X428632Y141412D01*
G01X428703Y139853D02*
X428689Y140340D01*
G01X428709Y139464D02*
X428703Y139853D01*
G01X428714Y138993D02*
X428709Y139464D01*
G01X428718Y138453D02*
X428714Y138993D01*
G01X428721Y137857D02*
X428718Y138453D01*
G01X428723Y137224D02*
X428721Y137857D01*
G01X428724Y136570D02*
X428723Y137224D01*
G01X428729Y134700D02*
X428736Y134627D01*
G01X428725Y134830D02*
X428729Y134700D01*
G01X428722Y135018D02*
X428725Y134830D01*
G01X428719Y135257D02*
X428722Y135018D01*
G01X428716Y135540D02*
X428719Y135257D01*
G01X428714Y135857D02*
X428716Y135540D01*
G01X428713Y136198D02*
X428714Y135857D01*
G01X428713Y136551D02*
Y136198D01*
G01X428697Y139013D02*
X428687Y139379D01*
G01X428701Y138722D02*
X428697Y139013D01*
G01X428705Y138368D02*
X428701Y138722D01*
G01X428708Y137963D02*
X428705Y138368D01*
G01X428711Y137516D02*
X428708Y137963D01*
G01X428712Y137041D02*
X428711Y137516D01*
G01X428713Y136551D02*
X428712Y137041D01*
G01X430343Y140412D02*
X430333Y140365D01*
G01X430349Y140314D02*
X430343Y140412D01*
G01X430354Y140138D02*
X430349Y140314D01*
G01X430258Y137516D02*
X430256Y136551D01*
G01X430261Y137963D02*
X430258Y137516D01*
G01X430264Y138368D02*
X430261Y137963D01*
G01X430267Y138722D02*
X430264Y138368D01*
G01X430272Y139013D02*
X430267Y138722D01*
G01X430277Y139234D02*
X430272Y139013D01*
G01X430282Y139379D02*
X430277Y139234D01*
G01X430255Y135857D02*
X430256Y136551D01*
G01X430253Y135540D02*
X430255Y135857D01*
G01X430250Y135257D02*
X430253Y135540D01*
G01X430247Y135018D02*
X430250Y135257D01*
G01X430244Y134830D02*
X430247Y135018D01*
G01X430240Y134700D02*
X430244Y134830D01*
G01X430236Y134632D02*
X430240Y134700D01*
G01X430233Y134627D02*
X430236Y134632D01*
G01X430248Y137857D02*
X430245Y136570D01*
G01X430251Y138453D02*
X430248Y137857D01*
G01X430255Y138993D02*
X430251Y138453D01*
G01X430260Y139464D02*
X430255Y138993D01*
G01X430266Y139853D02*
X430260Y139464D01*
G01X430273Y140148D02*
X430266Y139853D01*
G01X430280Y140340D02*
X430273Y140148D01*
G01X430345Y141390D02*
X430330Y141327D01*
G01X430352Y141259D02*
X430345Y141390D01*
G01X430359Y141024D02*
X430352Y141259D01*
G01X434175Y151754D02*
X434174Y151750D01*
G01X434175Y151756D02*
Y151754D01*
G01X434176Y151756D02*
X434175D01*
G01X442049Y151754D02*
X442048Y151750D01*
G01X442049Y151756D02*
Y151754D01*
G01X442050Y151756D02*
X442049D01*
G01X432678Y134624D02*
Y134627D01*
G01X432677Y134622D02*
X432678Y134624D01*
G01X432676Y134621D02*
X432677Y134622D01*
G01X449923Y151754D02*
X449922Y151750D01*
G01X449923Y151756D02*
Y151754D01*
G01X449924Y151756D02*
X449923D01*
G01X448121Y134823D02*
X448106Y134822D01*
G01X448136Y134823D02*
X448121D01*
G01X448151Y134824D02*
X448136Y134823D01*
G01X444179D02*
X444164Y134822D01*
G01X444194Y134823D02*
X444179D01*
G01X444209Y134824D02*
X444194Y134823D01*
G01X440247D02*
X440232Y134822D01*
G01X440262Y134823D02*
X440247D01*
G01X440277Y134824D02*
X440262Y134823D01*
G01X436305D02*
X436290Y134822D01*
G01X436320Y134823D02*
X436305D01*
G01X436335Y134824D02*
X436320Y134823D01*
G01X432373D02*
X432358Y134822D01*
G01X432388Y134823D02*
X432373D01*
G01X432403Y134824D02*
X432388Y134823D01*
G01X428431D02*
X428416Y134822D01*
G01X428446Y134823D02*
X428431D01*
G01X428461Y134824D02*
X428446Y134823D01*
G01X448121Y133838D02*
X448106D01*
G01X448136Y133839D02*
X448121Y133838D01*
G01X448151Y133840D02*
X448136Y133839D01*
G01X444179Y133838D02*
X444164D01*
G01X444194Y133839D02*
X444179Y133838D01*
G01X444209Y133840D02*
X444194Y133839D01*
G01X440247Y133838D02*
X440232D01*
G01X440262Y133839D02*
X440247Y133838D01*
G01X440277Y133840D02*
X440262Y133839D01*
G01X436305Y133838D02*
X436290D01*
G01X436320Y133839D02*
X436305Y133838D01*
G01X436335Y133840D02*
X436320Y133839D01*
G01X432373Y133838D02*
X432358D01*
G01X432388Y133839D02*
X432373Y133838D01*
G01X432403Y133840D02*
X432388Y133839D01*
G01X428431Y133838D02*
X428416D01*
G01X428446Y133839D02*
X428431Y133838D01*
G01X428461Y133840D02*
X428446Y133839D01*
G01X430523D02*
X430508Y133840D01*
G01X430538Y133838D02*
X430523Y133839D01*
G01X430553Y133838D02*
X430538D01*
G01X434465Y133839D02*
X434450Y133840D01*
G01X434480Y133838D02*
X434465Y133839D01*
G01X434495Y133838D02*
X434480D01*
G01X438397Y133839D02*
X438382Y133840D01*
G01X438412Y133838D02*
X438397Y133839D01*
G01X438427Y133838D02*
X438412D01*
G01X442339Y133839D02*
X442324Y133840D01*
G01X442354Y133838D02*
X442339Y133839D01*
G01X442369Y133838D02*
X442354D01*
G01X446271Y133839D02*
X446256Y133840D01*
G01X446286Y133838D02*
X446271Y133839D01*
G01X446301Y133838D02*
X446286D01*
G01X450213Y133839D02*
X450198Y133840D01*
G01X450228Y133838D02*
X450213Y133839D01*
G01X450243Y133838D02*
X450228D01*
G01X430523Y134823D02*
X430508Y134824D01*
G01X430538Y134823D02*
X430523D01*
G01X430553Y134822D02*
X430538Y134823D01*
G01X434465D02*
X434450Y134824D01*
G01X434480Y134823D02*
X434465D01*
G01X434495Y134822D02*
X434480Y134823D01*
G01X438397D02*
X438382Y134824D01*
G01X438412Y134823D02*
X438397D01*
G01X438427Y134822D02*
X438412Y134823D01*
G01X442339D02*
X442324Y134824D01*
G01X442354Y134823D02*
X442339D01*
G01X442369Y134822D02*
X442354Y134823D01*
G01X446271D02*
X446256Y134824D01*
G01X446286Y134823D02*
X446271D01*
G01X446301Y134822D02*
X446286Y134823D01*
G01X434175Y150768D02*
X434174Y150762D01*
G01X434175Y150771D02*
Y150768D01*
G01X434176Y150772D02*
X434175Y150771D01*
G01X432677Y135610D02*
X432678Y135615D01*
G01X432677Y135606D02*
Y135610D01*
G01X432676Y135605D02*
X432677Y135606D01*
G01X442049Y150768D02*
X442048Y150762D01*
G01X442049Y150771D02*
Y150768D01*
G01X442050Y150772D02*
X442049Y150771D01*
G01X440552Y134624D02*
Y134627D01*
G01X440551Y134622D02*
X440552Y134624D01*
G01X440550Y134621D02*
X440551Y134622D01*
G01X448426Y134624D02*
Y134627D01*
G01X448425Y134622D02*
X448426Y134624D01*
G01X448424Y134621D02*
X448425Y134622D01*
G01X450228Y151555D02*
X450243D01*
G01X450213Y151554D02*
X450228Y151555D01*
G01X450198Y151553D02*
X450213Y151554D01*
G01X442354Y151555D02*
X442369D01*
G01X442339Y151554D02*
X442354Y151555D01*
G01X442324Y151553D02*
X442339Y151554D01*
G01X434480Y151555D02*
X434495D01*
G01X434465Y151554D02*
X434480Y151555D01*
G01X434450Y151553D02*
X434465Y151554D01*
G01X430547Y151555D02*
X430562D01*
G01X430532Y151554D02*
X430547Y151555D01*
G01X430517Y151553D02*
X430532Y151554D01*
G01X450228Y152539D02*
X450243D01*
G01X450213Y152538D02*
X450228Y152539D01*
G01X450198Y152538D02*
X450213D01*
G01X446295Y152539D02*
X446311D01*
G01X446280Y152538D02*
X446295Y152539D01*
G01X446265Y152538D02*
X446280D01*
G01X442354Y152539D02*
X442369D01*
G01X442339Y152538D02*
X442354Y152539D01*
G01X442324Y152538D02*
X442339D01*
G01X438421Y152539D02*
X438436D01*
G01X438406Y152538D02*
X438421Y152539D01*
G01X438391Y152538D02*
X438406D01*
G01X434480Y152539D02*
X434495D01*
G01X434465Y152538D02*
X434480Y152539D01*
G01X434450Y152538D02*
X434465D01*
G01X430547Y152539D02*
X430562D01*
G01X430532Y152538D02*
X430547Y152539D01*
G01X430517Y152538D02*
X430532D01*
G01X428455D02*
X428470D01*
G01X428440Y152539D02*
X428455Y152538D01*
G01X428425Y152539D02*
X428440D01*
G01X432388Y152538D02*
X432403D01*
G01X432373Y152539D02*
X432388Y152538D01*
G01X432358Y152539D02*
X432373D01*
G01X436329Y152538D02*
X436344D01*
G01X436314Y152539D02*
X436329Y152538D01*
G01X436299Y152539D02*
X436314D01*
G01X440262Y152538D02*
X440277D01*
G01X440247Y152539D02*
X440262Y152538D01*
G01X440232Y152539D02*
X440247D01*
G01X444203Y152538D02*
X444218D01*
G01X444188Y152539D02*
X444203Y152538D01*
G01X444173Y152539D02*
X444188D01*
G01X448136Y152538D02*
X448151D01*
G01X448121Y152539D02*
X448136Y152538D01*
G01X448106Y152539D02*
X448121D01*
G01X432388Y151554D02*
X432403Y151553D01*
G01X432373Y151555D02*
X432388Y151554D01*
G01X432358Y151555D02*
X432373D01*
G01X436329Y151554D02*
X436344Y151553D01*
G01X436314Y151555D02*
X436329Y151554D01*
G01X436299Y151555D02*
X436314D01*
G01X440262Y151554D02*
X440277Y151553D01*
G01X440247Y151555D02*
X440262Y151554D01*
G01X440232Y151555D02*
X440247D01*
G01X444203Y151554D02*
X444218Y151553D01*
G01X444188Y151555D02*
X444203Y151554D01*
G01X444173Y151555D02*
X444188D01*
G01X448136Y151554D02*
X448151Y151553D01*
G01X448121Y151555D02*
X448136Y151554D01*
G01X448106Y151555D02*
X448121D01*
G01X450228Y134823D02*
X450243Y134822D01*
G01X450213Y134823D02*
X450228D01*
G01X450198Y134824D02*
X450213Y134823D01*
G01X428440Y151555D02*
X428425D01*
G01X428455Y151554D02*
X428440Y151555D01*
G01X428470Y151553D02*
X428455Y151554D01*
G01X428470Y134965D02*
X428474Y135117D01*
G01X428465Y134866D02*
X428470Y134965D01*
G01X428461Y134824D02*
X428465Y134866D01*
G01X430508Y151413D02*
X430504Y151260D01*
G01X430513Y151511D02*
X430508Y151413D01*
G01X430517Y151553D02*
X430513Y151511D01*
G01X432412Y134965D02*
X432416Y135117D01*
G01X432407Y134866D02*
X432412Y134965D01*
G01X432403Y134824D02*
X432407Y134866D01*
G01X434441Y151413D02*
X434437Y151260D01*
G01X434445Y151511D02*
X434441Y151413D01*
G01X434450Y151553D02*
X434445Y151511D01*
G01X430505Y152353D02*
X430499Y152147D01*
G01X430511Y152484D02*
X430505Y152353D01*
G01X430517Y152538D02*
X430511Y152484D01*
G01X428473Y134024D02*
X428479Y134231D01*
G01X428467Y133893D02*
X428473Y134024D01*
G01X428461Y133840D02*
X428467Y133893D01*
G01X434438Y152353D02*
X434432Y152147D01*
G01X434444Y152484D02*
X434438Y152353D01*
G01X434450Y152538D02*
X434444Y152484D01*
G01X432415Y134024D02*
X432421Y134231D01*
G01X432409Y133893D02*
X432415Y134024D01*
G01X432403Y133840D02*
X432409Y133893D01*
G01X428734Y150209D02*
X428733Y149807D01*
G01X428737Y150537D02*
X428734Y150209D01*
G01X428741Y150733D02*
X428737Y150537D01*
G01X428746Y150762D02*
X428741Y150733D01*
G01X430244Y136168D02*
X430245Y136570D01*
G01X430241Y135841D02*
X430244Y136168D01*
G01X430237Y135645D02*
X430241Y135841D01*
G01X430233Y135615D02*
X430237Y135645D01*
G01X436608Y150209D02*
X436607Y149807D01*
G01X436611Y150537D02*
X436608Y150209D01*
G01X436615Y150733D02*
X436611Y150537D01*
G01X436620Y150762D02*
X436615Y150733D01*
G01X440551Y135610D02*
X440552Y135615D01*
G01X440551Y135606D02*
Y135610D01*
G01X440550Y135605D02*
X440551Y135606D01*
G01X449923Y150768D02*
X449922Y150762D01*
G01X449923Y150771D02*
Y150768D01*
G01X449924Y150772D02*
X449923Y150771D01*
G01X448425Y135610D02*
X448426Y135615D01*
G01X448425Y135606D02*
Y135610D01*
G01X448424Y135605D02*
X448425Y135606D01*
G01X432677Y150771D02*
X432676Y150772D01*
G01X432677Y150768D02*
Y150771D01*
G01X432678Y150762D02*
X432677Y150768D01*
G01X434175Y135606D02*
X434176Y135605D01*
G01X434175Y135610D02*
Y135606D01*
G01X434174Y135615D02*
X434175Y135610D01*
G01X440551Y150771D02*
X440550Y150772D01*
G01X440551Y150768D02*
Y150771D01*
G01X440552Y150762D02*
X440551Y150768D01*
G01X442049Y135606D02*
X442050Y135605D01*
G01X442049Y135610D02*
Y135606D01*
G01X442048Y135615D02*
X442049Y135610D01*
G01X428476Y152484D02*
X428470Y152538D01*
G01X428482Y152353D02*
X428476Y152484D01*
G01X428488Y152147D02*
X428482Y152353D01*
G01X430502Y133893D02*
X430508Y133840D01*
G01X430496Y134024D02*
X430502Y133893D01*
G01X430490Y134231D02*
X430496Y134024D01*
G01X432409Y152484D02*
X432403Y152538D01*
G01X432415Y152353D02*
X432409Y152484D01*
G01X432421Y152147D02*
X432415Y152353D01*
G01X434444Y133893D02*
X434450Y133840D01*
G01X434438Y134024D02*
X434444Y133893D01*
G01X434432Y134231D02*
X434438Y134024D01*
G01X436350Y152484D02*
X436344Y152538D01*
G01X436356Y152353D02*
X436350Y152484D01*
G01X436362Y152147D02*
X436356Y152353D01*
G01X438376Y133893D02*
X438382Y133840D01*
G01X438370Y134024D02*
X438376Y133893D01*
G01X438364Y134231D02*
X438370Y134024D01*
G01X440283Y152484D02*
X440277Y152538D01*
G01X440289Y152353D02*
X440283Y152484D01*
G01X440295Y152147D02*
X440289Y152353D01*
G01X442318Y133893D02*
X442324Y133840D01*
G01X442312Y134024D02*
X442318Y133893D01*
G01X442306Y134231D02*
X442312Y134024D01*
G01X444224Y152484D02*
X444218Y152538D01*
G01X444230Y152353D02*
X444224Y152484D01*
G01X444236Y152147D02*
X444230Y152353D01*
G01X446250Y133893D02*
X446256Y133840D01*
G01X446244Y134024D02*
X446250Y133893D01*
G01X446238Y134231D02*
X446244Y134024D01*
G01X448157Y152484D02*
X448151Y152538D01*
G01X448163Y152353D02*
X448157Y152484D01*
G01X448169Y152147D02*
X448163Y152353D01*
G01X450192Y133893D02*
X450198Y133840D01*
G01X450186Y134024D02*
X450192Y133893D01*
G01X450180Y134231D02*
X450186Y134024D01*
G01X428475Y151511D02*
X428470Y151553D01*
G01X428479Y151413D02*
X428475Y151511D01*
G01X428483Y151260D02*
X428479Y151413D01*
G01X430504Y134866D02*
X430508Y134824D01*
G01X430499Y134965D02*
X430504Y134866D01*
G01X430495Y135117D02*
X430499Y134965D01*
G01X432407Y151511D02*
X432403Y151553D01*
G01X432412Y151413D02*
X432407Y151511D01*
G01X432416Y151260D02*
X432412Y151413D01*
G01X434445Y134866D02*
X434450Y134824D01*
G01X434441Y134965D02*
X434445Y134866D01*
G01X434437Y135117D02*
X434441Y134965D01*
G01X436349Y151511D02*
X436344Y151553D01*
G01X436353Y151413D02*
X436349Y151511D01*
G01X436357Y151260D02*
X436353Y151413D01*
G01X438378Y134866D02*
X438382Y134824D01*
G01X438373Y134965D02*
X438378Y134866D01*
G01X438369Y135117D02*
X438373Y134965D01*
G01X440281Y151511D02*
X440277Y151553D01*
G01X440286Y151413D02*
X440281Y151511D01*
G01X440290Y151260D02*
X440286Y151413D01*
G01X442319Y134866D02*
X442324Y134824D01*
G01X442315Y134965D02*
X442319Y134866D01*
G01X442311Y135117D02*
X442315Y134965D01*
G01X444223Y151511D02*
X444218Y151553D01*
G01X444227Y151413D02*
X444223Y151511D01*
G01X444231Y151260D02*
X444227Y151413D01*
G01X446252Y134866D02*
X446256Y134824D01*
G01X446247Y134965D02*
X446252Y134866D01*
G01X446243Y135117D02*
X446247Y134965D01*
G01X448155Y151511D02*
X448151Y151553D01*
G01X448160Y151413D02*
X448155Y151511D01*
G01X448164Y151260D02*
X448160Y151413D01*
G01X450193Y134866D02*
X450198Y134824D01*
G01X450189Y134965D02*
X450193Y134866D01*
G01X450185Y135117D02*
X450189Y134965D01*
G01X428732Y135645D02*
X428736Y135615D01*
G01X428728Y135841D02*
X428732Y135645D01*
G01X428725Y136168D02*
X428728Y135841D01*
G01X428724Y136570D02*
X428725Y136168D01*
G01X430247Y150733D02*
X430242Y150762D01*
G01X430251Y150537D02*
X430247Y150733D01*
G01X430253Y150209D02*
X430251Y150537D01*
G01X430255Y149807D02*
X430253Y150209D01*
G01X436606Y135645D02*
X436610Y135615D01*
G01X436602Y135841D02*
X436606Y135645D01*
G01X436599Y136168D02*
X436602Y135841D01*
G01X436598Y136570D02*
X436599Y136168D01*
G01X438121Y150733D02*
X438116Y150762D01*
G01X438125Y150537D02*
X438121Y150733D01*
G01X438127Y150209D02*
X438125Y150537D01*
G01X438129Y149807D02*
X438127Y150209D01*
G01X444480Y135645D02*
X444484Y135615D01*
G01X444476Y135841D02*
X444480Y135645D01*
G01X444473Y136168D02*
X444476Y135841D01*
G01X444472Y136570D02*
X444473Y136168D01*
G01X445995Y150733D02*
X445990Y150762D01*
G01X445999Y150537D02*
X445995Y150733D01*
G01X446002Y150209D02*
X445999Y150537D01*
G01X446003Y149807D02*
X446002Y150209D01*
G01X432668Y134770D02*
X432676Y134621D01*
G01X432661Y135184D02*
X432668Y134770D01*
G01X432656Y135804D02*
X432661Y135184D01*
G01X432654Y136551D02*
X432656Y135804D01*
G01X432672Y135678D02*
X432676Y135605D01*
G01X432669Y135887D02*
X432672Y135678D01*
G01X432666Y136200D02*
X432669Y135887D01*
G01X432665Y136570D02*
X432666Y136200D01*
G01X434180Y150699D02*
X434176Y150772D01*
G01X434184Y150490D02*
X434180Y150699D01*
G01X434186Y150178D02*
X434184Y150490D01*
G01X434187Y149807D02*
X434186Y150178D01*
G01X434184Y151608D02*
X434176Y151756D01*
G01X434191Y151193D02*
X434184Y151608D01*
G01X434196Y150573D02*
X434191Y151193D01*
G01X434198Y149826D02*
X434196Y150573D01*
G01X440542Y134770D02*
X440550Y134621D01*
G01X440535Y135184D02*
X440542Y134770D01*
G01X440530Y135804D02*
X440535Y135184D01*
G01X440528Y136551D02*
X440530Y135804D01*
G01X440546Y135678D02*
X440550Y135605D01*
G01X440543Y135887D02*
X440546Y135678D01*
G01X440540Y136200D02*
X440543Y135887D01*
G01X440539Y136570D02*
X440540Y136200D01*
G01X442054Y150699D02*
X442050Y150772D01*
G01X442058Y150490D02*
X442054Y150699D01*
G01X442060Y150178D02*
X442058Y150490D01*
G01X442061Y149807D02*
X442060Y150178D01*
G01X442058Y151608D02*
X442050Y151756D01*
G01X442065Y151193D02*
X442058Y151608D01*
G01X442070Y150573D02*
X442065Y151193D01*
G01X442072Y149826D02*
X442070Y150573D01*
G01X448416Y134770D02*
X448424Y134621D01*
G01X448409Y135184D02*
X448416Y134770D01*
G01X448404Y135804D02*
X448409Y135184D01*
G01X448403Y136551D02*
X448404Y135804D01*
G01X448420Y135678D02*
X448424Y135605D01*
G01X448417Y135887D02*
X448420Y135678D01*
G01X448414Y136200D02*
X448417Y135887D01*
G01X448413Y136570D02*
X448414Y136200D01*
G01X449928Y150699D02*
X449924Y150772D01*
G01X449932Y150490D02*
X449928Y150699D01*
G01X449934Y150178D02*
X449932Y150490D01*
G01X449935Y149807D02*
X449934Y150178D01*
G01X449932Y151608D02*
X449924Y151756D01*
G01X449939Y151193D02*
X449932Y151608D01*
G01X449944Y150573D02*
X449939Y151193D01*
G01X449946Y149826D02*
X449944Y150573D01*
G01X432656D02*
X432654Y149826D01*
G01X432661Y151193D02*
X432656Y150573D01*
G01X432668Y151608D02*
X432661Y151193D01*
G01X432676Y151756D02*
X432668Y151608D01*
G01X434196Y135804D02*
X434198Y136551D01*
G01X434191Y135184D02*
X434196Y135804D01*
G01X434184Y134770D02*
X434191Y135184D01*
G01X434176Y134621D02*
X434184Y134770D01*
G01X440530Y150573D02*
X440528Y149826D01*
G01X440535Y151193D02*
X440530Y150573D01*
G01X440542Y151608D02*
X440535Y151193D01*
G01X440550Y151756D02*
X440542Y151608D01*
G01X442070Y135804D02*
X442072Y136551D01*
G01X442065Y135184D02*
X442070Y135804D01*
G01X442058Y134770D02*
X442065Y135184D01*
G01X442050Y134621D02*
X442058Y134770D01*
G01X448404Y150573D02*
X448403Y149826D01*
G01X448409Y151193D02*
X448404Y150573D01*
G01X448416Y151608D02*
X448409Y151193D01*
G01X448424Y151756D02*
X448416Y151608D01*
G01X449944Y135804D02*
X449946Y136551D01*
G01X449939Y135184D02*
X449944Y135804D01*
G01X449932Y134770D02*
X449939Y135184D01*
G01X449924Y134621D02*
X449932Y134770D01*
G01X432666Y150178D02*
X432665Y149807D01*
G01X432669Y150490D02*
X432666Y150178D01*
G01X432672Y150699D02*
X432669Y150490D01*
G01X432676Y150772D02*
X432672Y150699D01*
G01X434186Y136200D02*
X434187Y136570D01*
G01X434184Y135887D02*
X434186Y136200D01*
G01X434180Y135678D02*
X434184Y135887D01*
G01X434176Y135605D02*
X434180Y135678D01*
G01X440540Y150178D02*
X440539Y149807D01*
G01X440543Y150490D02*
X440540Y150178D01*
G01X440546Y150699D02*
X440543Y150490D01*
G01X440550Y150772D02*
X440546Y150699D01*
G01X442060Y136200D02*
X442061Y136570D01*
G01X442058Y135887D02*
X442060Y136200D01*
G01X442054Y135678D02*
X442058Y135887D01*
G01X442050Y135605D02*
X442054Y135678D01*
G01X448414Y150178D02*
X448413Y149807D01*
G01X448417Y150490D02*
X448414Y150178D01*
G01X448420Y150699D02*
X448417Y150490D01*
G01X448424Y150772D02*
X448420Y150699D01*
G01X449934Y136200D02*
X449935Y136570D01*
G01X449932Y135887D02*
X449934Y136200D01*
G01X449928Y135678D02*
X449932Y135887D01*
G01X449924Y135605D02*
X449928Y135678D01*
G01X436344Y134965D02*
X436348Y135117D01*
G01X436339Y134866D02*
X436344Y134965D01*
G01X436335Y134824D02*
X436339Y134866D01*
G01X438382Y151413D02*
X438378Y151260D01*
G01X438387Y151511D02*
X438382Y151413D01*
G01X438391Y151553D02*
X438387Y151511D01*
G01X440286Y134965D02*
X440290Y135117D01*
G01X440281Y134866D02*
X440286Y134965D01*
G01X440277Y134824D02*
X440281Y134866D01*
G01X442315Y151413D02*
X442311Y151260D01*
G01X442319Y151511D02*
X442315Y151413D01*
G01X442324Y151553D02*
X442319Y151511D01*
G01X444218Y134965D02*
X444222Y135117D01*
G01X444213Y134866D02*
X444218Y134965D01*
G01X444209Y134824D02*
X444213Y134866D01*
G01X446257Y151413D02*
X446252Y151260D01*
G01X446261Y151511D02*
X446257Y151413D01*
G01X446265Y151553D02*
X446261Y151511D01*
G01X448160Y134965D02*
X448164Y135117D01*
G01X448155Y134866D02*
X448160Y134965D01*
G01X448151Y134824D02*
X448155Y134866D01*
G01X450189Y151413D02*
X450185Y151260D01*
G01X450193Y151511D02*
X450189Y151413D01*
G01X450198Y151553D02*
X450193Y151511D01*
G01X438379Y152353D02*
X438373Y152147D01*
G01X438385Y152484D02*
X438379Y152353D01*
G01X438391Y152538D02*
X438385Y152484D01*
G01X436347Y134024D02*
X436353Y134231D01*
G01X436341Y133893D02*
X436347Y134024D01*
G01X436335Y133840D02*
X436341Y133893D01*
G01X442312Y152353D02*
X442306Y152147D01*
G01X442318Y152484D02*
X442312Y152353D01*
G01X442324Y152538D02*
X442318Y152484D01*
G01X440289Y134024D02*
X440295Y134231D01*
G01X440283Y133893D02*
X440289Y134024D01*
G01X440277Y133840D02*
X440283Y133893D01*
G01X446253Y152353D02*
X446247Y152147D01*
G01X446259Y152484D02*
X446253Y152353D01*
G01X446265Y152538D02*
X446259Y152484D01*
G01X444221Y134024D02*
X444227Y134231D01*
G01X444215Y133893D02*
X444221Y134024D01*
G01X444209Y133840D02*
X444215Y133893D01*
G01X450186Y152353D02*
X450180Y152147D01*
G01X450192Y152484D02*
X450186Y152353D01*
G01X450198Y152538D02*
X450192Y152484D01*
G01X448163Y134024D02*
X448169Y134231D01*
G01X448157Y133893D02*
X448163Y134024D01*
G01X448151Y133840D02*
X448157Y133893D01*
G01X438118Y136168D02*
X438119Y136570D01*
G01X438115Y135841D02*
X438118Y136168D01*
G01X438111Y135645D02*
X438115Y135841D01*
G01X438107Y135615D02*
X438111Y135645D01*
G01X444482Y150209D02*
X444481Y149807D01*
G01X444485Y150537D02*
X444482Y150209D01*
G01X444489Y150733D02*
X444485Y150537D01*
G01X444494Y150762D02*
X444489Y150733D01*
G01X445992Y136168D02*
X445993Y136570D01*
G01X445989Y135841D02*
X445992Y136168D01*
G01X445985Y135645D02*
X445989Y135841D01*
G01X445981Y135615D02*
X445985Y135645D01*
G01X434175Y134622D02*
X434176Y134621D01*
G01X434175Y134624D02*
Y134622D01*
G01X434174Y134627D02*
X434175Y134624D01*
G01X432677Y151756D02*
X432676D01*
G01X432678Y151754D02*
X432677Y151756D01*
G01X432678Y151750D02*
Y151754D01*
G01X442049Y134622D02*
X442050Y134621D01*
G01X442049Y134624D02*
Y134622D01*
G01X442048Y134627D02*
X442049Y134624D01*
G01X440551Y151756D02*
X440550D01*
G01X440552Y151754D02*
X440551Y151756D01*
G01X440552Y151750D02*
Y151754D01*
G01X448425Y150771D02*
X448424Y150772D01*
G01X448425Y150768D02*
Y150771D01*
G01X448426Y150762D02*
X448425Y150768D01*
G01X449923Y135606D02*
X449924Y135605D01*
G01X449923Y135610D02*
Y135606D01*
G01X449922Y135615D02*
X449923Y135610D01*
G01Y134622D02*
X449924Y134621D01*
G01X449923Y134624D02*
Y134622D01*
G01X449922Y134627D02*
X449923Y134624D01*
G01X448425Y151756D02*
X448424D01*
G01X448426Y151754D02*
X448425Y151756D01*
G01X448426Y151750D02*
Y151754D01*
G01X430221Y134640D02*
X430233Y134627D01*
G01X428736D02*
X428748Y134640D01*
G01X430316Y138680D02*
X430158Y138717D01*
G01X428820D02*
X428662Y138680D01*
G01X430316Y137621D02*
X430158Y137696D01*
G01X428820D02*
X428662Y137621D01*
G01Y147698D02*
X428820Y147660D01*
G01X430158D02*
X430316Y147698D01*
G01X428662Y148756D02*
X428820Y148681D01*
G01X430158D02*
X430316Y148756D01*
G01X428757Y151737D02*
X428746Y151750D01*
G01X430242D02*
X430230Y151737D01*
G01X432599Y129981D02*
X432757Y129943D01*
G01X434095D02*
X434253Y129981D01*
G01X432599Y131039D02*
X432757Y130965D01*
G01X434095D02*
X434253Y131039D01*
G01X432678Y134627D02*
X432690Y134640D01*
G01X434163D02*
X434174Y134627D01*
G01X434253Y156396D02*
X434095Y156434D01*
G01X432757D02*
X432599Y156396D01*
G01X434253Y155338D02*
X434095Y155412D01*
G01X432757D02*
X432599Y155338D01*
G01X432690Y151737D02*
X432678Y151750D01*
G01X434174D02*
X434163Y151737D01*
G01X438095Y134640D02*
X438107Y134627D01*
G01X436610D02*
X436622Y134640D01*
G01X438190Y138680D02*
X438032Y138717D01*
G01X436694D02*
X436536Y138680D01*
G01X438190Y137621D02*
X438032Y137696D01*
G01X436694D02*
X436536Y137621D01*
G01Y147698D02*
X436694Y147660D01*
G01X436536Y148756D02*
X436694Y148681D01*
G01X438032D02*
X438190Y148756D01*
G01X438032Y147660D02*
X438190Y147698D01*
G01X438436Y151555D02*
X438391Y151553D01*
G01X436631Y151737D02*
X436620Y151750D01*
G01X438116D02*
X438104Y151737D01*
G01X440473Y129981D02*
X440631Y129943D01*
G01X441969D02*
X442127Y129981D01*
G01X440473Y131039D02*
X440631Y130965D01*
G01X441969D02*
X442127Y131039D01*
G01X440552Y134627D02*
X440564Y134640D01*
G01X442037D02*
X442048Y134627D01*
G01X442127Y156396D02*
X441969Y156434D01*
G01X440631D02*
X440473Y156396D01*
G01X442127Y155338D02*
X441969Y155412D01*
G01X440631D02*
X440473Y155338D01*
G01X440564Y151737D02*
X440552Y151750D01*
G01X442048D02*
X442037Y151737D01*
G01X445969Y134640D02*
X445981Y134627D01*
G01X444484D02*
X444496Y134640D01*
G01X446064Y138680D02*
X445906Y138717D01*
G01X444568D02*
X444410Y138680D01*
G01X446064Y137621D02*
X445906Y137696D01*
G01X444568D02*
X444410Y137621D01*
G01Y147698D02*
X444568Y147660D01*
G01X444410Y148756D02*
X444568Y148681D01*
G01X445906D02*
X446064Y148756D01*
G01X445906Y147660D02*
X446064Y147698D01*
G01X446311Y151555D02*
X446265Y151553D01*
G01X444505Y151737D02*
X444494Y151750D01*
G01X445990D02*
X445978Y151737D01*
G01X448347Y129981D02*
X448505Y129943D01*
G01X449843D02*
X450001Y129981D01*
G01X448347Y131039D02*
X448505Y130965D01*
G01X449843D02*
X450001Y131039D01*
G01X449911Y134640D02*
X449922Y134627D01*
G01X448426D02*
X448438Y134640D01*
G01X450001Y156396D02*
X449843Y156434D01*
G01X448505D02*
X448347Y156396D01*
G01X450001Y155338D02*
X449843Y155412D01*
G01X448505D02*
X448347Y155338D01*
G01X448438Y151737D02*
X448426Y151750D01*
G01X449922D02*
X449911Y151737D01*
G01X459391Y143189D02*
G03I-3130J0D01*
G01X460493D02*
G03I-4232J0D01*
G01X460887D02*
G03I-4626J0D01*
G01X448646Y150441D02*
X448655Y150393D01*
G01X449702Y135937D02*
X449693Y135984D01*
G01X444714Y150441D02*
X444723Y150393D01*
G01X445761Y135937D02*
X445751Y135984D01*
G01X454618Y139645D02*
X456576Y136693D01*
G01X448438Y151737D02*
X448692Y151368D01*
G01X448646Y150441D02*
X448425Y150762D01*
G01X444505Y151737D02*
X444759Y151368D01*
G01X444714Y150441D02*
X444492Y150762D01*
G01X440564Y151737D02*
X440818Y151368D01*
G01X440772Y150441D02*
X440551Y150762D01*
G01X449702Y135937D02*
X449924Y135615D01*
G01X449911Y134640D02*
X449657Y135009D01*
G01X436631Y151737D02*
X436885Y151368D01*
G01X436840Y150441D02*
X436618Y150762D01*
G01X445761Y135937D02*
X445982Y135615D01*
G01X445969Y134640D02*
X445715Y135009D01*
G01X468859Y119074D02*
Y161791D01*
G01X460985Y157854D02*
Y123011D01*
G01X460257Y144583D02*
Y155295D01*
G01Y131082D02*
Y141794D01*
G01X457836Y128523D02*
Y123011D01*
G01X457048Y134626D02*
Y130885D01*
G01Y155492D02*
Y151752D01*
G01X456576Y136693D02*
Y149685D01*
G01X455532Y139020D02*
Y131082D01*
G01Y155295D02*
Y147358D01*
G01X453170Y146732D02*
Y139645D01*
G01X453111Y151752D02*
Y155492D01*
G01Y130885D02*
Y134626D01*
G01X440772Y150441D02*
X440781Y150393D01*
G01X441828Y135937D02*
X441819Y135984D01*
G01X436840Y150441D02*
X436849Y150393D01*
G01X437887Y135937D02*
X437877Y135984D01*
G01X432898Y150441D02*
X432907Y150393D01*
G01X433954Y135937D02*
X433945Y135984D01*
G01X428966Y150441D02*
X428975Y150393D01*
G01X430013Y135937D02*
X430003Y135984D01*
G01X432690Y151737D02*
X432943Y151368D01*
G01X432898Y150441D02*
X432677Y150762D01*
G01X441828Y135937D02*
X442050Y135615D01*
G01X442037Y134640D02*
X441783Y135009D01*
G01X428757Y151737D02*
X429011Y151368D01*
G01X428966Y150441D02*
X428744Y150762D01*
G01X437887Y135937D02*
X438108Y135615D01*
G01X438095Y134640D02*
X437841Y135009D01*
G01X433954Y135937D02*
X434176Y135615D01*
G01X434163Y134640D02*
X433909Y135009D01*
G01X430013Y135937D02*
X430234Y135615D01*
G01X430221Y134640D02*
X429967Y135009D01*
G01X448655Y135984D02*
X448646Y135937D01*
G01X449693Y150393D02*
X449702Y150441D01*
G01X444714Y135984D02*
X444704Y135937D01*
G01X445761Y150393D02*
X445770Y150441D01*
G01X449972Y139379D02*
X450022Y140365D01*
G01X450020Y141327D02*
X449969Y140340D01*
G01X448328Y145050D02*
X448379Y146037D01*
G01X448377Y146999D02*
X448326Y146012D01*
G01X446030Y139379D02*
X446081Y140365D01*
G01X446078Y141327D02*
X446028Y140340D01*
G01X444396Y145050D02*
X444447Y146037D01*
G01X444444Y146999D02*
X444394Y146012D01*
G01X442098Y139379D02*
X442148Y140365D01*
G01X442146Y141327D02*
X442095Y140340D01*
G01X440454Y145050D02*
X440505Y146037D01*
G01X440503Y146999D02*
X440452Y146012D01*
G01X438156Y139379D02*
X438207Y140365D01*
G01X438204Y141327D02*
X438154Y140340D01*
G01X436522Y145050D02*
X436573Y146037D01*
G01X436570Y146999D02*
X436520Y146012D01*
G01X434224Y139379D02*
X434274Y140365D01*
G01X434272Y141327D02*
X434221Y140340D01*
G01X432580Y145050D02*
X432631Y146037D01*
G01X432629Y146999D02*
X432578Y146012D01*
G01X450048Y145353D02*
X450185Y151260D01*
G01X450180Y152147D02*
X450044Y146239D01*
G01X448169Y134231D02*
X448305Y140138D01*
G01X448300Y141024D02*
X448164Y135117D01*
G01X446116Y145353D02*
X446252Y151260D01*
G01X446247Y152147D02*
X446111Y146239D01*
G01X444227Y134231D02*
X444363Y140138D01*
G01X444358Y141024D02*
X444222Y135117D01*
G01X442174Y145353D02*
X442311Y151260D01*
G01X442306Y152147D02*
X442170Y146239D01*
G01X440295Y134231D02*
X440431Y140138D01*
G01X440426Y141024D02*
X440290Y135117D01*
G01X438242Y145353D02*
X438378Y151260D01*
G01X438373Y152147D02*
X438237Y146239D01*
G01X436353Y134231D02*
X436489Y140138D01*
G01X436484Y141024D02*
X436348Y135117D01*
G01X434300Y145353D02*
X434437Y151260D01*
G01X434432Y152147D02*
X434296Y146239D01*
G01X432421Y134231D02*
X432557Y140138D01*
G01X432552Y141024D02*
X432416Y135117D01*
G01X430368Y145353D02*
X430504Y151260D01*
G01X430499Y152147D02*
X430363Y146239D01*
G01X449670Y135984D02*
X449657Y135009D01*
G01X448678Y150393D02*
X448692Y151368D01*
G01X445728Y135984D02*
X445715Y135009D01*
G01X444746Y150393D02*
X444759Y151368D01*
G01X441796Y135984D02*
X441783Y135009D01*
G01X440804Y150393D02*
X440818Y151368D01*
G01X437854Y135984D02*
X437841Y135009D01*
G01X436872Y150393D02*
X436885Y151368D01*
G01X433922Y135984D02*
X433909Y135009D01*
G01X432930Y150393D02*
X432943Y151368D01*
G01X429980Y135984D02*
X429967Y135009D01*
G01X450592Y149862D02*
Y154035D01*
G01Y132342D02*
Y136515D01*
G01X450557Y134822D02*
Y133838D01*
G01X450552Y134822D02*
Y133838D01*
G01Y152539D02*
Y151555D01*
G01X450355Y135984D02*
Y129901D01*
G01Y156476D02*
Y150393D01*
G01X450277Y133838D02*
Y152539D01*
G01X450198Y134824D02*
Y133840D01*
G01Y152538D02*
Y151553D01*
G01X450001Y151555D02*
Y156396D01*
G01Y129981D02*
Y134822D01*
G01X449922Y150760D02*
Y151750D01*
G01Y134627D02*
Y135617D01*
G01X449843Y130965D02*
Y129901D01*
G01Y156476D02*
Y155412D01*
G01X449568Y129901D02*
Y130885D01*
G01Y156476D02*
Y155492D01*
G01X448780D02*
Y156476D01*
G01Y129901D02*
Y130885D01*
G01X448505Y130965D02*
Y129901D01*
G01Y156476D02*
Y155412D01*
G01X448426Y135617D02*
Y134627D01*
G01Y151750D02*
Y150760D01*
G01X448347Y151555D02*
Y156396D01*
G01Y129981D02*
Y134822D01*
G01X448151Y151553D02*
Y152538D01*
G01Y133840D02*
Y134824D01*
G01X448072Y152539D02*
Y133838D01*
G01X447993Y135984D02*
Y129901D01*
G01Y156476D02*
Y150393D01*
G01X447796Y134822D02*
Y133838D01*
G01Y152539D02*
Y151555D01*
G01X447792Y152539D02*
Y151555D01*
G01X447757Y136515D02*
Y132342D01*
G01Y154035D02*
Y149862D01*
G01X446655D02*
Y154035D01*
G01Y132342D02*
Y136515D01*
G01X446620Y152539D02*
Y151555D01*
G01X446615Y134822D02*
Y133838D01*
G01X446610Y134822D02*
Y133838D01*
G01X446418Y135984D02*
Y129901D01*
G01Y156476D02*
Y150393D01*
G01X446340Y133838D02*
Y152539D01*
G01X446265Y152538D02*
Y151553D01*
G01X446256Y134824D02*
Y133840D01*
G01X446064Y147698D02*
Y152539D01*
G01Y133838D02*
Y138680D01*
G01X445990Y150760D02*
Y151750D01*
G01X445981Y134627D02*
Y135617D01*
G01X445906Y138760D02*
Y137696D01*
G01Y148681D02*
Y147618D01*
G01X445631D02*
Y148602D01*
G01Y138760D02*
Y137775D01*
G01X444843Y147618D02*
Y148602D01*
G01Y137775D02*
Y138760D01*
G01X444568D02*
Y137696D01*
G01Y148681D02*
Y147618D01*
G01X444494Y151750D02*
Y150760D01*
G01X444484Y135617D02*
Y134627D01*
G01X444450Y128523D02*
Y123011D01*
G01X444410Y147698D02*
Y152539D01*
G01Y133838D02*
Y138680D01*
G01X444218Y151553D02*
Y152538D01*
G01X444209Y133840D02*
Y134824D01*
G01X444135Y152539D02*
Y133838D01*
G01X444056Y135984D02*
Y129901D01*
G01Y156476D02*
Y150393D01*
G01X443864Y152539D02*
Y151555D01*
G01X443859Y152539D02*
Y151555D01*
G01X443855Y134822D02*
Y133838D01*
G01X443820Y136515D02*
Y132342D01*
G01Y154035D02*
Y149862D01*
G01X442717D02*
Y154035D01*
G01Y132342D02*
Y136515D01*
G01X442683Y134822D02*
Y133838D01*
G01X442678Y134822D02*
Y133838D01*
G01Y152539D02*
Y151555D01*
G01X442481Y135984D02*
Y129901D01*
G01Y156476D02*
Y150393D01*
G01X442403Y133838D02*
Y152539D01*
G01X442324Y134824D02*
Y133840D01*
G01Y152538D02*
Y151553D01*
G01X442127Y151555D02*
Y156396D01*
G01Y129981D02*
Y134822D01*
G01X442048Y150760D02*
Y151750D01*
G01Y134627D02*
Y135617D01*
G01X441969Y130965D02*
Y129901D01*
G01Y156476D02*
Y155412D01*
G01X441694Y130885D02*
Y129901D01*
G01Y156476D02*
Y155492D01*
G01X441300Y128523D02*
Y123011D01*
G01X440906Y155492D02*
Y156476D01*
G01Y130885D02*
Y129901D01*
G01X440631Y130965D02*
Y129901D01*
G01Y156476D02*
Y155412D01*
G01X440552Y135617D02*
Y134627D01*
G01Y151750D02*
Y150760D01*
G01X440473Y151555D02*
Y156396D01*
G01Y129981D02*
Y134822D01*
G01X440277Y151553D02*
Y152538D01*
G01Y133840D02*
Y134824D01*
G01X440198Y152539D02*
Y133838D01*
G01X440119Y135984D02*
Y129901D01*
G01Y156476D02*
Y150393D01*
G01X439922Y134822D02*
Y133838D01*
G01Y152539D02*
Y151555D01*
G01X439918Y152539D02*
Y151555D01*
G01X439883Y136515D02*
Y132342D01*
G01Y154035D02*
Y149862D01*
G01X438780D02*
Y154035D01*
G01Y132342D02*
Y136515D01*
G01X438746Y152539D02*
Y151555D01*
G01X438741Y134822D02*
Y133838D01*
G01X438736Y134822D02*
Y133838D01*
G01X438544Y135984D02*
Y129901D01*
G01Y156476D02*
Y150393D01*
G01X438466Y133838D02*
Y152539D01*
G01X438391Y152538D02*
Y151553D01*
G01X438382Y134824D02*
Y133840D01*
G01X438190Y147698D02*
Y152539D01*
G01Y133838D02*
Y138680D01*
G01X438116Y150760D02*
Y151750D01*
G01X438107Y134627D02*
Y135617D01*
G01X438032Y138760D02*
Y137696D01*
G01Y148681D02*
Y147618D01*
G01X437757D02*
Y148602D01*
G01Y138760D02*
Y137775D01*
G01X437363Y128523D02*
Y123011D01*
G01X436969Y147618D02*
Y148602D01*
G01Y137775D02*
Y138760D01*
G01X436694D02*
Y137696D01*
G01Y148681D02*
Y147618D01*
G01X436620Y151750D02*
Y150760D01*
G01X436610Y135617D02*
Y134627D01*
G01X436536Y147698D02*
Y152539D01*
G01Y133838D02*
Y138680D01*
G01X436344Y151553D02*
Y152538D01*
G01X436335Y133840D02*
Y134824D01*
G01X436261Y152539D02*
Y133838D01*
G01X436182Y135984D02*
Y129901D01*
G01Y156476D02*
Y150393D01*
G01X435990Y152539D02*
Y151555D01*
G01X435985Y152539D02*
Y151555D01*
G01X435981Y134822D02*
Y133838D01*
G01X435946Y136515D02*
Y132342D01*
G01Y154035D02*
Y149862D01*
G01X434843D02*
Y154035D01*
G01Y132342D02*
Y136515D01*
G01X434809Y134822D02*
Y133838D01*
G01X434804Y134822D02*
Y133838D01*
G01Y152539D02*
Y151555D01*
G01X434607Y135984D02*
Y129901D01*
G01Y156476D02*
Y150393D01*
G01X434529Y133838D02*
Y152539D01*
G01X434450Y134824D02*
Y133840D01*
G01Y152538D02*
Y151553D01*
G01X434253Y151555D02*
Y156396D01*
G01Y129981D02*
Y134822D01*
G01X434214Y128523D02*
Y123011D01*
G01X434174Y150760D02*
Y151750D01*
G01Y134627D02*
Y135617D01*
G01X434095Y130965D02*
Y129901D01*
G01Y156476D02*
Y155412D01*
G01X433820Y130885D02*
Y129901D01*
G01Y156476D02*
Y155492D01*
G01X433032D02*
Y156476D01*
G01Y130885D02*
Y129901D01*
G01X432757Y130965D02*
Y129901D01*
G01Y156476D02*
Y155412D01*
G01X432678Y135617D02*
Y134627D01*
G01Y151750D02*
Y150760D01*
G01X432599Y151555D02*
Y156396D01*
G01Y129981D02*
Y134822D01*
G01X432403Y151553D02*
Y152538D01*
G01Y133840D02*
Y134824D01*
G01X432324Y152539D02*
Y133838D01*
G01X432245Y135984D02*
Y129901D01*
G01Y156476D02*
Y150393D01*
G01X432048Y134822D02*
Y133838D01*
G01Y152539D02*
Y151555D01*
G01X432044Y152539D02*
Y151555D01*
G01X432009Y136515D02*
Y132342D01*
G01Y154035D02*
Y149862D01*
G01X430906D02*
Y154035D01*
G01Y132342D02*
Y136515D01*
G01X430872Y152539D02*
Y151555D01*
G01X430867Y134822D02*
Y133838D01*
G01X430862Y134822D02*
Y133838D01*
G01X430670Y135984D02*
Y129901D01*
G01Y156476D02*
Y150393D01*
G01X430592Y133838D02*
Y152539D01*
G01X430517Y152538D02*
Y151553D01*
G01X430508Y134824D02*
Y133840D01*
G01X430316Y147698D02*
Y152539D01*
G01Y133838D02*
Y138680D01*
G01X430242Y150760D02*
Y151750D01*
G01X430233Y134627D02*
Y135617D01*
G01X430158Y138760D02*
Y137696D01*
G01Y148681D02*
Y147618D01*
G01X429883Y138760D02*
Y137775D01*
G01Y148602D02*
Y147618D01*
G01X429095Y138760D02*
Y137775D01*
G01Y148602D02*
Y147618D01*
G01X428820Y138760D02*
Y137696D01*
G01Y148681D02*
Y147618D01*
G01X428746Y151750D02*
Y150760D01*
G01X428736Y135617D02*
Y134627D01*
G01X428662Y147698D02*
Y152539D01*
G01Y133838D02*
Y138680D01*
G01X449657Y151368D02*
X449670Y150393D01*
G01X448692Y135009D02*
X448678Y135984D01*
G01X445725Y151368D02*
X445738Y150393D01*
G01X444750Y135009D02*
X444737Y135984D01*
G01X441783Y151368D02*
X441796Y150393D01*
G01X440818Y135009D02*
X440804Y135984D01*
G01X437851Y151368D02*
X437864Y150393D01*
G01X436876Y135009D02*
X436863Y135984D01*
G01X433909Y151368D02*
X433922Y150393D01*
G01X432943Y135009D02*
X432930Y135984D01*
G01X429976Y151368D02*
X429990Y150393D01*
G01X429002Y135009D02*
X428989Y135984D01*
G01X450185Y135117D02*
X450048Y141024D01*
G01X450044Y140138D02*
X450180Y134231D01*
G01X448305Y146239D02*
X448169Y152147D01*
G01X448164Y151260D02*
X448300Y145353D01*
G01X446243Y135117D02*
X446107Y141024D01*
G01X446102Y140138D02*
X446238Y134231D01*
G01X444372Y146239D02*
X444236Y152147D01*
G01X444231Y151260D02*
X444368Y145353D01*
G01X442311Y135117D02*
X442174Y141024D01*
G01X442170Y140138D02*
X442306Y134231D01*
G01X440431Y146239D02*
X440295Y152147D01*
G01X440290Y151260D02*
X440426Y145353D01*
G01X438369Y135117D02*
X438233Y141024D01*
G01X438228Y140138D02*
X438364Y134231D01*
G01X436498Y146239D02*
X436362Y152147D01*
G01X436357Y151260D02*
X436494Y145353D01*
G01X434437Y135117D02*
X434300Y141024D01*
G01X434296Y140138D02*
X434432Y134231D01*
G01X432557Y146239D02*
X432421Y152147D01*
G01X432416Y151260D02*
X432552Y145353D01*
G01X430495Y135117D02*
X430359Y141024D01*
G01X430354Y140138D02*
X430490Y134231D01*
G01X428624Y146239D02*
X428488Y152147D01*
G01X428483Y151260D02*
X428620Y145353D01*
G01X450022Y146012D02*
X449972Y146999D01*
G01X449969Y146037D02*
X450020Y145050D01*
G01X448379Y140340D02*
X448328Y141327D01*
G01X448326Y140365D02*
X448377Y139379D01*
G01X446090Y146012D02*
X446039Y146999D01*
G01X446037Y146037D02*
X446088Y145050D01*
G01X444437Y140340D02*
X444387Y141327D01*
G01X444384Y140365D02*
X444435Y139379D01*
G01X442148Y146012D02*
X442098Y146999D01*
G01X442095Y146037D02*
X442146Y145050D01*
G01X440505Y140340D02*
X440454Y141327D01*
G01X440452Y140365D02*
X440503Y139379D01*
G01X438216Y146012D02*
X438165Y146999D01*
G01X438163Y146037D02*
X438214Y145050D01*
G01X436563Y140340D02*
X436513Y141327D01*
G01X436510Y140365D02*
X436561Y139379D01*
G01X434274Y146012D02*
X434224Y146999D01*
G01X434221Y146037D02*
X434272Y145050D01*
G01X432631Y140340D02*
X432580Y141327D01*
G01X432578Y140365D02*
X432629Y139379D01*
G01X430342Y146012D02*
X430291Y146999D01*
G01X430289Y146037D02*
X430340Y145050D01*
G01X428689Y140340D02*
X428639Y141327D01*
G01X428636Y140365D02*
X428687Y139379D01*
G01X440781Y135984D02*
X440772Y135937D01*
G01X441819Y150393D02*
X441828Y150441D01*
G01X436840Y135984D02*
X436830Y135937D01*
G01X437887Y150393D02*
X437896Y150441D01*
G01X432907Y135984D02*
X432898Y135937D01*
G01X433945Y150393D02*
X433954Y150441D01*
G01X428966Y135984D02*
X428956Y135937D01*
G01X430013Y150393D02*
X430022Y150441D01*
G01X430282Y139379D02*
X430333Y140365D01*
G01X430330Y141327D02*
X430280Y140340D01*
G01X428648Y145050D02*
X428699Y146037D01*
G01X428696Y146999D02*
X428646Y146012D01*
G01X428479Y134231D02*
X428615Y140138D01*
G01X428610Y141024D02*
X428474Y135117D01*
G01X428998Y150393D02*
X429011Y151368D01*
G01X428470Y151553D02*
Y152538D01*
G01X428461Y133840D02*
Y134824D01*
G01X428387Y152539D02*
Y133838D01*
G01X428308Y135984D02*
Y129901D01*
G01Y156476D02*
Y150393D01*
G01X428116Y152539D02*
Y151555D01*
G01X428111Y152539D02*
Y151555D01*
G01X428107Y134822D02*
Y133838D01*
G01X428072Y136515D02*
Y132342D01*
G01Y154035D02*
Y149862D01*
G01X430670Y156476D02*
X428308D01*
G01X434607D02*
X432245D01*
G01X438544D02*
X436182D01*
G01X442481D02*
X440119D01*
G01X446418D02*
X444056D01*
G01X450355D02*
X447993D01*
G01X453111Y155492D02*
X457048D01*
G01X434095D02*
X432757D01*
G01X441969D02*
X440631D01*
G01X449843D02*
X448505D01*
G01X448347Y155393D02*
X450001D01*
G01X440473D02*
X442127D01*
G01X432599D02*
X434253D01*
G01X430670Y155295D02*
X428308D01*
G01X434607D02*
X432245D01*
G01X438544D02*
X436182D01*
G01X442481D02*
X440119D01*
G01X446418D02*
X444056D01*
G01X450355D02*
X447993D01*
G01X460257D02*
X455532D01*
G01X434253Y154901D02*
X432599D01*
G01X442127D02*
X440473D01*
G01X450001D02*
X448347D01*
G01X430906Y154035D02*
X428072D01*
G01X434843D02*
X432009D01*
G01X438780D02*
X435946D01*
G01X442717D02*
X439883D01*
G01X446655D02*
X443820D01*
G01X450592D02*
X447757D01*
G01X434253Y153130D02*
X432599D01*
G01X442127D02*
X440473D01*
G01X450001D02*
X448347D01*
G01Y152637D02*
X450001D01*
G01X440473D02*
X442127D01*
G01X432599D02*
X434253D01*
G01X430906Y152539D02*
X428072D01*
G01X434843D02*
X432009D01*
G01X438780D02*
X435946D01*
G01X442717D02*
X439883D01*
G01X446655D02*
X443820D01*
G01X450592D02*
X447757D01*
G01X450001Y152382D02*
X450592D01*
G01X447757D02*
X448347D01*
G01X446064D02*
X446655D01*
G01X443820D02*
X444410D01*
G01X442127D02*
X442717D01*
G01X439883D02*
X440473D01*
G01X438190D02*
X438780D01*
G01X435946D02*
X436536D01*
G01X434253D02*
X434843D01*
G01X432009D02*
X432599D01*
G01X430316D02*
X430906D01*
G01X428072D02*
X428662D01*
G01X448169Y152147D02*
X450180D01*
G01X444236D02*
X446247D01*
G01X440295D02*
X442306D01*
G01X436362D02*
X438373D01*
G01X432421D02*
X434432D01*
G01X428488D02*
X430499D01*
G01X430244Y151756D02*
X428744D01*
G01X434176D02*
X432676D01*
G01X438118D02*
X436618D01*
G01X442050D02*
X440550D01*
G01X445992D02*
X444492D01*
G01X449924D02*
X448424D01*
G01X457048Y151752D02*
X453111D01*
G01X448438Y151737D02*
X449911D01*
G01X444505D02*
X445978D01*
G01X440564D02*
X442037D01*
G01X436631D02*
X438104D01*
G01X432690D02*
X434163D01*
G01X428757D02*
X430230D01*
G01X428662Y151712D02*
X428072D01*
G01X430906D02*
X430316D01*
G01X432599D02*
X432009D01*
G01X434843D02*
X434253D01*
G01X436536D02*
X435946D01*
G01X438780D02*
X438190D01*
G01X440473D02*
X439883D01*
G01X442717D02*
X442127D01*
G01X444410D02*
X443820D01*
G01X446655D02*
X446064D01*
G01X448347D02*
X447757D01*
G01X450592D02*
X450001D01*
G01X447757Y151555D02*
X450592D01*
G01X443820D02*
X446655D01*
G01X439883D02*
X442717D01*
G01X435946D02*
X438780D01*
G01X432009D02*
X434843D01*
G01X428072D02*
X430906D01*
G01X430316Y151456D02*
X428662D01*
G01X438190D02*
X436536D01*
G01X446064D02*
X444410D01*
G01X429976Y151368D02*
X429011D01*
G01X433909D02*
X432943D01*
G01X437851D02*
X436885D01*
G01X441783D02*
X440818D01*
G01X445725D02*
X444759D01*
G01X449657D02*
X448692D01*
G01X447757Y151358D02*
X448072D01*
G01X443820D02*
X444135D01*
G01X439883D02*
X440198D01*
G01X435946D02*
X436261D01*
G01X432009D02*
X432324D01*
G01X428072D02*
X428387D01*
G01X430906D02*
X430592D01*
G01X434843D02*
X434529D01*
G01X438780D02*
X438466D01*
G01X442717D02*
X442403D01*
G01X446655D02*
X446340D01*
G01X450592D02*
X450277D01*
G01X430504Y151260D02*
X428483D01*
G01X434437D02*
X432416D01*
G01X438378D02*
X436357D01*
G01X442311D02*
X440290D01*
G01X446252D02*
X444231D01*
G01X450185D02*
X448164D01*
G01X444410Y150964D02*
X446064D01*
G01X436536D02*
X438190D01*
G01X428662D02*
X430316D01*
G01X430244Y150772D02*
X428744D01*
G01X434176D02*
X432676D01*
G01X438118D02*
X436618D01*
G01X442050D02*
X440550D01*
G01X445992D02*
X444492D01*
G01X449924D02*
X448424D01*
G01X460257Y150767D02*
X455532D01*
G01X430242Y150762D02*
X428746D01*
G01X434174D02*
X432678D01*
G01X438116D02*
X436620D01*
G01X442048D02*
X440552D01*
G01X445990D02*
X444494D01*
G01X449922D02*
X448426D01*
G01X448646Y150441D02*
X449702D01*
G01X444714D02*
X445770D01*
G01X440772D02*
X441828D01*
G01X436840D02*
X437896D01*
G01X432898D02*
X433954D01*
G01X428966D02*
X430022D01*
G01X430670Y150393D02*
X428308D01*
G01X434607D02*
X432245D01*
G01X438544D02*
X436182D01*
G01X442481D02*
X440119D01*
G01X446418D02*
X444056D01*
G01X450355D02*
X447993D01*
G01X450277Y149862D02*
X450592D01*
G01X447757D02*
X448072D01*
G01X446340D02*
X446655D01*
G01X443820D02*
X444135D01*
G01X442403D02*
X442717D01*
G01X439883D02*
X440198D01*
G01X438466D02*
X438780D01*
G01X435946D02*
X436261D01*
G01X434529D02*
X434843D01*
G01X432009D02*
X432324D01*
G01X430592D02*
X430906D01*
G01X428072D02*
X428387D01*
G01X448403Y149826D02*
X449946D01*
G01X444470D02*
X446014D01*
G01X440528D02*
X442072D01*
G01X436596D02*
X438140D01*
G01X432654D02*
X434198D01*
G01X428722D02*
X430265D01*
G01X448413Y149807D02*
X449935D01*
G01X444481D02*
X446003D01*
G01X440539D02*
X442061D01*
G01X436607D02*
X438129D01*
G01X432665D02*
X434187D01*
G01X428733D02*
X430255D01*
G01X444410Y149193D02*
X446064D01*
G01X436536D02*
X438190D01*
G01X428662D02*
X430316D01*
G01Y148700D02*
X428662D01*
G01X438190D02*
X436536D01*
G01X446064D02*
X444410D01*
G01X430158Y148602D02*
X428820D01*
G01X438032D02*
X436694D01*
G01X445906D02*
X444568D01*
G01Y147618D02*
X445906D01*
G01X436694D02*
X438032D01*
G01X428820D02*
X430158D01*
G01X430291Y146999D02*
X428696D01*
G01X434224D02*
X432629D01*
G01X438165D02*
X436570D01*
G01X442098D02*
X440503D01*
G01X446039D02*
X444444D01*
G01X449972D02*
X448377D01*
G01X430592Y146889D02*
X428387D01*
G01X434529D02*
X432324D01*
G01X438466D02*
X436261D01*
G01X442403D02*
X440198D01*
G01X446340D02*
X444135D01*
G01X450277D02*
X448072D01*
G01X430363Y146239D02*
X428624D01*
G01X434296D02*
X432557D01*
G01X438237D02*
X436498D01*
G01X442170D02*
X440431D01*
G01X446111D02*
X444372D01*
G01X450044D02*
X448305D01*
G01X448379Y146037D02*
X449969D01*
G01X444447D02*
X446037D01*
G01X440505D02*
X442095D01*
G01X436573D02*
X438163D01*
G01X432631D02*
X434221D01*
G01X428699D02*
X430289D01*
G01X448326Y146012D02*
X450022D01*
G01X444394D02*
X446090D01*
G01X440452D02*
X442148D01*
G01X436520D02*
X438216D01*
G01X432578D02*
X434274D01*
G01X428646D02*
X430342D01*
G01X430349Y145945D02*
X428639D01*
G01X434281D02*
X432571D01*
G01X438223D02*
X436513D01*
G01X442155D02*
X440445D01*
G01X446097D02*
X444387D01*
G01X450029D02*
X448319D01*
G01X448300Y145353D02*
X450048D01*
G01X444368D02*
X446116D01*
G01X440426D02*
X442174D01*
G01X436494D02*
X438242D01*
G01X432552D02*
X434300D01*
G01X428620D02*
X430368D01*
G01X430340Y145050D02*
X428648D01*
G01X434272D02*
X432580D01*
G01X438214D02*
X436522D01*
G01X442146D02*
X440454D01*
G01X446088D02*
X444396D01*
G01X450020D02*
X448328D01*
G01X430349Y144960D02*
X428639D01*
G01X434281D02*
X432571D01*
G01X438223D02*
X436513D01*
G01X442155D02*
X440445D01*
G01X446097D02*
X444387D01*
G01X450029D02*
X448319D01*
G01X448072Y144634D02*
X450277D01*
G01X444135D02*
X446340D01*
G01X440198D02*
X442403D01*
G01X436261D02*
X438466D01*
G01X432324D02*
X434529D01*
G01X428387D02*
X430592D01*
G01X448072Y144467D02*
X450277D01*
G01X444135D02*
X446340D01*
G01X440198D02*
X442403D01*
G01X436261D02*
X438466D01*
G01X432324D02*
X434529D01*
G01X428387D02*
X430592D01*
G01Y141910D02*
X428387D01*
G01X434529D02*
X432324D01*
G01X438466D02*
X436261D01*
G01X442403D02*
X440198D01*
G01X446340D02*
X444135D01*
G01X450277D02*
X448072D01*
G01X430592Y141743D02*
X428387D01*
G01X434529D02*
X432324D01*
G01X438466D02*
X436261D01*
G01X442403D02*
X440198D01*
G01X446340D02*
X444135D01*
G01X450277D02*
X448072D01*
G01X448319Y141417D02*
X450029D01*
G01X444377D02*
X446088D01*
G01X440445D02*
X442155D01*
G01X436503D02*
X438214D01*
G01X432571D02*
X434281D01*
G01X428629D02*
X430340D01*
G01X448328Y141327D02*
X450020D01*
G01X444387D02*
X446078D01*
G01X440454D02*
X442146D01*
G01X436513D02*
X438204D01*
G01X432580D02*
X434272D01*
G01X428639D02*
X430330D01*
G01X430359Y141024D02*
X428610D01*
G01X434300D02*
X432552D01*
G01X438233D02*
X436484D01*
G01X442174D02*
X440426D01*
G01X446107D02*
X444358D01*
G01X450048D02*
X448300D01*
G01X448319Y140433D02*
X450029D01*
G01X444377D02*
X446088D01*
G01X440445D02*
X442155D01*
G01X436503D02*
X438214D01*
G01X432571D02*
X434281D01*
G01X428629D02*
X430340D01*
G01X430333Y140365D02*
X428636D01*
G01X434274D02*
X432578D01*
G01X438207D02*
X436510D01*
G01X442148D02*
X440452D01*
G01X446081D02*
X444384D01*
G01X450022D02*
X448326D01*
G01X430280Y140340D02*
X428689D01*
G01X434221D02*
X432631D01*
G01X438154D02*
X436563D01*
G01X442095D02*
X440505D01*
G01X446028D02*
X444437D01*
G01X449969D02*
X448379D01*
G01X448305Y140138D02*
X450044D01*
G01X444363D02*
X446102D01*
G01X440431D02*
X442170D01*
G01X436489D02*
X438228D01*
G01X432557D02*
X434296D01*
G01X428615D02*
X430354D01*
G01X448072Y139488D02*
X450277D01*
G01X444135D02*
X446340D01*
G01X440198D02*
X442403D01*
G01X436261D02*
X438466D01*
G01X432324D02*
X434529D01*
G01X428387D02*
X430592D01*
G01X448377Y139379D02*
X449972D01*
G01X444435D02*
X446030D01*
G01X440503D02*
X442098D01*
G01X436561D02*
X438156D01*
G01X432629D02*
X434224D01*
G01X428687D02*
X430282D01*
G01X430158Y138760D02*
X428820D01*
G01X438032D02*
X436694D01*
G01X445906D02*
X444568D01*
G01X430158Y137775D02*
X428820D01*
G01X438032D02*
X436694D01*
G01X445906D02*
X444568D01*
G01X444410Y137677D02*
X446064D01*
G01X436536D02*
X438190D01*
G01X428662D02*
X430316D01*
G01Y137185D02*
X428662D01*
G01X438190D02*
X436536D01*
G01X446064D02*
X444410D01*
G01X448438Y134640D02*
X448692Y135009D01*
G01X448425Y135615D02*
X448646Y135937D01*
G01X444496Y134640D02*
X444750Y135009D01*
G01X444483Y135615D02*
X444704Y135937D01*
G01X440564Y134640D02*
X440818Y135009D01*
G01X440551Y135615D02*
X440772Y135937D01*
G01X449924Y150762D02*
X449702Y150441D01*
G01X449911Y151737D02*
X449657Y151368D01*
G01X436622Y134640D02*
X436876Y135009D01*
G01X436609Y135615D02*
X436830Y135937D01*
G01X445991Y150762D02*
X445770Y150441D01*
G01X445978Y151737D02*
X445725Y151368D01*
G01X432690Y134640D02*
X432943Y135009D01*
G01X432677Y135615D02*
X432898Y135937D01*
G01X442050Y150762D02*
X441828Y150441D01*
G01X442037Y151737D02*
X441783Y151368D01*
G01X428748Y134640D02*
X429002Y135009D01*
G01X428735Y135615D02*
X428956Y135937D01*
G01X438117Y150762D02*
X437896Y150441D01*
G01X438104Y151737D02*
X437851Y151368D01*
G01X456576Y149685D02*
X454618Y146732D01*
G01X430245Y136570D02*
X428724D01*
G01X434187D02*
X432665D01*
G01X438119D02*
X436598D01*
G01X442061D02*
X440539D01*
G01X445993D02*
X444472D01*
G01X449935D02*
X448413D01*
G01X430256Y136551D02*
X428713D01*
G01X434198D02*
X432654D01*
G01X438130D02*
X436587D01*
G01X442072D02*
X440528D01*
G01X446004D02*
X444461D01*
G01X449946D02*
X448403D01*
G01X428387Y136515D02*
X428072D01*
G01X430906D02*
X430592D01*
G01X432324D02*
X432009D01*
G01X436261D02*
X435946D01*
G01X434843D02*
X434529D01*
G01X438780D02*
X438466D01*
G01X440198D02*
X439883D01*
G01X442717D02*
X442403D01*
G01X444135D02*
X443820D01*
G01X446655D02*
X446340D01*
G01X448072D02*
X447757D01*
G01X450592D02*
X450277D01*
G01X430670Y135984D02*
X428308D01*
G01X434607D02*
X432245D01*
G01X438544D02*
X436182D01*
G01X442481D02*
X440119D01*
G01X446418D02*
X444056D01*
G01X450355D02*
X447993D01*
G01X430013Y135937D02*
X428956D01*
G01X433954D02*
X432898D01*
G01X437887D02*
X436830D01*
G01X441828D02*
X440772D01*
G01X445761D02*
X444704D01*
G01X449702D02*
X448646D01*
G01X448426Y135615D02*
X449922D01*
G01X444484D02*
X445981D01*
G01X440552D02*
X442048D01*
G01X436610D02*
X438107D01*
G01X432678D02*
X434174D01*
G01X428736D02*
X430233D01*
G01X460257Y135610D02*
X455532D01*
G01X448424Y135605D02*
X449924D01*
G01X444483D02*
X445982D01*
G01X440550D02*
X442050D01*
G01X436609D02*
X438108D01*
G01X432676D02*
X434176D01*
G01X428735D02*
X430234D01*
G01X430316Y135413D02*
X428662D01*
G01X438190D02*
X436536D01*
G01X446064D02*
X444410D01*
G01X448164Y135117D02*
X450185D01*
G01X444222D02*
X446243D01*
G01X440290D02*
X442311D01*
G01X436348D02*
X438369D01*
G01X432416D02*
X434437D01*
G01X428474D02*
X430495D01*
G01X450277Y135019D02*
X450592D01*
G01X446340D02*
X446655D01*
G01X442403D02*
X442717D01*
G01X438466D02*
X438780D01*
G01X434529D02*
X434843D01*
G01X430592D02*
X430906D01*
G01X428387D02*
X428072D01*
G01X432324D02*
X432009D01*
G01X436261D02*
X435946D01*
G01X440198D02*
X439883D01*
G01X444135D02*
X443820D01*
G01X448072D02*
X447757D01*
G01X448692Y135009D02*
X449657D01*
G01X444750D02*
X445715D01*
G01X440818D02*
X441783D01*
G01X436876D02*
X437841D01*
G01X432943D02*
X433909D01*
G01X429002D02*
X429967D01*
G01X444410Y134921D02*
X446064D01*
G01X436536D02*
X438190D01*
G01X428662D02*
X430316D01*
G01X447757Y134822D02*
X450592D01*
G01X443820D02*
X446655D01*
G01X439883D02*
X442717D01*
G01X435946D02*
X438780D01*
G01X432009D02*
X434843D01*
G01X428072D02*
X430906D01*
G01X450001Y134665D02*
X450592D01*
G01X447757D02*
X448347D01*
G01X446064D02*
X446655D01*
G01X443820D02*
X444410D01*
G01X442127D02*
X442717D01*
G01X439883D02*
X440473D01*
G01X438190D02*
X438780D01*
G01X435946D02*
X436536D01*
G01X434253D02*
X434843D01*
G01X432009D02*
X432599D01*
G01X430316D02*
X430906D01*
G01X428072D02*
X428662D01*
G01X430221Y134640D02*
X428748D01*
G01X434163D02*
X432690D01*
G01X438095D02*
X436622D01*
G01X442037D02*
X440564D01*
G01X445969D02*
X444496D01*
G01X449911D02*
X448438D01*
G01X453111Y134626D02*
X457048D01*
G01X448424Y134621D02*
X449924D01*
G01X444483D02*
X445982D01*
G01X440550D02*
X442050D01*
G01X436609D02*
X438108D01*
G01X432676D02*
X434176D01*
G01X428735D02*
X430234D01*
G01X430490Y134231D02*
X428479D01*
G01X434432D02*
X432421D01*
G01X438364D02*
X436353D01*
G01X442306D02*
X440295D01*
G01X446238D02*
X444227D01*
G01X450180D02*
X448169D01*
G01X428662Y133996D02*
X428072D01*
G01X430906D02*
X430316D01*
G01X432599D02*
X432009D01*
G01X434843D02*
X434253D01*
G01X436536D02*
X435946D01*
G01X438780D02*
X438190D01*
G01X440473D02*
X439883D01*
G01X442717D02*
X442127D01*
G01X444410D02*
X443820D01*
G01X446655D02*
X446064D01*
G01X448347D02*
X447757D01*
G01X450592D02*
X450001D01*
G01X430906Y133838D02*
X428072D01*
G01X434843D02*
X432009D01*
G01X438780D02*
X435946D01*
G01X442717D02*
X439883D01*
G01X446655D02*
X443820D01*
G01X450592D02*
X447757D01*
G01X434253Y133740D02*
X432599D01*
G01X442127D02*
X440473D01*
G01X450001D02*
X448347D01*
G01Y133248D02*
X450001D01*
G01X440473D02*
X442127D01*
G01X432599D02*
X434253D01*
G01X447757Y132342D02*
X450592D01*
G01X443820D02*
X446655D01*
G01X439883D02*
X442717D01*
G01X435946D02*
X438780D01*
G01X432009D02*
X434843D01*
G01X428072D02*
X430906D01*
G01X448347Y131476D02*
X450001D01*
G01X440473D02*
X442127D01*
G01X432599D02*
X434253D01*
G01X455532Y131082D02*
X460257D01*
G01X447993D02*
X450355D01*
G01X430670D02*
X428308D01*
G01X434607D02*
X432245D01*
G01X438544D02*
X436182D01*
G01X442481D02*
X440119D01*
G01X446418D02*
X444056D01*
G01X434253Y130984D02*
X432599D01*
G01X442127D02*
X440473D01*
G01X450001D02*
X448347D01*
G01X434095Y130885D02*
X432757D01*
G01X441969D02*
X440631D01*
G01X449843D02*
X448505D01*
G01X457048D02*
X453111D01*
G01X447993Y129901D02*
X450355D01*
G01X444056D02*
X446418D01*
G01X440119D02*
X442481D01*
G01X436182D02*
X438544D01*
G01X432245D02*
X434607D01*
G01X428308D02*
X430670D01*
G01X441300Y123011D02*
X460985D01*
G01X434176Y150762D02*
X433954Y150441D01*
G01X434163Y151737D02*
X433909Y151368D01*
G01X430243Y150762D02*
X430022Y150441D01*
G01X430230Y151737D02*
X429976Y151368D01*
G01X450033Y225965D02*
X450044Y226239D01*
G01X450028Y225948D02*
X450033Y225965D01*
G01X450022Y226012D02*
X450028Y225948D01*
G01X450034Y224988D02*
X450048Y225353D01*
G01X450027Y224965D02*
X450034Y224988D01*
G01X450020Y225050D02*
X450027Y224965D01*
G01X449956Y226524D02*
X449969Y226037D01*
G01X449950Y226913D02*
X449956Y226524D01*
G01X449945Y227384D02*
X449950Y226913D01*
G01X449941Y227925D02*
X449945Y227384D01*
G01X449938Y228520D02*
X449941Y227925D01*
G01X449936Y229153D02*
X449938Y228520D01*
G01X449935Y229807D02*
X449936Y229153D01*
G01X449962Y227364D02*
X449972Y226999D01*
G01X449957Y227656D02*
X449962Y227364D01*
G01X449953Y228009D02*
X449957Y227656D01*
G01X449950Y228414D02*
X449953Y228009D01*
G01X449948Y228861D02*
X449950Y228414D01*
G01X449946Y229336D02*
X449948Y228861D01*
G01X449946Y229826D02*
Y229336D01*
G01X448315Y225965D02*
X448326Y226012D01*
G01X448310Y226063D02*
X448315Y225965D01*
G01X448305Y226239D02*
X448310Y226063D01*
G01X448400Y228861D02*
X448403Y229826D01*
G01X448398Y228414D02*
X448400Y228861D01*
G01X448395Y228009D02*
X448398Y228414D01*
G01X448391Y227656D02*
X448395Y228009D01*
G01X448387Y227364D02*
X448391Y227656D01*
G01X448382Y227143D02*
X448387Y227364D01*
G01X448377Y226999D02*
X448382Y227143D01*
G01X448411Y228520D02*
X448413Y229807D01*
G01X448408Y227925D02*
X448411Y228520D01*
G01X448404Y227384D02*
X448408Y227925D01*
G01X448398Y226913D02*
X448404Y227384D01*
G01X448392Y226524D02*
X448398Y226913D01*
G01X448386Y226230D02*
X448392Y226524D01*
G01X448379Y226037D02*
X448386Y226230D01*
G01X448314Y224988D02*
X448328Y225050D01*
G01X448307Y225118D02*
X448314Y224988D01*
G01X448300Y225353D02*
X448307Y225118D01*
G01X448315Y220412D02*
X448305Y220138D01*
G01X448321Y220429D02*
X448315Y220412D01*
G01X448326Y220365D02*
X448321Y220429D01*
G01X448314Y221390D02*
X448300Y221024D01*
G01X448321Y221412D02*
X448314Y221390D01*
G01X448328Y221327D02*
X448321Y221412D01*
G01X448392Y219853D02*
X448379Y220340D01*
G01X448398Y219464D02*
X448392Y219853D01*
G01X448404Y218993D02*
X448398Y219464D01*
G01X448408Y218453D02*
X448404Y218993D01*
G01X448411Y217857D02*
X448408Y218453D01*
G01X448413Y217224D02*
X448411Y217857D01*
G01X448413Y216570D02*
Y217224D01*
G01X448387Y219013D02*
X448377Y219379D01*
G01X448391Y218722D02*
X448387Y219013D01*
G01X448395Y218368D02*
X448391Y218722D01*
G01X448398Y217963D02*
X448395Y218368D01*
G01X448400Y217516D02*
X448398Y217963D01*
G01X448402Y217041D02*
X448400Y217516D01*
G01X448403Y216551D02*
X448402Y217041D01*
G01X450033Y220412D02*
X450022Y220365D01*
G01X450039Y220314D02*
X450033Y220412D01*
G01X450044Y220138D02*
X450039Y220314D01*
G01X449948Y217516D02*
X449946Y216551D01*
G01X449950Y217963D02*
X449948Y217516D01*
G01X449953Y218368D02*
X449950Y217963D01*
G01X449957Y218722D02*
X449953Y218368D01*
G01X449962Y219013D02*
X449957Y218722D01*
G01X449967Y219234D02*
X449962Y219013D01*
G01X449972Y219379D02*
X449967Y219234D01*
G01X449938Y217857D02*
X449935Y216570D01*
G01X449941Y218453D02*
X449938Y217857D01*
G01X449945Y218993D02*
X449941Y218453D01*
G01X449950Y219464D02*
X449945Y218993D01*
G01X449956Y219853D02*
X449950Y219464D01*
G01X449962Y220148D02*
X449956Y219853D01*
G01X449969Y220340D02*
X449962Y220148D01*
G01X450034Y221390D02*
X450020Y221327D01*
G01X450042Y221259D02*
X450034Y221390D01*
G01X450048Y221024D02*
X450042Y221259D01*
G01X446101Y225965D02*
X446111Y226239D01*
G01X446095Y225948D02*
X446101Y225965D01*
G01X446090Y226012D02*
X446095Y225948D01*
G01X446102Y224988D02*
X446116Y225353D01*
G01X446095Y224965D02*
X446102Y224988D01*
G01X446088Y225050D02*
X446095Y224965D01*
G01X446024Y226524D02*
X446037Y226037D01*
G01X446018Y226913D02*
X446024Y226524D01*
G01X446013Y227384D02*
X446018Y226913D01*
G01X446008Y227925D02*
X446013Y227384D01*
G01X446005Y228520D02*
X446008Y227925D01*
G01X446003Y229153D02*
X446005Y228520D01*
G01X446003Y229807D02*
Y229153D01*
G01X445998Y231677D02*
X445990Y231750D01*
G01X446001Y231547D02*
X445998Y231677D01*
G01X446005Y231359D02*
X446001Y231547D01*
G01X446008Y231120D02*
X446005Y231359D01*
G01X446010Y230838D02*
X446008Y231120D01*
G01X446012Y230521D02*
X446010Y230838D01*
G01X446013Y230180D02*
X446012Y230521D01*
G01X446014Y229826D02*
X446013Y230180D01*
G01X446029Y227364D02*
X446039Y226999D01*
G01X446025Y227656D02*
X446029Y227364D01*
G01X446021Y228009D02*
X446025Y227656D01*
G01X446018Y228414D02*
X446021Y228009D01*
G01X446016Y228861D02*
X446018Y228414D01*
G01X446014Y229336D02*
X446016Y228861D01*
G01X446014Y229826D02*
Y229336D01*
G01X444383Y225965D02*
X444394Y226012D01*
G01X444378Y226063D02*
X444383Y225965D01*
G01X444372Y226239D02*
X444378Y226063D01*
G01X444468Y228861D02*
X444470Y229826D01*
G01X444466Y228414D02*
X444468Y228861D01*
G01X444463Y228009D02*
X444466Y228414D01*
G01X444459Y227656D02*
X444463Y228009D01*
G01X444454Y227364D02*
X444459Y227656D01*
G01X444450Y227143D02*
X444454Y227364D01*
G01X444444Y226999D02*
X444450Y227143D01*
G01X444472Y230521D02*
X444470Y229826D01*
G01X444474Y230838D02*
X444472Y230521D01*
G01X444476Y231120D02*
X444474Y230838D01*
G01X444479Y231359D02*
X444476Y231120D01*
G01X444482Y231547D02*
X444479Y231359D01*
G01X444486Y231677D02*
X444482Y231547D01*
G01X444490Y231746D02*
X444486Y231677D01*
G01X444494Y231750D02*
X444490Y231746D01*
G01X444478Y228520D02*
X444481Y229807D01*
G01X444475Y227925D02*
X444478Y228520D01*
G01X444471Y227384D02*
X444475Y227925D01*
G01X444466Y226913D02*
X444471Y227384D01*
G01X444460Y226524D02*
X444466Y226913D01*
G01X444454Y226230D02*
X444460Y226524D01*
G01X444447Y226037D02*
X444454Y226230D01*
G01X444382Y224988D02*
X444396Y225050D01*
G01X444374Y225118D02*
X444382Y224988D01*
G01X444368Y225353D02*
X444374Y225118D01*
G01Y220412D02*
X444363Y220138D01*
G01X444379Y220429D02*
X444374Y220412D01*
G01X444384Y220365D02*
X444379Y220429D01*
G01X444372Y221390D02*
X444358Y221024D01*
G01X444380Y221412D02*
X444372Y221390D01*
G01X444387Y221327D02*
X444380Y221412D01*
G01X444451Y219853D02*
X444437Y220340D01*
G01X444457Y219464D02*
X444451Y219853D01*
G01X444462Y218993D02*
X444457Y219464D01*
G01X444466Y218453D02*
X444462Y218993D01*
G01X444469Y217857D02*
X444466Y218453D01*
G01X444471Y217224D02*
X444469Y217857D01*
G01X444472Y216570D02*
X444471Y217224D01*
G01X444477Y214700D02*
X444484Y214627D01*
G01X444473Y214830D02*
X444477Y214700D01*
G01X444470Y215018D02*
X444473Y214830D01*
G01X444467Y215257D02*
X444470Y215018D01*
G01X444464Y215540D02*
X444467Y215257D01*
G01X444462Y215857D02*
X444464Y215540D01*
G01X444461Y216198D02*
X444462Y215857D01*
G01X444461Y216551D02*
Y216198D01*
G01X444445Y219013D02*
X444435Y219379D01*
G01X444450Y218722D02*
X444445Y219013D01*
G01X444453Y218368D02*
X444450Y218722D01*
G01X444456Y217963D02*
X444453Y218368D01*
G01X444459Y217516D02*
X444456Y217963D01*
G01X444460Y217041D02*
X444459Y217516D01*
G01X444461Y216551D02*
X444460Y217041D01*
G01X446091Y220412D02*
X446081Y220365D01*
G01X446097Y220314D02*
X446091Y220412D01*
G01X446102Y220138D02*
X446097Y220314D01*
G01X446006Y217516D02*
X446004Y216551D01*
G01X446009Y217963D02*
X446006Y217516D01*
G01X446012Y218368D02*
X446009Y217963D01*
G01X446015Y218722D02*
X446012Y218368D01*
G01X446020Y219013D02*
X446015Y218722D01*
G01X446025Y219234D02*
X446020Y219013D01*
G01X446030Y219379D02*
X446025Y219234D01*
G01X446003Y215857D02*
X446004Y216551D01*
G01X446001Y215540D02*
X446003Y215857D01*
G01X445998Y215257D02*
X446001Y215540D01*
G01X445995Y215018D02*
X445998Y215257D01*
G01X445992Y214830D02*
X445995Y215018D01*
G01X445988Y214700D02*
X445992Y214830D01*
G01X445985Y214632D02*
X445988Y214700D01*
G01X445981Y214627D02*
X445985Y214632D01*
G01X445996Y217857D02*
X445993Y216570D01*
G01X445999Y218453D02*
X445996Y217857D01*
G01X446003Y218993D02*
X445999Y218453D01*
G01X446008Y219464D02*
X446003Y218993D01*
G01X446014Y219853D02*
X446008Y219464D01*
G01X446021Y220148D02*
X446014Y219853D01*
G01X446028Y220340D02*
X446021Y220148D01*
G01X446093Y221390D02*
X446078Y221327D01*
G01X446100Y221259D02*
X446093Y221390D01*
G01X446107Y221024D02*
X446100Y221259D01*
G01X440441Y225965D02*
X440452Y226012D01*
G01X440436Y226063D02*
X440441Y225965D01*
G01X440431Y226239D02*
X440436Y226063D01*
G01X440526Y228861D02*
X440528Y229826D01*
G01X440524Y228414D02*
X440526Y228861D01*
G01X440521Y228009D02*
X440524Y228414D01*
G01X440517Y227656D02*
X440521Y228009D01*
G01X440513Y227364D02*
X440517Y227656D01*
G01X440508Y227143D02*
X440513Y227364D01*
G01X440503Y226999D02*
X440508Y227143D01*
G01X440537Y228520D02*
X440539Y229807D01*
G01X440534Y227925D02*
X440537Y228520D01*
G01X440529Y227384D02*
X440534Y227925D01*
G01X440524Y226913D02*
X440529Y227384D01*
G01X440518Y226524D02*
X440524Y226913D01*
G01X440512Y226230D02*
X440518Y226524D01*
G01X440505Y226037D02*
X440512Y226230D01*
G01X440440Y224988D02*
X440454Y225050D01*
G01X440433Y225118D02*
X440440Y224988D01*
G01X440426Y225353D02*
X440433Y225118D01*
G01X442159Y225965D02*
X442170Y226239D01*
G01X442154Y225948D02*
X442159Y225965D01*
G01X442148Y226012D02*
X442154Y225948D01*
G01X442160Y224988D02*
X442174Y225353D01*
G01X442153Y224965D02*
X442160Y224988D01*
G01X442146Y225050D02*
X442153Y224965D01*
G01X442082Y226524D02*
X442095Y226037D01*
G01X442076Y226913D02*
X442082Y226524D01*
G01X442071Y227384D02*
X442076Y226913D01*
G01X442067Y227925D02*
X442071Y227384D01*
G01X442064Y228520D02*
X442067Y227925D01*
G01X442062Y229153D02*
X442064Y228520D01*
G01X442061Y229807D02*
X442062Y229153D01*
G01X442088Y227364D02*
X442098Y226999D01*
G01X442083Y227656D02*
X442088Y227364D01*
G01X442079Y228009D02*
X442083Y227656D01*
G01X442076Y228414D02*
X442079Y228009D01*
G01X442074Y228861D02*
X442076Y228414D01*
G01X442072Y229336D02*
X442074Y228861D01*
G01X442072Y229826D02*
Y229336D01*
G01X442159Y220412D02*
X442148Y220365D01*
G01X442164Y220314D02*
X442159Y220412D01*
G01X442170Y220138D02*
X442164Y220314D01*
G01X442074Y217516D02*
X442072Y216551D01*
G01X442076Y217963D02*
X442074Y217516D01*
G01X442079Y218368D02*
X442076Y217963D01*
G01X442083Y218722D02*
X442079Y218368D01*
G01X442088Y219013D02*
X442083Y218722D01*
G01X442093Y219234D02*
X442088Y219013D01*
G01X442098Y219379D02*
X442093Y219234D01*
G01X442064Y217857D02*
X442061Y216570D01*
G01X442067Y218453D02*
X442064Y217857D01*
G01X442071Y218993D02*
X442067Y218453D01*
G01X442076Y219464D02*
X442071Y218993D01*
G01X442082Y219853D02*
X442076Y219464D01*
G01X442088Y220148D02*
X442082Y219853D01*
G01X442095Y220340D02*
X442088Y220148D01*
G01X442160Y221390D02*
X442146Y221327D01*
G01X442168Y221259D02*
X442160Y221390D01*
G01X442174Y221024D02*
X442168Y221259D01*
G01X440441Y220412D02*
X440431Y220138D01*
G01X440447Y220429D02*
X440441Y220412D01*
G01X440452Y220365D02*
X440447Y220429D01*
G01X440440Y221390D02*
X440426Y221024D01*
G01X440447Y221412D02*
X440440Y221390D01*
G01X440454Y221327D02*
X440447Y221412D01*
G01X440518Y219853D02*
X440505Y220340D01*
G01X440524Y219464D02*
X440518Y219853D01*
G01X440529Y218993D02*
X440524Y219464D01*
G01X440534Y218453D02*
X440529Y218993D01*
G01X440537Y217857D02*
X440534Y218453D01*
G01X440539Y217224D02*
X440537Y217857D01*
G01X440539Y216570D02*
Y217224D01*
G01X440513Y219013D02*
X440503Y219379D01*
G01X440517Y218722D02*
X440513Y219013D01*
G01X440521Y218368D02*
X440517Y218722D01*
G01X440524Y217963D02*
X440521Y218368D01*
G01X440526Y217516D02*
X440524Y217963D01*
G01X440528Y217041D02*
X440526Y217516D01*
G01X440528Y216551D02*
Y217041D01*
G01X438227Y225965D02*
X438237Y226239D01*
G01X438221Y225948D02*
X438227Y225965D01*
G01X438216Y226012D02*
X438221Y225948D01*
G01X438228Y224988D02*
X438242Y225353D01*
G01X438221Y224965D02*
X438228Y224988D01*
G01X438214Y225050D02*
X438221Y224965D01*
G01X438150Y226524D02*
X438163Y226037D01*
G01X438144Y226913D02*
X438150Y226524D01*
G01X438139Y227384D02*
X438144Y226913D01*
G01X438134Y227925D02*
X438139Y227384D01*
G01X438131Y228520D02*
X438134Y227925D01*
G01X438129Y229153D02*
X438131Y228520D01*
G01X438129Y229807D02*
Y229153D01*
G01X438124Y231677D02*
X438116Y231750D01*
G01X438127Y231547D02*
X438124Y231677D01*
G01X438131Y231359D02*
X438127Y231547D01*
G01X438134Y231120D02*
X438131Y231359D01*
G01X438136Y230838D02*
X438134Y231120D01*
G01X438138Y230521D02*
X438136Y230838D01*
G01X438139Y230180D02*
X438138Y230521D01*
G01X438140Y229826D02*
X438139Y230180D01*
G01X438155Y227364D02*
X438165Y226999D01*
G01X438151Y227656D02*
X438155Y227364D01*
G01X438147Y228009D02*
X438151Y227656D01*
G01X438144Y228414D02*
X438147Y228009D01*
G01X438142Y228861D02*
X438144Y228414D01*
G01X438140Y229336D02*
X438142Y228861D01*
G01X438140Y229826D02*
Y229336D01*
G01X436509Y225965D02*
X436520Y226012D01*
G01X436504Y226063D02*
X436509Y225965D01*
G01X436498Y226239D02*
X436504Y226063D01*
G01X436594Y228861D02*
X436596Y229826D01*
G01X436592Y228414D02*
X436594Y228861D01*
G01X436589Y228009D02*
X436592Y228414D01*
G01X436585Y227656D02*
X436589Y228009D01*
G01X436580Y227364D02*
X436585Y227656D01*
G01X436575Y227143D02*
X436580Y227364D01*
G01X436570Y226999D02*
X436575Y227143D01*
G01X436598Y230521D02*
X436596Y229826D01*
G01X436600Y230838D02*
X436598Y230521D01*
G01X436602Y231120D02*
X436600Y230838D01*
G01X436605Y231359D02*
X436602Y231120D01*
G01X436608Y231547D02*
X436605Y231359D01*
G01X436612Y231677D02*
X436608Y231547D01*
G01X436616Y231746D02*
X436612Y231677D01*
G01X436620Y231750D02*
X436616Y231746D01*
G01X436604Y228520D02*
X436607Y229807D01*
G01X436601Y227925D02*
X436604Y228520D01*
G01X436597Y227384D02*
X436601Y227925D01*
G01X436592Y226913D02*
X436597Y227384D01*
G01X436586Y226524D02*
X436592Y226913D01*
G01X436580Y226230D02*
X436586Y226524D01*
G01X436573Y226037D02*
X436580Y226230D01*
G01X436508Y224988D02*
X436522Y225050D01*
G01X436500Y225118D02*
X436508Y224988D01*
G01X436494Y225353D02*
X436500Y225118D01*
G01Y220412D02*
X436489Y220138D01*
G01X436505Y220429D02*
X436500Y220412D01*
G01X436510Y220365D02*
X436505Y220429D01*
G01X436498Y221390D02*
X436484Y221024D01*
G01X436506Y221412D02*
X436498Y221390D01*
G01X436513Y221327D02*
X436506Y221412D01*
G01X436577Y219853D02*
X436563Y220340D01*
G01X436583Y219464D02*
X436577Y219853D01*
G01X436588Y218993D02*
X436583Y219464D01*
G01X436592Y218453D02*
X436588Y218993D01*
G01X436595Y217857D02*
X436592Y218453D01*
G01X436597Y217224D02*
X436595Y217857D01*
G01X436598Y216570D02*
X436597Y217224D01*
G01X436603Y214700D02*
X436610Y214627D01*
G01X436599Y214830D02*
X436603Y214700D01*
G01X436596Y215018D02*
X436599Y214830D01*
G01X436593Y215257D02*
X436596Y215018D01*
G01X436590Y215540D02*
X436593Y215257D01*
G01X436588Y215857D02*
X436590Y215540D01*
G01X436587Y216198D02*
X436588Y215857D01*
G01X436587Y216551D02*
Y216198D01*
G01X436571Y219013D02*
X436561Y219379D01*
G01X436575Y218722D02*
X436571Y219013D01*
G01X436579Y218368D02*
X436575Y218722D01*
G01X436582Y217963D02*
X436579Y218368D01*
G01X436585Y217516D02*
X436582Y217963D01*
G01X436586Y217041D02*
X436585Y217516D01*
G01X436587Y216551D02*
X436586Y217041D01*
G01X438217Y220412D02*
X438207Y220365D01*
G01X438223Y220314D02*
X438217Y220412D01*
G01X438228Y220138D02*
X438223Y220314D01*
G01X438132Y217516D02*
X438130Y216551D01*
G01X438135Y217963D02*
X438132Y217516D01*
G01X438138Y218368D02*
X438135Y217963D01*
G01X438141Y218722D02*
X438138Y218368D01*
G01X438146Y219013D02*
X438141Y218722D01*
G01X438151Y219234D02*
X438146Y219013D01*
G01X438156Y219379D02*
X438151Y219234D01*
G01X438129Y215857D02*
X438130Y216551D01*
G01X438127Y215540D02*
X438129Y215857D01*
G01X438124Y215257D02*
X438127Y215540D01*
G01X438121Y215018D02*
X438124Y215257D01*
G01X438118Y214830D02*
X438121Y215018D01*
G01X438114Y214700D02*
X438118Y214830D01*
G01X438111Y214632D02*
X438114Y214700D01*
G01X438107Y214627D02*
X438111Y214632D01*
G01X438122Y217857D02*
X438119Y216570D01*
G01X438125Y218453D02*
X438122Y217857D01*
G01X438129Y218993D02*
X438125Y218453D01*
G01X438134Y219464D02*
X438129Y218993D01*
G01X438140Y219853D02*
X438134Y219464D01*
G01X438147Y220148D02*
X438140Y219853D01*
G01X438154Y220340D02*
X438147Y220148D01*
G01X438219Y221390D02*
X438204Y221327D01*
G01X438226Y221259D02*
X438219Y221390D01*
G01X438233Y221024D02*
X438226Y221259D01*
G01X432567Y225965D02*
X432578Y226012D01*
G01X432562Y226063D02*
X432567Y225965D01*
G01X432557Y226239D02*
X432562Y226063D01*
G01X432652Y228861D02*
X432654Y229826D01*
G01X432650Y228414D02*
X432652Y228861D01*
G01X432647Y228009D02*
X432650Y228414D01*
G01X432643Y227656D02*
X432647Y228009D01*
G01X432639Y227364D02*
X432643Y227656D01*
G01X432634Y227143D02*
X432639Y227364D01*
G01X432629Y226999D02*
X432634Y227143D01*
G01X432663Y228520D02*
X432665Y229807D01*
G01X432660Y227925D02*
X432663Y228520D01*
G01X432655Y227384D02*
X432660Y227925D01*
G01X432650Y226913D02*
X432655Y227384D01*
G01X432644Y226524D02*
X432650Y226913D01*
G01X432638Y226230D02*
X432644Y226524D01*
G01X432631Y226037D02*
X432638Y226230D01*
G01X432566Y224988D02*
X432580Y225050D01*
G01X432559Y225118D02*
X432566Y224988D01*
G01X432552Y225353D02*
X432559Y225118D01*
G01X434285Y225965D02*
X434296Y226239D01*
G01X434280Y225948D02*
X434285Y225965D01*
G01X434274Y226012D02*
X434280Y225948D01*
G01X434286Y224988D02*
X434300Y225353D01*
G01X434279Y224965D02*
X434286Y224988D01*
G01X434272Y225050D02*
X434279Y224965D01*
G01X434208Y226524D02*
X434221Y226037D01*
G01X434202Y226913D02*
X434208Y226524D01*
G01X434197Y227384D02*
X434202Y226913D01*
G01X434193Y227925D02*
X434197Y227384D01*
G01X434190Y228520D02*
X434193Y227925D01*
G01X434188Y229153D02*
X434190Y228520D01*
G01X434187Y229807D02*
X434188Y229153D01*
G01X434214Y227364D02*
X434224Y226999D01*
G01X434209Y227656D02*
X434214Y227364D01*
G01X434205Y228009D02*
X434209Y227656D01*
G01X434202Y228414D02*
X434205Y228009D01*
G01X434200Y228861D02*
X434202Y228414D01*
G01X434198Y229336D02*
X434200Y228861D01*
G01X434198Y229826D02*
Y229336D01*
G01X434285Y220412D02*
X434274Y220365D01*
G01X434290Y220314D02*
X434285Y220412D01*
G01X434296Y220138D02*
X434290Y220314D01*
G01X434200Y217516D02*
X434198Y216551D01*
G01X434202Y217963D02*
X434200Y217516D01*
G01X434205Y218368D02*
X434202Y217963D01*
G01X434209Y218722D02*
X434205Y218368D01*
G01X434214Y219013D02*
X434209Y218722D01*
G01X434218Y219234D02*
X434214Y219013D01*
G01X434224Y219379D02*
X434218Y219234D01*
G01X434190Y217857D02*
X434187Y216570D01*
G01X434193Y218453D02*
X434190Y217857D01*
G01X434197Y218993D02*
X434193Y218453D01*
G01X434202Y219464D02*
X434197Y218993D01*
G01X434208Y219853D02*
X434202Y219464D01*
G01X434214Y220148D02*
X434208Y219853D01*
G01X434221Y220340D02*
X434214Y220148D01*
G01X434286Y221390D02*
X434272Y221327D01*
G01X434294Y221259D02*
X434286Y221390D01*
G01X434300Y221024D02*
X434294Y221259D01*
G01X432567Y220412D02*
X432557Y220138D01*
G01X432573Y220429D02*
X432567Y220412D01*
G01X432578Y220365D02*
X432573Y220429D01*
G01X432566Y221390D02*
X432552Y221024D01*
G01X432573Y221412D02*
X432566Y221390D01*
G01X432580Y221327D02*
X432573Y221412D01*
G01X432644Y219853D02*
X432631Y220340D01*
G01X432650Y219464D02*
X432644Y219853D01*
G01X432655Y218993D02*
X432650Y219464D01*
G01X432660Y218453D02*
X432655Y218993D01*
G01X432663Y217857D02*
X432660Y218453D01*
G01X432665Y217224D02*
X432663Y217857D01*
G01X432665Y216570D02*
Y217224D01*
G01X432639Y219013D02*
X432629Y219379D01*
G01X432643Y218722D02*
X432639Y219013D01*
G01X432647Y218368D02*
X432643Y218722D01*
G01X432650Y217963D02*
X432647Y218368D01*
G01X432652Y217516D02*
X432650Y217963D01*
G01X432654Y217041D02*
X432652Y217516D01*
G01X432654Y216551D02*
Y217041D01*
G01X430353Y225965D02*
X430363Y226239D01*
G01X430347Y225948D02*
X430353Y225965D01*
G01X430342Y226012D02*
X430347Y225948D01*
G01X430354Y224988D02*
X430368Y225353D01*
G01X430347Y224965D02*
X430354Y224988D01*
G01X430340Y225050D02*
X430347Y224965D01*
G01X430276Y226524D02*
X430289Y226037D01*
G01X430270Y226913D02*
X430276Y226524D01*
G01X430265Y227384D02*
X430270Y226913D01*
G01X430260Y227925D02*
X430265Y227384D01*
G01X430257Y228520D02*
X430260Y227925D01*
G01X430255Y229153D02*
X430257Y228520D01*
G01X430255Y229807D02*
Y229153D01*
G01X430250Y231677D02*
X430242Y231750D01*
G01X430253Y231547D02*
X430250Y231677D01*
G01X430257Y231359D02*
X430253Y231547D01*
G01X430260Y231120D02*
X430257Y231359D01*
G01X430262Y230838D02*
X430260Y231120D01*
G01X430264Y230521D02*
X430262Y230838D01*
G01X430265Y230180D02*
X430264Y230521D01*
G01X430265Y229826D02*
Y230180D01*
G01X430281Y227364D02*
X430291Y226999D01*
G01X430277Y227656D02*
X430281Y227364D01*
G01X430273Y228009D02*
X430277Y227656D01*
G01X430270Y228414D02*
X430273Y228009D01*
G01X430268Y228861D02*
X430270Y228414D01*
G01X430266Y229336D02*
X430268Y228861D01*
G01X430265Y229826D02*
X430266Y229336D01*
G01X428635Y225965D02*
X428646Y226012D01*
G01X428630Y226063D02*
X428635Y225965D01*
G01X428624Y226239D02*
X428630Y226063D01*
G01X428720Y228861D02*
X428722Y229826D01*
G01X428718Y228414D02*
X428720Y228861D01*
G01X428715Y228009D02*
X428718Y228414D01*
G01X428711Y227656D02*
X428715Y228009D01*
G01X428706Y227364D02*
X428711Y227656D01*
G01X428701Y227143D02*
X428706Y227364D01*
G01X428696Y226999D02*
X428701Y227143D01*
G01X428724Y230521D02*
X428722Y229826D01*
G01X428726Y230838D02*
X428724Y230521D01*
G01X428728Y231120D02*
X428726Y230838D01*
G01X428731Y231359D02*
X428728Y231120D01*
G01X428734Y231547D02*
X428731Y231359D01*
G01X428738Y231677D02*
X428734Y231547D01*
G01X428742Y231746D02*
X428738Y231677D01*
G01X428746Y231750D02*
X428742Y231746D01*
G01X428730Y228520D02*
X428733Y229807D01*
G01X428727Y227925D02*
X428730Y228520D01*
G01X428723Y227384D02*
X428727Y227925D01*
G01X428718Y226913D02*
X428723Y227384D01*
G01X428712Y226524D02*
X428718Y226913D01*
G01X428706Y226230D02*
X428712Y226524D01*
G01X428699Y226037D02*
X428706Y226230D01*
G01X428634Y224988D02*
X428648Y225050D01*
G01X428626Y225118D02*
X428634Y224988D01*
G01X428620Y225353D02*
X428626Y225118D01*
G01Y220412D02*
X428615Y220138D01*
G01X428631Y220429D02*
X428626Y220412D01*
G01X428636Y220365D02*
X428631Y220429D01*
G01X428624Y221390D02*
X428610Y221024D01*
G01X428632Y221412D02*
X428624Y221390D01*
G01X428639Y221327D02*
X428632Y221412D01*
G01X428703Y219853D02*
X428689Y220340D01*
G01X428709Y219464D02*
X428703Y219853D01*
G01X428714Y218993D02*
X428709Y219464D01*
G01X428718Y218453D02*
X428714Y218993D01*
G01X428721Y217857D02*
X428718Y218453D01*
G01X428723Y217224D02*
X428721Y217857D01*
G01X428724Y216570D02*
X428723Y217224D01*
G01X428729Y214700D02*
X428736Y214627D01*
G01X428725Y214830D02*
X428729Y214700D01*
G01X428722Y215018D02*
X428725Y214830D01*
G01X428719Y215257D02*
X428722Y215018D01*
G01X428716Y215540D02*
X428719Y215257D01*
G01X428714Y215857D02*
X428716Y215540D01*
G01X428713Y216198D02*
X428714Y215857D01*
G01X428713Y216551D02*
Y216198D01*
G01X428697Y219013D02*
X428687Y219379D01*
G01X428701Y218722D02*
X428697Y219013D01*
G01X428705Y218368D02*
X428701Y218722D01*
G01X428708Y217963D02*
X428705Y218368D01*
G01X428711Y217516D02*
X428708Y217963D01*
G01X428712Y217041D02*
X428711Y217516D01*
G01X428713Y216551D02*
X428712Y217041D01*
G01X430343Y220412D02*
X430333Y220365D01*
G01X430349Y220314D02*
X430343Y220412D01*
G01X430354Y220138D02*
X430349Y220314D01*
G01X430258Y217516D02*
X430256Y216551D01*
G01X430261Y217963D02*
X430258Y217516D01*
G01X430264Y218368D02*
X430261Y217963D01*
G01X430267Y218722D02*
X430264Y218368D01*
G01X430272Y219013D02*
X430267Y218722D01*
G01X430277Y219234D02*
X430272Y219013D01*
G01X430282Y219379D02*
X430277Y219234D01*
G01X430255Y215857D02*
X430256Y216551D01*
G01X430253Y215540D02*
X430255Y215857D01*
G01X430250Y215257D02*
X430253Y215540D01*
G01X430247Y215018D02*
X430250Y215257D01*
G01X430244Y214830D02*
X430247Y215018D01*
G01X430240Y214700D02*
X430244Y214830D01*
G01X430236Y214632D02*
X430240Y214700D01*
G01X430233Y214627D02*
X430236Y214632D01*
G01X430248Y217857D02*
X430245Y216570D01*
G01X430251Y218453D02*
X430248Y217857D01*
G01X430255Y218993D02*
X430251Y218453D01*
G01X430260Y219464D02*
X430255Y218993D01*
G01X430266Y219853D02*
X430260Y219464D01*
G01X430273Y220148D02*
X430266Y219853D01*
G01X430280Y220340D02*
X430273Y220148D01*
G01X430345Y221390D02*
X430330Y221327D01*
G01X430352Y221259D02*
X430345Y221390D01*
G01X430359Y221024D02*
X430352Y221259D01*
G01X434175Y231754D02*
X434174Y231750D01*
G01X434175Y231756D02*
Y231754D01*
G01X434176Y231756D02*
X434175D01*
G01X442049Y231754D02*
X442048Y231750D01*
G01X442049Y231756D02*
Y231754D01*
G01X442050Y231756D02*
X442049D01*
G01X432678Y214624D02*
Y214627D01*
G01X432677Y214622D02*
X432678Y214624D01*
G01X432676Y214621D02*
X432677Y214622D01*
G01X449923Y231754D02*
X449922Y231750D01*
G01X449923Y231756D02*
Y231754D01*
G01X449924Y231756D02*
X449923D01*
G01X440552Y214624D02*
Y214627D01*
G01X440551Y214622D02*
X440552Y214624D01*
G01X440550Y214621D02*
X440551Y214622D01*
G01X448426Y214624D02*
Y214627D01*
G01X448425Y214622D02*
X448426Y214624D01*
G01X448424Y214621D02*
X448425Y214622D01*
G01X434175Y230768D02*
X434174Y230762D01*
G01X434175Y230771D02*
Y230768D01*
G01X434176Y230772D02*
X434175Y230771D01*
G01X432677Y215610D02*
X432678Y215615D01*
G01X432677Y215606D02*
Y215610D01*
G01X432676Y215605D02*
X432677Y215606D01*
G01X442049Y230768D02*
X442048Y230762D01*
G01X442049Y230771D02*
Y230768D01*
G01X442050Y230772D02*
X442049Y230771D01*
G01X440551Y215610D02*
X440552Y215615D01*
G01X440551Y215606D02*
Y215610D01*
G01X440550Y215605D02*
X440551Y215606D01*
G01X449923Y230768D02*
X449922Y230762D01*
G01X449923Y230771D02*
Y230768D01*
G01X449924Y230772D02*
X449923Y230771D01*
G01X448425Y215610D02*
X448426Y215615D01*
G01X448425Y215606D02*
Y215610D01*
G01X448424Y215605D02*
X448425Y215606D01*
G01X432656Y230573D02*
X432654Y229826D01*
G01X432661Y231193D02*
X432656Y230573D01*
G01X432668Y231608D02*
X432661Y231193D01*
G01X432676Y231756D02*
X432668Y231608D01*
G01X434196Y215804D02*
X434198Y216551D01*
G01X434191Y215184D02*
X434196Y215804D01*
G01X434184Y214770D02*
X434191Y215184D01*
G01X434176Y214621D02*
X434184Y214770D01*
G01X432666Y230178D02*
X432665Y229807D01*
G01X432669Y230490D02*
X432666Y230178D01*
G01X432672Y230699D02*
X432669Y230490D01*
G01X432676Y230772D02*
X432672Y230699D01*
G01X434186Y216200D02*
X434187Y216570D01*
G01X434184Y215887D02*
X434186Y216200D01*
G01X434180Y215678D02*
X434184Y215887D01*
G01X434176Y215605D02*
X434180Y215678D01*
G01X428470Y214965D02*
X428474Y215117D01*
G01X428465Y214866D02*
X428470Y214965D01*
G01X428461Y214824D02*
X428465Y214866D01*
G01X430508Y231413D02*
X430504Y231260D01*
G01X430513Y231511D02*
X430508Y231413D01*
G01X430517Y231553D02*
X430513Y231511D01*
G01X432412Y214965D02*
X432416Y215117D01*
G01X432407Y214866D02*
X432412Y214965D01*
G01X432403Y214824D02*
X432407Y214866D01*
G01X434441Y231413D02*
X434437Y231260D01*
G01X434445Y231511D02*
X434441Y231413D01*
G01X434450Y231553D02*
X434445Y231511D01*
G01X436344Y214965D02*
X436348Y215117D01*
G01X436339Y214866D02*
X436344Y214965D01*
G01X436335Y214824D02*
X436339Y214866D01*
G01X438382Y231413D02*
X438378Y231260D01*
G01X438387Y231511D02*
X438382Y231413D01*
G01X438391Y231553D02*
X438387Y231511D01*
G01X440286Y214965D02*
X440290Y215117D01*
G01X440281Y214866D02*
X440286Y214965D01*
G01X440277Y214824D02*
X440281Y214866D01*
G01X442315Y231413D02*
X442311Y231260D01*
G01X442319Y231511D02*
X442315Y231413D01*
G01X442324Y231553D02*
X442319Y231511D01*
G01X430505Y232353D02*
X430499Y232147D01*
G01X430511Y232484D02*
X430505Y232353D01*
G01X430517Y232538D02*
X430511Y232484D01*
G01X428473Y214024D02*
X428479Y214231D01*
G01X428467Y213893D02*
X428473Y214024D01*
G01X428461Y213840D02*
X428467Y213893D01*
G01X434438Y232353D02*
X434432Y232147D01*
G01X434444Y232484D02*
X434438Y232353D01*
G01X434450Y232538D02*
X434444Y232484D01*
G01X432415Y214024D02*
X432421Y214231D01*
G01X432409Y213893D02*
X432415Y214024D01*
G01X432403Y213840D02*
X432409Y213893D01*
G01X438379Y232353D02*
X438373Y232147D01*
G01X438385Y232484D02*
X438379Y232353D01*
G01X438391Y232538D02*
X438385Y232484D01*
G01X436347Y214024D02*
X436353Y214231D01*
G01X436341Y213893D02*
X436347Y214024D01*
G01X436335Y213840D02*
X436341Y213893D01*
G01X442312Y232353D02*
X442306Y232147D01*
G01X442318Y232484D02*
X442312Y232353D01*
G01X442324Y232538D02*
X442318Y232484D01*
G01X440289Y214024D02*
X440295Y214231D01*
G01X440283Y213893D02*
X440289Y214024D01*
G01X440277Y213840D02*
X440283Y213893D01*
G01X446253Y232353D02*
X446247Y232147D01*
G01X446259Y232484D02*
X446253Y232353D01*
G01X446265Y232538D02*
X446259Y232484D01*
G01X428734Y230209D02*
X428733Y229807D01*
G01X428737Y230537D02*
X428734Y230209D01*
G01X428741Y230733D02*
X428737Y230537D01*
G01X428746Y230762D02*
X428741Y230733D01*
G01X430244Y216168D02*
X430245Y216570D01*
G01X430241Y215841D02*
X430244Y216168D01*
G01X430237Y215645D02*
X430241Y215841D01*
G01X430233Y215615D02*
X430237Y215645D01*
G01X436608Y230209D02*
X436607Y229807D01*
G01X436611Y230537D02*
X436608Y230209D01*
G01X436615Y230733D02*
X436611Y230537D01*
G01X436620Y230762D02*
X436615Y230733D01*
G01X438118Y216168D02*
X438119Y216570D01*
G01X438115Y215841D02*
X438118Y216168D01*
G01X438111Y215645D02*
X438115Y215841D01*
G01X438107Y215615D02*
X438111Y215645D01*
G01X444482Y230209D02*
X444481Y229807D01*
G01X444485Y230537D02*
X444482Y230209D01*
G01X444489Y230733D02*
X444485Y230537D01*
G01X444494Y230762D02*
X444489Y230733D01*
G01X445992Y216168D02*
X445993Y216570D01*
G01X445989Y215841D02*
X445992Y216168D01*
G01X445985Y215645D02*
X445989Y215841D01*
G01X445981Y215615D02*
X445985Y215645D01*
G01X432677Y230771D02*
X432676Y230772D01*
G01X432677Y230768D02*
Y230771D01*
G01X432678Y230762D02*
X432677Y230768D01*
G01X434175Y215606D02*
X434176Y215605D01*
G01X434175Y215610D02*
Y215606D01*
G01X434174Y215615D02*
X434175Y215610D01*
G01X428476Y232484D02*
X428470Y232538D01*
G01X428482Y232353D02*
X428476Y232484D01*
G01X428488Y232147D02*
X428482Y232353D01*
G01X430502Y213893D02*
X430508Y213840D01*
G01X430496Y214024D02*
X430502Y213893D01*
G01X430490Y214231D02*
X430496Y214024D01*
G01X432409Y232484D02*
X432403Y232538D01*
G01X432415Y232353D02*
X432409Y232484D01*
G01X432421Y232147D02*
X432415Y232353D01*
G01X434444Y213893D02*
X434450Y213840D01*
G01X434438Y214024D02*
X434444Y213893D01*
G01X434432Y214231D02*
X434438Y214024D01*
G01X436350Y232484D02*
X436344Y232538D01*
G01X436356Y232353D02*
X436350Y232484D01*
G01X436362Y232147D02*
X436356Y232353D01*
G01X438376Y213893D02*
X438382Y213840D01*
G01X438370Y214024D02*
X438376Y213893D01*
G01X438364Y214231D02*
X438370Y214024D01*
G01X440283Y232484D02*
X440277Y232538D01*
G01X440289Y232353D02*
X440283Y232484D01*
G01X440295Y232147D02*
X440289Y232353D01*
G01X442318Y213893D02*
X442324Y213840D01*
G01X442312Y214024D02*
X442318Y213893D01*
G01X442306Y214231D02*
X442312Y214024D01*
G01X444224Y232484D02*
X444218Y232538D01*
G01X444230Y232353D02*
X444224Y232484D01*
G01X444236Y232147D02*
X444230Y232353D01*
G01X446250Y213893D02*
X446256Y213840D01*
G01X446244Y214024D02*
X446250Y213893D01*
G01X446238Y214231D02*
X446244Y214024D01*
G01X448157Y232484D02*
X448151Y232538D01*
G01X448163Y232353D02*
X448157Y232484D01*
G01X448169Y232147D02*
X448163Y232353D01*
G01X428475Y231511D02*
X428470Y231553D01*
G01X428479Y231413D02*
X428475Y231511D01*
G01X428483Y231260D02*
X428479Y231413D01*
G01X430504Y214866D02*
X430508Y214824D01*
G01X430499Y214965D02*
X430504Y214866D01*
G01X430495Y215117D02*
X430499Y214965D01*
G01X432407Y231511D02*
X432403Y231553D01*
G01X432412Y231413D02*
X432407Y231511D01*
G01X432416Y231260D02*
X432412Y231413D01*
G01X434445Y214866D02*
X434450Y214824D01*
G01X434441Y214965D02*
X434445Y214866D01*
G01X434437Y215117D02*
X434441Y214965D01*
G01X436349Y231511D02*
X436344Y231553D01*
G01X436353Y231413D02*
X436349Y231511D01*
G01X436357Y231260D02*
X436353Y231413D01*
G01X438378Y214866D02*
X438382Y214824D01*
G01X438373Y214965D02*
X438378Y214866D01*
G01X438369Y215117D02*
X438373Y214965D01*
G01X440281Y231511D02*
X440277Y231553D01*
G01X440286Y231413D02*
X440281Y231511D01*
G01X440290Y231260D02*
X440286Y231413D01*
G01X442319Y214866D02*
X442324Y214824D01*
G01X442315Y214965D02*
X442319Y214866D01*
G01X442311Y215117D02*
X442315Y214965D01*
G01X444223Y231511D02*
X444218Y231553D01*
G01X444227Y231413D02*
X444223Y231511D01*
G01X444231Y231260D02*
X444227Y231413D01*
G01X446252Y214866D02*
X446256Y214824D01*
G01X446247Y214965D02*
X446252Y214866D01*
G01X446243Y215117D02*
X446247Y214965D01*
G01X448155Y231511D02*
X448151Y231553D01*
G01X448160Y231413D02*
X448155Y231511D01*
G01X448164Y231260D02*
X448160Y231413D01*
G01X428732Y215645D02*
X428736Y215615D01*
G01X428728Y215841D02*
X428732Y215645D01*
G01X428725Y216168D02*
X428728Y215841D01*
G01X428724Y216570D02*
X428725Y216168D01*
G01X430247Y230733D02*
X430242Y230762D01*
G01X430251Y230537D02*
X430247Y230733D01*
G01X430253Y230209D02*
X430251Y230537D01*
G01X430255Y229807D02*
X430253Y230209D01*
G01X436606Y215645D02*
X436610Y215615D01*
G01X436602Y215841D02*
X436606Y215645D01*
G01X436599Y216168D02*
X436602Y215841D01*
G01X436598Y216570D02*
X436599Y216168D01*
G01X438121Y230733D02*
X438116Y230762D01*
G01X438125Y230537D02*
X438121Y230733D01*
G01X438127Y230209D02*
X438125Y230537D01*
G01X438129Y229807D02*
X438127Y230209D01*
G01X444480Y215645D02*
X444484Y215615D01*
G01X444476Y215841D02*
X444480Y215645D01*
G01X444473Y216168D02*
X444476Y215841D01*
G01X444472Y216570D02*
X444473Y216168D01*
G01X445995Y230733D02*
X445990Y230762D01*
G01X445999Y230537D02*
X445995Y230733D01*
G01X446002Y230209D02*
X445999Y230537D01*
G01X446003Y229807D02*
X446002Y230209D01*
G01X432668Y214770D02*
X432676Y214621D01*
G01X432661Y215184D02*
X432668Y214770D01*
G01X432656Y215804D02*
X432661Y215184D01*
G01X432654Y216551D02*
X432656Y215804D01*
G01X432672Y215678D02*
X432676Y215605D01*
G01X432669Y215887D02*
X432672Y215678D01*
G01X432666Y216200D02*
X432669Y215887D01*
G01X432665Y216570D02*
X432666Y216200D01*
G01X434180Y230699D02*
X434176Y230772D01*
G01X434184Y230490D02*
X434180Y230699D01*
G01X434186Y230178D02*
X434184Y230490D01*
G01X434187Y229807D02*
X434186Y230178D01*
G01X434184Y231608D02*
X434176Y231756D01*
G01X434191Y231193D02*
X434184Y231608D01*
G01X434196Y230573D02*
X434191Y231193D01*
G01X434198Y229826D02*
X434196Y230573D01*
G01X440542Y214770D02*
X440550Y214621D01*
G01X440535Y215184D02*
X440542Y214770D01*
G01X440530Y215804D02*
X440535Y215184D01*
G01X440528Y216551D02*
X440530Y215804D01*
G01X440546Y215678D02*
X440550Y215605D01*
G01X440543Y215887D02*
X440546Y215678D01*
G01X440540Y216200D02*
X440543Y215887D01*
G01X440539Y216570D02*
X440540Y216200D01*
G01X442054Y230699D02*
X442050Y230772D01*
G01X442058Y230490D02*
X442054Y230699D01*
G01X442060Y230178D02*
X442058Y230490D01*
G01X442061Y229807D02*
X442060Y230178D01*
G01X442058Y231608D02*
X442050Y231756D01*
G01X442065Y231193D02*
X442058Y231608D01*
G01X442070Y230573D02*
X442065Y231193D01*
G01X442072Y229826D02*
X442070Y230573D01*
G01X448416Y214770D02*
X448424Y214621D01*
G01X448409Y215184D02*
X448416Y214770D01*
G01X448404Y215804D02*
X448409Y215184D01*
G01X448403Y216551D02*
X448404Y215804D01*
G01X448420Y215678D02*
X448424Y215605D01*
G01X448417Y215887D02*
X448420Y215678D01*
G01X448414Y216200D02*
X448417Y215887D01*
G01X448413Y216570D02*
X448414Y216200D01*
G01X449928Y230699D02*
X449924Y230772D01*
G01X449932Y230490D02*
X449928Y230699D01*
G01X449934Y230178D02*
X449932Y230490D01*
G01X449935Y229807D02*
X449934Y230178D01*
G01X449932Y231608D02*
X449924Y231756D01*
G01X449939Y231193D02*
X449932Y231608D01*
G01X449944Y230573D02*
X449939Y231193D01*
G01X449946Y229826D02*
X449944Y230573D01*
G01X440530D02*
X440528Y229826D01*
G01X440535Y231193D02*
X440530Y230573D01*
G01X440542Y231608D02*
X440535Y231193D01*
G01X440550Y231756D02*
X440542Y231608D01*
G01X442070Y215804D02*
X442072Y216551D01*
G01X442065Y215184D02*
X442070Y215804D01*
G01X442058Y214770D02*
X442065Y215184D01*
G01X442050Y214621D02*
X442058Y214770D01*
G01X448404Y230573D02*
X448403Y229826D01*
G01X448409Y231193D02*
X448404Y230573D01*
G01X448416Y231608D02*
X448409Y231193D01*
G01X448424Y231756D02*
X448416Y231608D01*
G01X449944Y215804D02*
X449946Y216551D01*
G01X449939Y215184D02*
X449944Y215804D01*
G01X449932Y214770D02*
X449939Y215184D01*
G01X449924Y214621D02*
X449932Y214770D01*
G01X440540Y230178D02*
X440539Y229807D01*
G01X440543Y230490D02*
X440540Y230178D01*
G01X440546Y230699D02*
X440543Y230490D01*
G01X440550Y230772D02*
X440546Y230699D01*
G01X442060Y216200D02*
X442061Y216570D01*
G01X442058Y215887D02*
X442060Y216200D01*
G01X442054Y215678D02*
X442058Y215887D01*
G01X442050Y215605D02*
X442054Y215678D01*
G01X448414Y230178D02*
X448413Y229807D01*
G01X448417Y230490D02*
X448414Y230178D01*
G01X448420Y230699D02*
X448417Y230490D01*
G01X448424Y230772D02*
X448420Y230699D01*
G01X449934Y216200D02*
X449935Y216570D01*
G01X449932Y215887D02*
X449934Y216200D01*
G01X449928Y215678D02*
X449932Y215887D01*
G01X449924Y215605D02*
X449928Y215678D01*
G01X444218Y214965D02*
X444222Y215117D01*
G01X444213Y214866D02*
X444218Y214965D01*
G01X444209Y214824D02*
X444213Y214866D01*
G01X446257Y231413D02*
X446252Y231260D01*
G01X446261Y231511D02*
X446257Y231413D01*
G01X446265Y231553D02*
X446261Y231511D01*
G01X448160Y214965D02*
X448164Y215117D01*
G01X448155Y214866D02*
X448160Y214965D01*
G01X448151Y214824D02*
X448155Y214866D01*
G01X450189Y231413D02*
X450185Y231260D01*
G01X450193Y231511D02*
X450189Y231413D01*
G01X450198Y231553D02*
X450193Y231511D01*
G01X444221Y214024D02*
X444227Y214231D01*
G01X444215Y213893D02*
X444221Y214024D01*
G01X444209Y213840D02*
X444215Y213893D01*
G01X450186Y232353D02*
X450180Y232147D01*
G01X450192Y232484D02*
X450186Y232353D01*
G01X450198Y232538D02*
X450192Y232484D01*
G01X448163Y214024D02*
X448169Y214231D01*
G01X448157Y213893D02*
X448163Y214024D01*
G01X448151Y213840D02*
X448157Y213893D01*
G01X448121Y214823D02*
X448106Y214822D01*
G01X448136Y214823D02*
X448121D01*
G01X448151Y214824D02*
X448136Y214823D01*
G01X444179D02*
X444164Y214822D01*
G01X444194Y214823D02*
X444179D01*
G01X444209Y214824D02*
X444194Y214823D01*
G01X440247D02*
X440232Y214822D01*
G01X440262Y214823D02*
X440247D01*
G01X440277Y214824D02*
X440262Y214823D01*
G01X436305D02*
X436290Y214822D01*
G01X436320Y214823D02*
X436305D01*
G01X436335Y214824D02*
X436320Y214823D01*
G01X432373D02*
X432358Y214822D01*
G01X432388Y214823D02*
X432373D01*
G01X432403Y214824D02*
X432388Y214823D01*
G01X428431D02*
X428416Y214822D01*
G01X428446Y214823D02*
X428431D01*
G01X428461Y214824D02*
X428446Y214823D01*
G01X448121Y213838D02*
X448106D01*
G01X448136Y213839D02*
X448121Y213838D01*
G01X448151Y213840D02*
X448136Y213839D01*
G01X444179Y213838D02*
X444164D01*
G01X444194Y213839D02*
X444179Y213838D01*
G01X444209Y213840D02*
X444194Y213839D01*
G01X440247Y213838D02*
X440232D01*
G01X440262Y213839D02*
X440247Y213838D01*
G01X440277Y213840D02*
X440262Y213839D01*
G01X436305Y213838D02*
X436290D01*
G01X436320Y213839D02*
X436305Y213838D01*
G01X436335Y213840D02*
X436320Y213839D01*
G01X432373Y213838D02*
X432358D01*
G01X432388Y213839D02*
X432373Y213838D01*
G01X432403Y213840D02*
X432388Y213839D01*
G01X428431Y213838D02*
X428416D01*
G01X428446Y213839D02*
X428431Y213838D01*
G01X428461Y213840D02*
X428446Y213839D01*
G01X440551Y230771D02*
X440550Y230772D01*
G01X440551Y230768D02*
Y230771D01*
G01X440552Y230762D02*
X440551Y230768D01*
G01X442049Y215606D02*
X442050Y215605D01*
G01X442049Y215610D02*
Y215606D01*
G01X442048Y215615D02*
X442049Y215610D01*
G01X448425Y230771D02*
X448424Y230772D01*
G01X448425Y230768D02*
Y230771D01*
G01X448426Y230762D02*
X448425Y230768D01*
G01X449923Y215606D02*
X449924Y215605D01*
G01X449923Y215610D02*
Y215606D01*
G01X449922Y215615D02*
X449923Y215610D01*
G01X450192Y213893D02*
X450198Y213840D01*
G01X450186Y214024D02*
X450192Y213893D01*
G01X450180Y214231D02*
X450186Y214024D01*
G01X450193Y214866D02*
X450198Y214824D01*
G01X450189Y214965D02*
X450193Y214866D01*
G01X450185Y215117D02*
X450189Y214965D01*
G01X450228Y231555D02*
X450243D01*
G01X450213Y231554D02*
X450228Y231555D01*
G01X450198Y231553D02*
X450213Y231554D01*
G01X442354Y231555D02*
X442369D01*
G01X442339Y231554D02*
X442354Y231555D01*
G01X442324Y231553D02*
X442339Y231554D01*
G01X434480Y231555D02*
X434495D01*
G01X434465Y231554D02*
X434480Y231555D01*
G01X434450Y231553D02*
X434465Y231554D01*
G01X430547Y231555D02*
X430562D01*
G01X430532Y231554D02*
X430547Y231555D01*
G01X430517Y231553D02*
X430532Y231554D01*
G01X450228Y232539D02*
X450243D01*
G01X450213Y232538D02*
X450228Y232539D01*
G01X450198Y232538D02*
X450213D01*
G01X446295Y232539D02*
X446311D01*
G01X446280Y232538D02*
X446295Y232539D01*
G01X446265Y232538D02*
X446280D01*
G01X442354Y232539D02*
X442369D01*
G01X442339Y232538D02*
X442354Y232539D01*
G01X442324Y232538D02*
X442339D01*
G01X438421Y232539D02*
X438436D01*
G01X438406Y232538D02*
X438421Y232539D01*
G01X438391Y232538D02*
X438406D01*
G01X434480Y232539D02*
X434495D01*
G01X434465Y232538D02*
X434480Y232539D01*
G01X434450Y232538D02*
X434465D01*
G01X430547Y232539D02*
X430562D01*
G01X430532Y232538D02*
X430547Y232539D01*
G01X430517Y232538D02*
X430532D01*
G01X430523Y213839D02*
X430508Y213840D01*
G01X430538Y213838D02*
X430523Y213839D01*
G01X430553Y213838D02*
X430538D01*
G01X434465Y213839D02*
X434450Y213840D01*
G01X434480Y213838D02*
X434465Y213839D01*
G01X434495Y213838D02*
X434480D01*
G01X438397Y213839D02*
X438382Y213840D01*
G01X438412Y213838D02*
X438397Y213839D01*
G01X438427Y213838D02*
X438412D01*
G01X442339Y213839D02*
X442324Y213840D01*
G01X442354Y213838D02*
X442339Y213839D01*
G01X442369Y213838D02*
X442354D01*
G01X446271Y213839D02*
X446256Y213840D01*
G01X446286Y213838D02*
X446271Y213839D01*
G01X446301Y213838D02*
X446286D01*
G01X450213Y213839D02*
X450198Y213840D01*
G01X450228Y213838D02*
X450213Y213839D01*
G01X450243Y213838D02*
X450228D01*
G01X428455Y232538D02*
X428470D01*
G01X428440Y232539D02*
X428455Y232538D01*
G01X428425Y232539D02*
X428440D01*
G01X432388Y232538D02*
X432403D01*
G01X432373Y232539D02*
X432388Y232538D01*
G01X432358Y232539D02*
X432373D01*
G01X436329Y232538D02*
X436344D01*
G01X436314Y232539D02*
X436329Y232538D01*
G01X436299Y232539D02*
X436314D01*
G01X440262Y232538D02*
X440277D01*
G01X440247Y232539D02*
X440262Y232538D01*
G01X440232Y232539D02*
X440247D01*
G01X444203Y232538D02*
X444218D01*
G01X444188Y232539D02*
X444203Y232538D01*
G01X444173Y232539D02*
X444188D01*
G01X448136Y232538D02*
X448151D01*
G01X448121Y232539D02*
X448136Y232538D01*
G01X448106Y232539D02*
X448121D01*
G01X430523Y214823D02*
X430508Y214824D01*
G01X430538Y214823D02*
X430523D01*
G01X430553Y214822D02*
X430538Y214823D01*
G01X434465D02*
X434450Y214824D01*
G01X434480Y214823D02*
X434465D01*
G01X434495Y214822D02*
X434480Y214823D01*
G01X438397D02*
X438382Y214824D01*
G01X438412Y214823D02*
X438397D01*
G01X438427Y214822D02*
X438412Y214823D01*
G01X442339D02*
X442324Y214824D01*
G01X442354Y214823D02*
X442339D01*
G01X442369Y214822D02*
X442354Y214823D01*
G01X446271D02*
X446256Y214824D01*
G01X446286Y214823D02*
X446271D01*
G01X446301Y214822D02*
X446286Y214823D01*
G01X432388Y231554D02*
X432403Y231553D01*
G01X432373Y231555D02*
X432388Y231554D01*
G01X432358Y231555D02*
X432373D01*
G01X436329Y231554D02*
X436344Y231553D01*
G01X436314Y231555D02*
X436329Y231554D01*
G01X436299Y231555D02*
X436314D01*
G01X440262Y231554D02*
X440277Y231553D01*
G01X440247Y231555D02*
X440262Y231554D01*
G01X440232Y231555D02*
X440247D01*
G01X444203Y231554D02*
X444218Y231553D01*
G01X444188Y231555D02*
X444203Y231554D01*
G01X444173Y231555D02*
X444188D01*
G01X448136Y231554D02*
X448151Y231553D01*
G01X448121Y231555D02*
X448136Y231554D01*
G01X448106Y231555D02*
X448121D01*
G01X450228Y214823D02*
X450243Y214822D01*
G01X450213Y214823D02*
X450228D01*
G01X450198Y214824D02*
X450213Y214823D01*
G01X434175Y214622D02*
X434176Y214621D01*
G01X434175Y214624D02*
Y214622D01*
G01X434174Y214627D02*
X434175Y214624D01*
G01X432677Y231756D02*
X432676D01*
G01X432678Y231754D02*
X432677Y231756D01*
G01X432678Y231750D02*
Y231754D01*
G01X442049Y214622D02*
X442050Y214621D01*
G01X442049Y214624D02*
Y214622D01*
G01X442048Y214627D02*
X442049Y214624D01*
G01X440551Y231756D02*
X440550D01*
G01X440552Y231754D02*
X440551Y231756D01*
G01X440552Y231750D02*
Y231754D01*
G01X449923Y214622D02*
X449924Y214621D01*
G01X449923Y214624D02*
Y214622D01*
G01X449922Y214627D02*
X449923Y214624D01*
G01X448425Y231756D02*
X448424D01*
G01X448426Y231754D02*
X448425Y231756D01*
G01X448426Y231750D02*
Y231754D01*
G01X428440Y231555D02*
X428425D01*
G01X428455Y231554D02*
X428440Y231555D01*
G01X428470Y231553D02*
X428455Y231554D01*
G01X430221Y214640D02*
X430233Y214627D01*
G01X428736D02*
X428748Y214640D01*
G01X430316Y218680D02*
X430158Y218717D01*
G01X428820D02*
X428662Y218680D01*
G01X430316Y217621D02*
X430158Y217696D01*
G01X428820D02*
X428662Y217621D01*
G01Y227698D02*
X428820Y227660D01*
G01X430158D02*
X430316Y227698D01*
G01X428662Y228756D02*
X428820Y228681D01*
G01X430158D02*
X430316Y228756D01*
G01X428757Y231737D02*
X428746Y231750D01*
G01X430242D02*
X430230Y231737D01*
G01X432599Y209981D02*
X432757Y209943D01*
G01X434095D02*
X434253Y209981D01*
G01X432599Y211039D02*
X432757Y210965D01*
G01X434095D02*
X434253Y211039D01*
G01X432678Y214627D02*
X432690Y214640D01*
G01X434163D02*
X434174Y214627D01*
G01X434253Y236396D02*
X434095Y236434D01*
G01X432757D02*
X432599Y236396D01*
G01X434253Y235338D02*
X434095Y235412D01*
G01X432757D02*
X432599Y235338D01*
G01X432690Y231737D02*
X432678Y231750D01*
G01X434174D02*
X434163Y231737D01*
G01X438095Y214640D02*
X438107Y214627D01*
G01X436610D02*
X436622Y214640D01*
G01X438190Y218680D02*
X438032Y218717D01*
G01X436694D02*
X436536Y218680D01*
G01X438190Y217621D02*
X438032Y217696D01*
G01X436694D02*
X436536Y217621D01*
G01Y227698D02*
X436694Y227660D01*
G01X436536Y228756D02*
X436694Y228681D01*
G01X438032D02*
X438190Y228756D01*
G01X438032Y227660D02*
X438190Y227698D01*
G01X438436Y231555D02*
X438391Y231553D01*
G01X436631Y231737D02*
X436620Y231750D01*
G01X438116D02*
X438104Y231737D01*
G01X440473Y209981D02*
X440631Y209943D01*
G01X441969D02*
X442127Y209981D01*
G01X440473Y211039D02*
X440631Y210965D01*
G01X441969D02*
X442127Y211039D01*
G01X440552Y214627D02*
X440564Y214640D01*
G01X442037D02*
X442048Y214627D01*
G01X442127Y236396D02*
X441969Y236434D01*
G01X440631D02*
X440473Y236396D01*
G01X442127Y235338D02*
X441969Y235412D01*
G01X440631D02*
X440473Y235338D01*
G01X440564Y231737D02*
X440552Y231750D01*
G01X442048D02*
X442037Y231737D01*
G01X445969Y214640D02*
X445981Y214627D01*
G01X444484D02*
X444496Y214640D01*
G01X446064Y218680D02*
X445906Y218717D01*
G01X444568D02*
X444410Y218680D01*
G01X446064Y217621D02*
X445906Y217696D01*
G01X444568D02*
X444410Y217621D01*
G01Y227698D02*
X444568Y227660D01*
G01X444410Y228756D02*
X444568Y228681D01*
G01X445906D02*
X446064Y228756D01*
G01X445906Y227660D02*
X446064Y227698D01*
G01X446311Y231555D02*
X446265Y231553D01*
G01X444505Y231737D02*
X444494Y231750D01*
G01X445990D02*
X445978Y231737D01*
G01X448347Y209981D02*
X448505Y209943D01*
G01X449843D02*
X450001Y209981D01*
G01X448347Y211039D02*
X448505Y210965D01*
G01X449843D02*
X450001Y211039D01*
G01X449911Y214640D02*
X449922Y214627D01*
G01X448426D02*
X448438Y214640D01*
G01X450001Y236396D02*
X449843Y236434D01*
G01X448505D02*
X448347Y236396D01*
G01X450001Y235338D02*
X449843Y235412D01*
G01X448505D02*
X448347Y235338D01*
G01X448438Y231737D02*
X448426Y231750D01*
G01X449922D02*
X449911Y231737D01*
G01X459391Y223189D02*
G03I-3130J0D01*
G01X460493D02*
G03I-4232J0D01*
G01X460887D02*
G03I-4626J0D01*
G01X454618Y219645D02*
X456576Y216693D01*
G01X448438Y231737D02*
X448692Y231368D01*
G01X448646Y230441D02*
X448425Y230762D01*
G01X444505Y231737D02*
X444759Y231368D01*
G01X444714Y230441D02*
X444492Y230762D01*
G01X440564Y231737D02*
X440818Y231368D01*
G01X440772Y230441D02*
X440551Y230762D01*
G01X449702Y215937D02*
X449924Y215615D01*
G01X449911Y214640D02*
X449657Y215009D01*
G01X436631Y231737D02*
X436885Y231368D01*
G01X436840Y230441D02*
X436618Y230762D01*
G01X445761Y215937D02*
X445982Y215615D01*
G01X445969Y214640D02*
X445715Y215009D01*
G01X432690Y231737D02*
X432943Y231368D01*
G01X432898Y230441D02*
X432677Y230762D01*
G01X441828Y215937D02*
X442050Y215615D01*
G01X442037Y214640D02*
X441783Y215009D01*
G01X428757Y231737D02*
X429011Y231368D01*
G01X428966Y230441D02*
X428744Y230762D01*
G01X437887Y215937D02*
X438108Y215615D01*
G01X438095Y214640D02*
X437841Y215009D01*
G01X433954Y215937D02*
X434176Y215615D01*
G01X434163Y214640D02*
X433909Y215009D01*
G01X430013Y215937D02*
X430234Y215615D01*
G01X430221Y214640D02*
X429967Y215009D01*
G01X602307Y241988D02*
X468859D01*
G01X430670Y236476D02*
X428308D01*
G01X434607D02*
X432245D01*
G01X438544D02*
X436182D01*
G01X442481D02*
X440119D01*
G01X446418D02*
X444056D01*
G01X450355D02*
X447993D01*
G01X453111Y235492D02*
X457048D01*
G01X434095D02*
X432757D01*
G01X441969D02*
X440631D01*
G01X449843D02*
X448505D01*
G01X448347Y235393D02*
X450001D01*
G01X440473D02*
X442127D01*
G01X432599D02*
X434253D01*
G01X430670Y235295D02*
X428308D01*
G01X434607D02*
X432245D01*
G01X438544D02*
X436182D01*
G01X442481D02*
X440119D01*
G01X446418D02*
X444056D01*
G01X450355D02*
X447993D01*
G01X460257D02*
X455532D01*
G01X448646Y230441D02*
X448655Y230393D01*
G01X449702Y215937D02*
X449693Y215984D01*
G01X444714Y230441D02*
X444723Y230393D01*
G01X445761Y215937D02*
X445751Y215984D01*
G01X440772Y230441D02*
X440781Y230393D01*
G01X441828Y215937D02*
X441819Y215984D01*
G01X436840Y230441D02*
X436849Y230393D01*
G01X437887Y215937D02*
X437877Y215984D01*
G01X432898Y230441D02*
X432907Y230393D01*
G01X433954Y215937D02*
X433945Y215984D01*
G01X428966Y230441D02*
X428975Y230393D01*
G01X430013Y215937D02*
X430003Y215984D01*
G01X434253Y234901D02*
X432599D01*
G01X442127D02*
X440473D01*
G01X450001D02*
X448347D01*
G01X430906Y234035D02*
X428072D01*
G01X434843D02*
X432009D01*
G01X438780D02*
X435946D01*
G01X442717D02*
X439883D01*
G01X446655D02*
X443820D01*
G01X450592D02*
X447757D01*
G01X434253Y233130D02*
X432599D01*
G01X442127D02*
X440473D01*
G01X450001D02*
X448347D01*
G01Y232637D02*
X450001D01*
G01X440473D02*
X442127D01*
G01X432599D02*
X434253D01*
G01X430906Y232539D02*
X428072D01*
G01X434843D02*
X432009D01*
G01X438780D02*
X435946D01*
G01X442717D02*
X439883D01*
G01X446655D02*
X443820D01*
G01X450592D02*
X447757D01*
G01X450001Y232382D02*
X450592D01*
G01X447757D02*
X448347D01*
G01X446064D02*
X446655D01*
G01X443820D02*
X444410D01*
G01X442127D02*
X442717D01*
G01X439883D02*
X440473D01*
G01X438190D02*
X438780D01*
G01X435946D02*
X436536D01*
G01X434253D02*
X434843D01*
G01X432009D02*
X432599D01*
G01X430316D02*
X430906D01*
G01X428072D02*
X428662D01*
G01X448169Y232147D02*
X450180D01*
G01X444236D02*
X446247D01*
G01X440295D02*
X442306D01*
G01X436362D02*
X438373D01*
G01X432421D02*
X434432D01*
G01X428488D02*
X430499D01*
G01X430244Y231756D02*
X428744D01*
G01X434176D02*
X432676D01*
G01X438118D02*
X436618D01*
G01X442050D02*
X440550D01*
G01X445992D02*
X444492D01*
G01X449924D02*
X448424D01*
G01X457048Y231752D02*
X453111D01*
G01X448438Y231737D02*
X449911D01*
G01X444505D02*
X445978D01*
G01X440564D02*
X442037D01*
G01X436631D02*
X438104D01*
G01X432690D02*
X434163D01*
G01X428757D02*
X430230D01*
G01X428662Y231712D02*
X428072D01*
G01X430906D02*
X430316D01*
G01X432599D02*
X432009D01*
G01X434843D02*
X434253D01*
G01X436536D02*
X435946D01*
G01X438780D02*
X438190D01*
G01X440473D02*
X439883D01*
G01X442717D02*
X442127D01*
G01X444410D02*
X443820D01*
G01X446655D02*
X446064D01*
G01X448347D02*
X447757D01*
G01X450592D02*
X450001D01*
G01X447757Y231555D02*
X450592D01*
G01X443820D02*
X446655D01*
G01X439883D02*
X442717D01*
G01X435946D02*
X438780D01*
G01X432009D02*
X434843D01*
G01X428072D02*
X430906D01*
G01X430316Y231456D02*
X428662D01*
G01X438190D02*
X436536D01*
G01X446064D02*
X444410D01*
G01X429976Y231368D02*
X429011D01*
G01X433909D02*
X432943D01*
G01X437851D02*
X436885D01*
G01X441783D02*
X440818D01*
G01X445725D02*
X444759D01*
G01X449657D02*
X448692D01*
G01X447757Y231358D02*
X448072D01*
G01X443820D02*
X444135D01*
G01X439883D02*
X440198D01*
G01X435946D02*
X436261D01*
G01X432009D02*
X432324D01*
G01X428072D02*
X428387D01*
G01X430906D02*
X430592D01*
G01X434843D02*
X434529D01*
G01X438780D02*
X438466D01*
G01X442717D02*
X442403D01*
G01X446655D02*
X446340D01*
G01X450592D02*
X450277D01*
G01X430504Y231260D02*
X428483D01*
G01X434437D02*
X432416D01*
G01X438378D02*
X436357D01*
G01X442311D02*
X440290D01*
G01X446252D02*
X444231D01*
G01X450185D02*
X448164D01*
G01X444410Y230964D02*
X446064D01*
G01X436536D02*
X438190D01*
G01X428662D02*
X430316D01*
G01X430244Y230772D02*
X428744D01*
G01X434176D02*
X432676D01*
G01X438118D02*
X436618D01*
G01X442050D02*
X440550D01*
G01X445992D02*
X444492D01*
G01X449924D02*
X448424D01*
G01X460257Y230767D02*
X455532D01*
G01X430242Y230762D02*
X428746D01*
G01X434174D02*
X432678D01*
G01X438116D02*
X436620D01*
G01X442048D02*
X440552D01*
G01X445990D02*
X444494D01*
G01X449922D02*
X448426D01*
G01X448646Y230441D02*
X449702D01*
G01X444714D02*
X445770D01*
G01X440772D02*
X441828D01*
G01X436840D02*
X437896D01*
G01X432898D02*
X433954D01*
G01X428966D02*
X430022D01*
G01X430670Y230393D02*
X428308D01*
G01X434607D02*
X432245D01*
G01X438544D02*
X436182D01*
G01X442481D02*
X440119D01*
G01X446418D02*
X444056D01*
G01X450355D02*
X447993D01*
G01X450277Y229862D02*
X450592D01*
G01X447757D02*
X448072D01*
G01X446340D02*
X446655D01*
G01X443820D02*
X444135D01*
G01X442403D02*
X442717D01*
G01X439883D02*
X440198D01*
G01X438466D02*
X438780D01*
G01X435946D02*
X436261D01*
G01X434529D02*
X434843D01*
G01X432009D02*
X432324D01*
G01X430592D02*
X430906D01*
G01X428072D02*
X428387D01*
G01X448403Y229826D02*
X449946D01*
G01X444470D02*
X446014D01*
G01X440528D02*
X442072D01*
G01X436596D02*
X438140D01*
G01X432654D02*
X434198D01*
G01X428722D02*
X430265D01*
G01X448413Y229807D02*
X449935D01*
G01X444481D02*
X446003D01*
G01X440539D02*
X442061D01*
G01X436607D02*
X438129D01*
G01X432665D02*
X434187D01*
G01X428733D02*
X430255D01*
G01X444410Y229193D02*
X446064D01*
G01X436536D02*
X438190D01*
G01X428662D02*
X430316D01*
G01Y228700D02*
X428662D01*
G01X438190D02*
X436536D01*
G01X446064D02*
X444410D01*
G01X430158Y228602D02*
X428820D01*
G01X438032D02*
X436694D01*
G01X445906D02*
X444568D01*
G01Y227618D02*
X445906D01*
G01X436694D02*
X438032D01*
G01X428820D02*
X430158D01*
G01X430291Y226999D02*
X428696D01*
G01X434224D02*
X432629D01*
G01X438165D02*
X436570D01*
G01X442098D02*
X440503D01*
G01X446039D02*
X444444D01*
G01X449972D02*
X448377D01*
G01X430592Y226889D02*
X428387D01*
G01X434529D02*
X432324D01*
G01X438466D02*
X436261D01*
G01X442403D02*
X440198D01*
G01X446340D02*
X444135D01*
G01X450277D02*
X448072D01*
G01X430363Y226239D02*
X428624D01*
G01X434296D02*
X432557D01*
G01X438237D02*
X436498D01*
G01X442170D02*
X440431D01*
G01X446111D02*
X444372D01*
G01X450044D02*
X448305D01*
G01X448379Y226037D02*
X449969D01*
G01X444447D02*
X446037D01*
G01X440505D02*
X442095D01*
G01X436573D02*
X438163D01*
G01X432631D02*
X434221D01*
G01X428699D02*
X430289D01*
G01X448326Y226012D02*
X450022D01*
G01X444394D02*
X446090D01*
G01X440452D02*
X442148D01*
G01X436520D02*
X438216D01*
G01X432578D02*
X434274D01*
G01X428646D02*
X430342D01*
G01X430349Y225945D02*
X428639D01*
G01X434281D02*
X432571D01*
G01X438223D02*
X436513D01*
G01X442155D02*
X440445D01*
G01X446097D02*
X444387D01*
G01X450029D02*
X448319D01*
G01X448300Y225353D02*
X450048D01*
G01X444368D02*
X446116D01*
G01X440426D02*
X442174D01*
G01X436494D02*
X438242D01*
G01X432552D02*
X434300D01*
G01X428620D02*
X430368D01*
G01X430340Y225050D02*
X428648D01*
G01X434272D02*
X432580D01*
G01X438214D02*
X436522D01*
G01X442146D02*
X440454D01*
G01X446088D02*
X444396D01*
G01X450020D02*
X448328D01*
G01X430349Y224960D02*
X428639D01*
G01X434281D02*
X432571D01*
G01X438223D02*
X436513D01*
G01X442155D02*
X440445D01*
G01X446097D02*
X444387D01*
G01X450029D02*
X448319D01*
G01X448072Y224634D02*
X450277D01*
G01X444135D02*
X446340D01*
G01X440198D02*
X442403D01*
G01X436261D02*
X438466D01*
G01X432324D02*
X434529D01*
G01X428387D02*
X430592D01*
G01X448072Y224467D02*
X450277D01*
G01X444135D02*
X446340D01*
G01X440198D02*
X442403D01*
G01X436261D02*
X438466D01*
G01X432324D02*
X434529D01*
G01X428387D02*
X430592D01*
G01Y221910D02*
X428387D01*
G01X434529D02*
X432324D01*
G01X438466D02*
X436261D01*
G01X442403D02*
X440198D01*
G01X446340D02*
X444135D01*
G01X450277D02*
X448072D01*
G01X430592Y221743D02*
X428387D01*
G01X434529D02*
X432324D01*
G01X438466D02*
X436261D01*
G01X442403D02*
X440198D01*
G01X446340D02*
X444135D01*
G01X450277D02*
X448072D01*
G01X448319Y221417D02*
X450029D01*
G01X444377D02*
X446088D01*
G01X440445D02*
X442155D01*
G01X436503D02*
X438214D01*
G01X432571D02*
X434281D01*
G01X428629D02*
X430340D01*
G01X448328Y221327D02*
X450020D01*
G01X444387D02*
X446078D01*
G01X440454D02*
X442146D01*
G01X436513D02*
X438204D01*
G01X432580D02*
X434272D01*
G01X428639D02*
X430330D01*
G01X430359Y221024D02*
X428610D01*
G01X434300D02*
X432552D01*
G01X438233D02*
X436484D01*
G01X442174D02*
X440426D01*
G01X446107D02*
X444358D01*
G01X450048D02*
X448300D01*
G01X448319Y220433D02*
X450029D01*
G01X444377D02*
X446088D01*
G01X440445D02*
X442155D01*
G01X436503D02*
X438214D01*
G01X432571D02*
X434281D01*
G01X428629D02*
X430340D01*
G01X430333Y220365D02*
X428636D01*
G01X434274D02*
X432578D01*
G01X438207D02*
X436510D01*
G01X442148D02*
X440452D01*
G01X446081D02*
X444384D01*
G01X450022D02*
X448326D01*
G01X430280Y220340D02*
X428689D01*
G01X434221D02*
X432631D01*
G01X438154D02*
X436563D01*
G01X442095D02*
X440505D01*
G01X446028D02*
X444437D01*
G01X449969D02*
X448379D01*
G01X448305Y220138D02*
X450044D01*
G01X444363D02*
X446102D01*
G01X440431D02*
X442170D01*
G01X436489D02*
X438228D01*
G01X432557D02*
X434296D01*
G01X428615D02*
X430354D01*
G01X448072Y219488D02*
X450277D01*
G01X444135D02*
X446340D01*
G01X440198D02*
X442403D01*
G01X436261D02*
X438466D01*
G01X432324D02*
X434529D01*
G01X428387D02*
X430592D01*
G01X448377Y219379D02*
X449972D01*
G01X444435D02*
X446030D01*
G01X440503D02*
X442098D01*
G01X436561D02*
X438156D01*
G01X432629D02*
X434224D01*
G01X428687D02*
X430282D01*
G01X430158Y218760D02*
X428820D01*
G01X438032D02*
X436694D01*
G01X445906D02*
X444568D01*
G01X430158Y217775D02*
X428820D01*
G01X438032D02*
X436694D01*
G01X445906D02*
X444568D01*
G01X444410Y217677D02*
X446064D01*
G01X436536D02*
X438190D01*
G01X428662D02*
X430316D01*
G01Y217185D02*
X428662D01*
G01X438190D02*
X436536D01*
G01X446064D02*
X444410D01*
G01X430245Y216570D02*
X428724D01*
G01X434187D02*
X432665D01*
G01X438119D02*
X436598D01*
G01X442061D02*
X440539D01*
G01X445993D02*
X444472D01*
G01X449935D02*
X448413D01*
G01X430256Y216551D02*
X428713D01*
G01X434198D02*
X432654D01*
G01X438130D02*
X436587D01*
G01X442072D02*
X440528D01*
G01X446004D02*
X444461D01*
G01X449946D02*
X448403D01*
G01X428387Y216515D02*
X428072D01*
G01X430906D02*
X430592D01*
G01X432324D02*
X432009D01*
G01X436261D02*
X435946D01*
G01X434843D02*
X434529D01*
G01X438780D02*
X438466D01*
G01X440198D02*
X439883D01*
G01X442717D02*
X442403D01*
G01X444135D02*
X443820D01*
G01X446655D02*
X446340D01*
G01X448072D02*
X447757D01*
G01X450592D02*
X450277D01*
G01X430670Y215984D02*
X428308D01*
G01X434607D02*
X432245D01*
G01X438544D02*
X436182D01*
G01X442481D02*
X440119D01*
G01X446418D02*
X444056D01*
G01X450355D02*
X447993D01*
G01X430013Y215937D02*
X428956D01*
G01X433954D02*
X432898D01*
G01X437887D02*
X436830D01*
G01X441828D02*
X440772D01*
G01X445761D02*
X444704D01*
G01X449702D02*
X448646D01*
G01X448426Y215615D02*
X449922D01*
G01X444484D02*
X445981D01*
G01X440552D02*
X442048D01*
G01X436610D02*
X438107D01*
G01X432678D02*
X434174D01*
G01X428736D02*
X430233D01*
G01X460257Y215610D02*
X455532D01*
G01X448424Y215605D02*
X449924D01*
G01X444483D02*
X445982D01*
G01X440550D02*
X442050D01*
G01X436609D02*
X438108D01*
G01X432676D02*
X434176D01*
G01X428735D02*
X430234D01*
G01X430316Y215413D02*
X428662D01*
G01X438190D02*
X436536D01*
G01X446064D02*
X444410D01*
G01X448164Y215117D02*
X450185D01*
G01X444222D02*
X446243D01*
G01X440290D02*
X442311D01*
G01X436348D02*
X438369D01*
G01X432416D02*
X434437D01*
G01X428474D02*
X430495D01*
G01X450277Y215019D02*
X450592D01*
G01X446340D02*
X446655D01*
G01X442403D02*
X442717D01*
G01X438466D02*
X438780D01*
G01X434529D02*
X434843D01*
G01X430592D02*
X430906D01*
G01X428387D02*
X428072D01*
G01X432324D02*
X432009D01*
G01X436261D02*
X435946D01*
G01X440198D02*
X439883D01*
G01X444135D02*
X443820D01*
G01X448072D02*
X447757D01*
G01X448692Y215009D02*
X449657D01*
G01X444750D02*
X445715D01*
G01X440818D02*
X441783D01*
G01X436876D02*
X437841D01*
G01X432943D02*
X433909D01*
G01X429002D02*
X429967D01*
G01X444410Y214921D02*
X446064D01*
G01X436536D02*
X438190D01*
G01X428662D02*
X430316D01*
G01X447757Y214822D02*
X450592D01*
G01X443820D02*
X446655D01*
G01X439883D02*
X442717D01*
G01X435946D02*
X438780D01*
G01X432009D02*
X434843D01*
G01X428072D02*
X430906D01*
G01X450001Y214665D02*
X450592D01*
G01X447757D02*
X448347D01*
G01X446064D02*
X446655D01*
G01X443820D02*
X444410D01*
G01X442127D02*
X442717D01*
G01X439883D02*
X440473D01*
G01X438190D02*
X438780D01*
G01X435946D02*
X436536D01*
G01X434253D02*
X434843D01*
G01X432009D02*
X432599D01*
G01X430316D02*
X430906D01*
G01X428072D02*
X428662D01*
G01X430221Y214640D02*
X428748D01*
G01X434163D02*
X432690D01*
G01X438095D02*
X436622D01*
G01X442037D02*
X440564D01*
G01X445969D02*
X444496D01*
G01X449911D02*
X448438D01*
G01X453111Y214626D02*
X457048D01*
G01X448424Y214621D02*
X449924D01*
G01X444483D02*
X445982D01*
G01X440550D02*
X442050D01*
G01X436609D02*
X438108D01*
G01X432676D02*
X434176D01*
G01X428735D02*
X430234D01*
G01X430490Y214231D02*
X428479D01*
G01X434432D02*
X432421D01*
G01X438364D02*
X436353D01*
G01X442306D02*
X440295D01*
G01X446238D02*
X444227D01*
G01X450180D02*
X448169D01*
G01X428662Y213996D02*
X428072D01*
G01X430906D02*
X430316D01*
G01X432599D02*
X432009D01*
G01X434843D02*
X434253D01*
G01X436536D02*
X435946D01*
G01X438780D02*
X438190D01*
G01X440473D02*
X439883D01*
G01X442717D02*
X442127D01*
G01X444410D02*
X443820D01*
G01X446655D02*
X446064D01*
G01X448347D02*
X447757D01*
G01X450592D02*
X450001D01*
G01X430906Y213838D02*
X428072D01*
G01X434843D02*
X432009D01*
G01X438780D02*
X435946D01*
G01X442717D02*
X439883D01*
G01X446655D02*
X443820D01*
G01X450592D02*
X447757D01*
G01X434253Y213740D02*
X432599D01*
G01X442127D02*
X440473D01*
G01X450001D02*
X448347D01*
G01Y213248D02*
X450001D01*
G01X440473D02*
X442127D01*
G01X432599D02*
X434253D01*
G01X447757Y212342D02*
X450592D01*
G01X443820D02*
X446655D01*
G01X439883D02*
X442717D01*
G01X435946D02*
X438780D01*
G01X432009D02*
X434843D01*
G01X428072D02*
X430906D01*
G01X448347Y211476D02*
X450001D01*
G01X440473D02*
X442127D01*
G01X432599D02*
X434253D01*
G01X455532Y211082D02*
X460257D01*
G01X447993D02*
X450355D01*
G01X430670D02*
X428308D01*
G01X434607D02*
X432245D01*
G01X438544D02*
X436182D01*
G01X442481D02*
X440119D01*
G01X446418D02*
X444056D01*
G01X434253Y210984D02*
X432599D01*
G01X442127D02*
X440473D01*
G01X450001D02*
X448347D01*
G01X434095Y210885D02*
X432757D01*
G01X441969D02*
X440631D01*
G01X449843D02*
X448505D01*
G01X457048D02*
X453111D01*
G01X468859Y199055D02*
Y242008D01*
G01X460985Y237854D02*
Y203011D01*
G01X460257Y224583D02*
Y235295D01*
G01Y211082D02*
Y221794D01*
G01X457836Y208523D02*
Y203011D01*
G01X457048Y214626D02*
Y210885D01*
G01Y235492D02*
Y231752D01*
G01X456576Y216693D02*
Y229685D01*
G01X455532Y219020D02*
Y211082D01*
G01Y235295D02*
Y227358D01*
G01X453170Y226732D02*
Y219645D01*
G01X453111Y231752D02*
Y235492D01*
G01Y210885D02*
Y214626D01*
G01X450185Y215117D02*
X450048Y221024D01*
G01X450044Y220138D02*
X450180Y214231D01*
G01X450022Y226012D02*
X449972Y226999D01*
G01X449969Y226037D02*
X450020Y225050D01*
G01X448379Y220340D02*
X448328Y221327D01*
G01X448326Y220365D02*
X448377Y219379D01*
G01X446090Y226012D02*
X446039Y226999D01*
G01X446037Y226037D02*
X446088Y225050D01*
G01X447993Y209901D02*
X450355D01*
G01X444056D02*
X446418D01*
G01X440119D02*
X442481D01*
G01X436182D02*
X438544D01*
G01X432245D02*
X434607D01*
G01X428308D02*
X430670D01*
G01X441300Y203011D02*
X460985D01*
G01X449972Y219379D02*
X450022Y220365D01*
G01X450020Y221327D02*
X449969Y220340D01*
G01X448328Y225050D02*
X448379Y226037D01*
G01X448377Y226999D02*
X448326Y226012D01*
G01X446030Y219379D02*
X446081Y220365D01*
G01X446078Y221327D02*
X446028Y220340D01*
G01X444396Y225050D02*
X444447Y226037D01*
G01X444444Y226999D02*
X444394Y226012D01*
G01X442098Y219379D02*
X442148Y220365D01*
G01X442146Y221327D02*
X442095Y220340D01*
G01X440454Y225050D02*
X440505Y226037D01*
G01X440503Y226999D02*
X440452Y226012D01*
G01X438156Y219379D02*
X438207Y220365D01*
G01X438204Y221327D02*
X438154Y220340D01*
G01X436522Y225050D02*
X436573Y226037D01*
G01X436570Y226999D02*
X436520Y226012D01*
G01X450048Y225353D02*
X450185Y231260D01*
G01X450180Y232147D02*
X450044Y226239D01*
G01X448169Y214231D02*
X448305Y220138D01*
G01X448300Y221024D02*
X448164Y215117D01*
G01X446116Y225353D02*
X446252Y231260D01*
G01X446247Y232147D02*
X446111Y226239D01*
G01X444227Y214231D02*
X444363Y220138D01*
G01X444358Y221024D02*
X444222Y215117D01*
G01X442174Y225353D02*
X442311Y231260D01*
G01X442306Y232147D02*
X442170Y226239D01*
G01X440295Y214231D02*
X440431Y220138D01*
G01X440426Y221024D02*
X440290Y215117D01*
G01X438242Y225353D02*
X438378Y231260D01*
G01X438373Y232147D02*
X438237Y226239D01*
G01X436353Y214231D02*
X436489Y220138D01*
G01X436484Y221024D02*
X436348Y215117D01*
G01X434300Y225353D02*
X434437Y231260D01*
G01X434432Y232147D02*
X434296Y226239D01*
G01X432421Y214231D02*
X432557Y220138D01*
G01X432552Y221024D02*
X432416Y215117D01*
G01X449670Y215984D02*
X449657Y215009D01*
G01X448678Y230393D02*
X448692Y231368D01*
G01X445728Y215984D02*
X445715Y215009D01*
G01X444746Y230393D02*
X444759Y231368D01*
G01X441796Y215984D02*
X441783Y215009D01*
G01X440804Y230393D02*
X440818Y231368D01*
G01X437854Y215984D02*
X437841Y215009D01*
G01X436872Y230393D02*
X436885Y231368D01*
G01X433922Y215984D02*
X433909Y215009D01*
G01X432930Y230393D02*
X432943Y231368D01*
G01X450592Y229862D02*
Y234035D01*
G01Y212342D02*
Y216515D01*
G01X450557Y214822D02*
Y213838D01*
G01X450552Y214822D02*
Y213838D01*
G01Y232539D02*
Y231555D01*
G01X450355Y215984D02*
Y209901D01*
G01Y236476D02*
Y230393D01*
G01X450277Y213838D02*
Y232539D01*
G01X450198Y214824D02*
Y213840D01*
G01Y232538D02*
Y231553D01*
G01X450001Y231555D02*
Y236396D01*
G01Y209981D02*
Y214822D01*
G01X449922Y230760D02*
Y231750D01*
G01Y214627D02*
Y215617D01*
G01X449843Y210965D02*
Y209901D01*
G01Y236476D02*
Y235412D01*
G01X449568Y209901D02*
Y210885D01*
G01Y236476D02*
Y235492D01*
G01X448780D02*
Y236476D01*
G01Y209901D02*
Y210885D01*
G01X448505Y210965D02*
Y209901D01*
G01Y236476D02*
Y235412D01*
G01X448426Y215617D02*
Y214627D01*
G01Y231750D02*
Y230760D01*
G01X448347Y231555D02*
Y236396D01*
G01Y209981D02*
Y214822D01*
G01X448151Y231553D02*
Y232538D01*
G01Y213840D02*
Y214824D01*
G01X448072Y232539D02*
Y213838D01*
G01X447993Y215984D02*
Y209901D01*
G01Y236476D02*
Y230393D01*
G01X447796Y214822D02*
Y213838D01*
G01Y232539D02*
Y231555D01*
G01X447792Y232539D02*
Y231555D01*
G01X447757Y216515D02*
Y212342D01*
G01Y234035D02*
Y229862D01*
G01X446655D02*
Y234035D01*
G01Y212342D02*
Y216515D01*
G01X446620Y232539D02*
Y231555D01*
G01X446615Y214822D02*
Y213838D01*
G01X446610Y214822D02*
Y213838D01*
G01X446418Y215984D02*
Y209901D01*
G01Y236476D02*
Y230393D01*
G01X446340Y213838D02*
Y232539D01*
G01X446265Y232538D02*
Y231553D01*
G01X446256Y214824D02*
Y213840D01*
G01X446064Y227698D02*
Y232539D01*
G01Y213838D02*
Y218680D01*
G01X445990Y230760D02*
Y231750D01*
G01X445981Y214627D02*
Y215617D01*
G01X445906Y218760D02*
Y217696D01*
G01Y228681D02*
Y227618D01*
G01X445631D02*
Y228602D01*
G01Y218760D02*
Y217775D01*
G01X444843Y227618D02*
Y228602D01*
G01Y217775D02*
Y218760D01*
G01X444568D02*
Y217696D01*
G01Y228681D02*
Y227618D01*
G01X444494Y231750D02*
Y230760D01*
G01X444484Y215617D02*
Y214627D01*
G01X444450Y208523D02*
Y203011D01*
G01X444410Y227698D02*
Y232539D01*
G01Y213838D02*
Y218680D01*
G01X444218Y231553D02*
Y232538D01*
G01X444209Y213840D02*
Y214824D01*
G01X444135Y232539D02*
Y213838D01*
G01X444056Y215984D02*
Y209901D01*
G01Y236476D02*
Y230393D01*
G01X443864Y232539D02*
Y231555D01*
G01X443859Y232539D02*
Y231555D01*
G01X443855Y214822D02*
Y213838D01*
G01X443820Y216515D02*
Y212342D01*
G01Y234035D02*
Y229862D01*
G01X442717D02*
Y234035D01*
G01Y212342D02*
Y216515D01*
G01X442683Y214822D02*
Y213838D01*
G01X442678Y214822D02*
Y213838D01*
G01Y232539D02*
Y231555D01*
G01X442481Y215984D02*
Y209901D01*
G01Y236476D02*
Y230393D01*
G01X442403Y213838D02*
Y232539D01*
G01X442324Y214824D02*
Y213840D01*
G01Y232538D02*
Y231553D01*
G01X442127Y231555D02*
Y236396D01*
G01Y209981D02*
Y214822D01*
G01X442048Y230760D02*
Y231750D01*
G01Y214627D02*
Y215617D01*
G01X441969Y210965D02*
Y209901D01*
G01Y236476D02*
Y235412D01*
G01X441694Y210885D02*
Y209901D01*
G01Y236476D02*
Y235492D01*
G01X441300Y208523D02*
Y203011D01*
G01X440906Y235492D02*
Y236476D01*
G01Y210885D02*
Y209901D01*
G01X440631Y210965D02*
Y209901D01*
G01Y236476D02*
Y235412D01*
G01X440552Y215617D02*
Y214627D01*
G01Y231750D02*
Y230760D01*
G01X440473Y231555D02*
Y236396D01*
G01Y209981D02*
Y214822D01*
G01X440277Y231553D02*
Y232538D01*
G01Y213840D02*
Y214824D01*
G01X440198Y232539D02*
Y213838D01*
G01X440119Y215984D02*
Y209901D01*
G01Y236476D02*
Y230393D01*
G01X439922Y214822D02*
Y213838D01*
G01Y232539D02*
Y231555D01*
G01X439918Y232539D02*
Y231555D01*
G01X439883Y216515D02*
Y212342D01*
G01Y234035D02*
Y229862D01*
G01X438780D02*
Y234035D01*
G01Y212342D02*
Y216515D01*
G01X438746Y232539D02*
Y231555D01*
G01X438741Y214822D02*
Y213838D01*
G01X438736Y214822D02*
Y213838D01*
G01X438544Y215984D02*
Y209901D01*
G01Y236476D02*
Y230393D01*
G01X438466Y213838D02*
Y232539D01*
G01X438391Y232538D02*
Y231553D01*
G01X438382Y214824D02*
Y213840D01*
G01X438190Y227698D02*
Y232539D01*
G01Y213838D02*
Y218680D01*
G01X438116Y230760D02*
Y231750D01*
G01X438107Y214627D02*
Y215617D01*
G01X438032Y218760D02*
Y217696D01*
G01Y228681D02*
Y227618D01*
G01X437757D02*
Y228602D01*
G01Y218760D02*
Y217775D01*
G01X437363Y208523D02*
Y203011D01*
G01X436969Y227618D02*
Y228602D01*
G01Y217775D02*
Y218760D01*
G01X436694D02*
Y217696D01*
G01Y228681D02*
Y227618D01*
G01X436620Y231750D02*
Y230760D01*
G01X436610Y215617D02*
Y214627D01*
G01X436536Y227698D02*
Y232539D01*
G01Y213838D02*
Y218680D01*
G01X436344Y231553D02*
Y232538D01*
G01X436335Y213840D02*
Y214824D01*
G01X436261Y232539D02*
Y213838D01*
G01X436182Y215984D02*
Y209901D01*
G01Y236476D02*
Y230393D01*
G01X435990Y232539D02*
Y231555D01*
G01X435985Y232539D02*
Y231555D01*
G01X435981Y214822D02*
Y213838D01*
G01X435946Y216515D02*
Y212342D01*
G01Y234035D02*
Y229862D01*
G01X434843D02*
Y234035D01*
G01Y212342D02*
Y216515D01*
G01X434809Y214822D02*
Y213838D01*
G01X434804Y214822D02*
Y213838D01*
G01Y232539D02*
Y231555D01*
G01X434607Y215984D02*
Y209901D01*
G01Y236476D02*
Y230393D01*
G01X434529Y213838D02*
Y232539D01*
G01X434450Y214824D02*
Y213840D01*
G01Y232538D02*
Y231553D01*
G01X434253Y231555D02*
Y236396D01*
G01Y209981D02*
Y214822D01*
G01X434214Y208523D02*
Y203011D01*
G01X434174Y230760D02*
Y231750D01*
G01Y214627D02*
Y215617D01*
G01X434095Y210965D02*
Y209901D01*
G01Y236476D02*
Y235412D01*
G01X433820Y210885D02*
Y209901D01*
G01Y236476D02*
Y235492D01*
G01X433032D02*
Y236476D01*
G01Y210885D02*
Y209901D01*
G01X432757Y210965D02*
Y209901D01*
G01Y236476D02*
Y235412D01*
G01X432678Y215617D02*
Y214627D01*
G01Y231750D02*
Y230760D01*
G01X432599Y231555D02*
Y236396D01*
G01Y209981D02*
Y214822D01*
G01X432403Y231553D02*
Y232538D01*
G01Y213840D02*
Y214824D01*
G01X432324Y232539D02*
Y213838D01*
G01X432245Y215984D02*
Y209901D01*
G01Y236476D02*
Y230393D01*
G01X432048Y214822D02*
Y213838D01*
G01Y232539D02*
Y231555D01*
G01X432044Y232539D02*
Y231555D01*
G01X432009Y216515D02*
Y212342D01*
G01Y234035D02*
Y229862D01*
G01X430906D02*
Y234035D01*
G01Y212342D02*
Y216515D01*
G01X430872Y232539D02*
Y231555D01*
G01X430867Y214822D02*
Y213838D01*
G01X430862Y214822D02*
Y213838D01*
G01X430670Y215984D02*
Y209901D01*
G01Y236476D02*
Y230393D01*
G01X430592Y213838D02*
Y232539D01*
G01X430517Y232538D02*
Y231553D01*
G01X430508Y214824D02*
Y213840D01*
G01X430316Y227698D02*
Y232539D01*
G01Y213838D02*
Y218680D01*
G01X430242Y230760D02*
Y231750D01*
G01X430233Y214627D02*
Y215617D01*
G01X430158Y218760D02*
Y217696D01*
G01Y228681D02*
Y227618D01*
G01X429883Y218760D02*
Y217775D01*
G01Y228602D02*
Y227618D01*
G01X429095Y218760D02*
Y217775D01*
G01Y228602D02*
Y227618D01*
G01X428820Y218760D02*
Y217696D01*
G01Y228681D02*
Y227618D01*
G01X428746Y231750D02*
Y230760D01*
G01X428736Y215617D02*
Y214627D01*
G01X428662Y227698D02*
Y232539D01*
G01Y213838D02*
Y218680D01*
G01X449657Y231368D02*
X449670Y230393D01*
G01X448692Y215009D02*
X448678Y215984D01*
G01X445725Y231368D02*
X445738Y230393D01*
G01X444750Y215009D02*
X444737Y215984D01*
G01X441783Y231368D02*
X441796Y230393D01*
G01X440818Y215009D02*
X440804Y215984D01*
G01X437851Y231368D02*
X437864Y230393D01*
G01X436876Y215009D02*
X436863Y215984D01*
G01X433909Y231368D02*
X433922Y230393D01*
G01X432943Y215009D02*
X432930Y215984D01*
G01X429976Y231368D02*
X429990Y230393D01*
G01X429002Y215009D02*
X428989Y215984D01*
G01X448305Y226239D02*
X448169Y232147D01*
G01X448164Y231260D02*
X448300Y225353D01*
G01X446243Y215117D02*
X446107Y221024D01*
G01X446102Y220138D02*
X446238Y214231D01*
G01X444372Y226239D02*
X444236Y232147D01*
G01X444231Y231260D02*
X444368Y225353D01*
G01X442311Y215117D02*
X442174Y221024D01*
G01X442170Y220138D02*
X442306Y214231D01*
G01X440431Y226239D02*
X440295Y232147D01*
G01X440290Y231260D02*
X440426Y225353D01*
G01X438369Y215117D02*
X438233Y221024D01*
G01X438228Y220138D02*
X438364Y214231D01*
G01X436498Y226239D02*
X436362Y232147D01*
G01X436357Y231260D02*
X436494Y225353D01*
G01X434437Y215117D02*
X434300Y221024D01*
G01X434296Y220138D02*
X434432Y214231D01*
G01X432557Y226239D02*
X432421Y232147D01*
G01X432416Y231260D02*
X432552Y225353D01*
G01X430495Y215117D02*
X430359Y221024D01*
G01X430354Y220138D02*
X430490Y214231D01*
G01X428624Y226239D02*
X428488Y232147D01*
G01X428483Y231260D02*
X428620Y225353D01*
G01X444437Y220340D02*
X444387Y221327D01*
G01X444384Y220365D02*
X444435Y219379D01*
G01X442148Y226012D02*
X442098Y226999D01*
G01X442095Y226037D02*
X442146Y225050D01*
G01X440505Y220340D02*
X440454Y221327D01*
G01X440452Y220365D02*
X440503Y219379D01*
G01X438216Y226012D02*
X438165Y226999D01*
G01X438163Y226037D02*
X438214Y225050D01*
G01X436563Y220340D02*
X436513Y221327D01*
G01X436510Y220365D02*
X436561Y219379D01*
G01X434274Y226012D02*
X434224Y226999D01*
G01X434221Y226037D02*
X434272Y225050D01*
G01X432631Y220340D02*
X432580Y221327D01*
G01X432578Y220365D02*
X432629Y219379D01*
G01X430342Y226012D02*
X430291Y226999D01*
G01X430289Y226037D02*
X430340Y225050D01*
G01X428689Y220340D02*
X428639Y221327D01*
G01X428636Y220365D02*
X428687Y219379D01*
G01X448655Y215984D02*
X448646Y215937D01*
G01X449693Y230393D02*
X449702Y230441D01*
G01X444714Y215984D02*
X444704Y215937D01*
G01X445761Y230393D02*
X445770Y230441D01*
G01X440781Y215984D02*
X440772Y215937D01*
G01X441819Y230393D02*
X441828Y230441D01*
G01X436840Y215984D02*
X436830Y215937D01*
G01X437887Y230393D02*
X437896Y230441D01*
G01X432907Y215984D02*
X432898Y215937D01*
G01X434224Y219379D02*
X434274Y220365D01*
G01X434272Y221327D02*
X434221Y220340D01*
G01X432580Y225050D02*
X432631Y226037D01*
G01X432629Y226999D02*
X432578Y226012D01*
G01X430282Y219379D02*
X430333Y220365D01*
G01X430330Y221327D02*
X430280Y220340D01*
G01X428648Y225050D02*
X428699Y226037D01*
G01X428696Y226999D02*
X428646Y226012D01*
G01X430368Y225353D02*
X430504Y231260D01*
G01X430499Y232147D02*
X430363Y226239D01*
G01X428479Y214231D02*
X428615Y220138D01*
G01X428610Y221024D02*
X428474Y215117D01*
G01X429980Y215984D02*
X429967Y215009D01*
G01X428998Y230393D02*
X429011Y231368D01*
G01X428470Y231553D02*
Y232538D01*
G01X428461Y213840D02*
Y214824D01*
G01X428387Y232539D02*
Y213838D01*
G01X428308Y215984D02*
Y209901D01*
G01Y236476D02*
Y230393D01*
G01X428116Y232539D02*
Y231555D01*
G01X428111Y232539D02*
Y231555D01*
G01X428107Y214822D02*
Y213838D01*
G01X428072Y216515D02*
Y212342D01*
G01Y234035D02*
Y229862D01*
G01X433945Y230393D02*
X433954Y230441D01*
G01X428966Y215984D02*
X428956Y215937D01*
G01X430013Y230393D02*
X430022Y230441D01*
G01X448438Y214640D02*
X448692Y215009D01*
G01X448425Y215615D02*
X448646Y215937D01*
G01X444496Y214640D02*
X444750Y215009D01*
G01X444483Y215615D02*
X444704Y215937D01*
G01X440564Y214640D02*
X440818Y215009D01*
G01X440551Y215615D02*
X440772Y215937D01*
G01X449924Y230762D02*
X449702Y230441D01*
G01X449911Y231737D02*
X449657Y231368D01*
G01X436622Y214640D02*
X436876Y215009D01*
G01X436609Y215615D02*
X436830Y215937D01*
G01X445991Y230762D02*
X445770Y230441D01*
G01X445978Y231737D02*
X445725Y231368D01*
G01X432690Y214640D02*
X432943Y215009D01*
G01X432677Y215615D02*
X432898Y215937D01*
G01X442050Y230762D02*
X441828Y230441D01*
G01X442037Y231737D02*
X441783Y231368D01*
G01X428748Y214640D02*
X429002Y215009D01*
G01X428735Y215615D02*
X428956Y215937D01*
G01X438117Y230762D02*
X437896Y230441D01*
G01X438104Y231737D02*
X437851Y231368D01*
G01X434176Y230762D02*
X433954Y230441D01*
G01X434163Y231737D02*
X433909Y231368D01*
G01X456576Y229685D02*
X454618Y226732D01*
G01X430243Y230762D02*
X430022Y230441D01*
G01X430230Y231737D02*
X429976Y231368D01*
G01X428505Y544724D02*
Y563228D01*
G01Y544724D02*
G03X437954I4725J0D01*
G01Y563228D02*
Y544724D01*
G01X439922Y565196D02*
X437954Y563228D01*
G01X540828Y565196D02*
X439922D01*
G01X461302Y782204D02*
Y764881D01*
G01X553543Y-588550D02*
X554013Y-589075D01*
X554561Y-589390D01*
X555266Y-589495D01*
X555971Y-589285D01*
X556519Y-588865D01*
X556911Y-588130D01*
X556989Y-587290D01*
X556833Y-586450D01*
X556441Y-585925D01*
X555893Y-585505D01*
X555344Y-585400D01*
X554796Y-585505D01*
X554091Y-585925D01*
X554326Y-583195D01*
X556441D01*
G01X558505Y-396313D02*
X558992Y-397034D01*
G01X558505D02*
Y-396313D01*
G01X558992Y-397034D02*
X558505D01*
G01X519240Y-396313D02*
X519727Y-397034D01*
G01X519240D02*
Y-396313D01*
G01X519727Y-397034D02*
X519240D01*
G01X512906Y-396313D02*
X511932Y-397034D01*
G01X513393Y-395591D02*
X512906Y-396313D01*
G01X513881Y-394147D02*
X513393Y-395591D01*
G01X513881Y-391260D02*
Y-394147D01*
G01X513393Y-389817D02*
X513881Y-391260D01*
G01X512906Y-389095D02*
X513393Y-389817D01*
G01X511932Y-388373D02*
X512906Y-389095D01*
G01X510957D02*
X511932Y-388373D01*
G01X510470Y-389817D02*
X510957Y-389095D01*
G01X509983Y-391260D02*
X510470Y-389817D01*
G01X509983Y-394147D02*
Y-391260D01*
G01X510470Y-395591D02*
X509983Y-394147D01*
G01X510957Y-396313D02*
X510470Y-395591D01*
G01X511932Y-397034D02*
X510957Y-396313D01*
G01X528497D02*
X527522Y-397034D01*
G01X528984Y-395591D02*
X528497Y-396313D01*
G01X529471Y-394147D02*
X528984Y-395591D01*
G01X529471Y-391260D02*
Y-394147D01*
G01X528984Y-389817D02*
X529471Y-391260D01*
G01X528497Y-389095D02*
X528984Y-389817D01*
G01X527522Y-388373D02*
X528497Y-389095D01*
G01X526548D02*
X527522Y-388373D01*
G01X526061Y-389817D02*
X526548Y-389095D01*
G01X525574Y-391260D02*
X526061Y-389817D01*
G01X525574Y-394147D02*
Y-391260D01*
G01X526061Y-395591D02*
X525574Y-394147D01*
G01X526548Y-396313D02*
X526061Y-395591D01*
G01X527522Y-397034D02*
X526548Y-396313D01*
G01X567762D02*
X566787Y-397034D01*
G01X568249Y-395591D02*
X567762Y-396313D01*
G01X568736Y-394147D02*
X568249Y-395591D01*
G01X568736Y-391260D02*
Y-394147D01*
G01X568249Y-389817D02*
X568736Y-391260D01*
G01X567762Y-389095D02*
X568249Y-389817D01*
G01X566787Y-388373D02*
X567762Y-389095D01*
G01X565813D02*
X566787Y-388373D01*
G01X565326Y-389817D02*
X565813Y-389095D01*
G01X564839Y-391260D02*
X565326Y-389817D01*
G01X564839Y-394147D02*
Y-391260D01*
G01X565326Y-395591D02*
X564839Y-394147D01*
G01X565813Y-396313D02*
X565326Y-395591D01*
G01X566787Y-397034D02*
X565813Y-396313D01*
G01X532142Y-386208D02*
X531420Y-386929D01*
G01X533585Y-386208D02*
X532142D01*
G01X534307Y-386929D02*
X533585Y-386208D01*
G01X534307Y-388373D02*
Y-386929D01*
G01X533585Y-389095D02*
X534307Y-388373D01*
G01X532142Y-389095D02*
X533585D01*
G01X531420Y-388373D02*
X532142Y-389095D01*
G01X531420Y-386929D02*
Y-388373D01*
G01X571407Y-386208D02*
X570685Y-386929D01*
G01X572850Y-386208D02*
X571407D01*
G01X573572Y-386929D02*
X572850Y-386208D01*
G01X573572Y-388373D02*
Y-386929D01*
G01X572850Y-389095D02*
X573572Y-388373D01*
G01X571407Y-389095D02*
X572850D01*
G01X570685Y-388373D02*
X571407Y-389095D01*
G01X570685Y-386929D02*
Y-388373D01*
G01X553146Y-391260D02*
X552659Y-391982D01*
G01X553146Y-389817D02*
Y-391260D01*
G01X552659Y-389095D02*
X553146Y-389817D01*
G01X551684Y-388373D02*
X552659Y-389095D01*
G01X550710Y-388373D02*
X551684D01*
G01X549735Y-389095D02*
X550710Y-388373D01*
G01X549248Y-389817D02*
X549735Y-389095D01*
G01X549248Y-397034D02*
X553146D01*
G01X549735Y-394869D02*
X549248Y-397034D01*
G01X550710Y-393425D02*
X549735Y-394869D01*
G01X552659Y-391982D02*
X550710Y-393425D01*
G01X541525Y-388373D02*
Y-397034D01*
G01X537194Y-392704D02*
X545856D01*
G01X537194Y-397034D02*
X545856D01*
G01X521360Y-331782D02*
X521847Y-332504D01*
G01X521360D02*
Y-331782D01*
G01X521847Y-332504D02*
X521360D01*
G01X515027Y-331782D02*
X514052Y-332504D01*
G01X515514Y-331061D02*
X515027Y-331782D01*
G01X516001Y-329617D02*
X515514Y-331061D01*
G01X516001Y-326730D02*
Y-329617D01*
G01X515514Y-325286D02*
X516001Y-326730D01*
G01X515027Y-324565D02*
X515514Y-325286D01*
G01X514052Y-323843D02*
X515027Y-324565D01*
G01X513078D02*
X514052Y-323843D01*
G01X512591Y-325286D02*
X513078Y-324565D01*
G01X512103Y-326730D02*
X512591Y-325286D01*
G01X512103Y-329617D02*
Y-326730D01*
G01X512591Y-331061D02*
X512103Y-329617D01*
G01X513078Y-331782D02*
X512591Y-331061D01*
G01X514052Y-332504D02*
X513078Y-331782D01*
G01X538412D02*
X537438Y-332504D01*
G01X538900Y-331061D02*
X538412Y-331782D01*
G01X539387Y-329617D02*
X538900Y-331061D01*
G01X539387Y-326730D02*
Y-329617D01*
G01X538900Y-325286D02*
X539387Y-326730D01*
G01X538412Y-324565D02*
X538900Y-325286D01*
G01X537438Y-323843D02*
X538412Y-324565D01*
G01X536464D02*
X537438Y-323843D01*
G01X535976Y-325286D02*
X536464Y-324565D01*
G01X535489Y-326730D02*
X535976Y-325286D01*
G01X535489Y-329617D02*
Y-326730D01*
G01X535976Y-331061D02*
X535489Y-329617D01*
G01X536464Y-331782D02*
X535976Y-331061D01*
G01X537438Y-332504D02*
X536464Y-331782D01*
G01X529643Y-323843D02*
Y-332504D01*
G01X538111Y-73347D02*
X540080Y-71378D01*
G01X538111Y-73347D02*
X540080Y-71378D01*
G01D02*
Y-3937D01*
G01Y-71378D02*
Y-3937D01*
G01X537127Y-59174D02*
Y-69410D01*
G01X534962Y-59174D02*
Y-69410D01*
G01X533977Y-59174D02*
Y-69410D01*
G01X531812Y-59174D02*
Y-69410D01*
G01X530828Y-59174D02*
Y-69410D01*
G01X528662Y-59174D02*
Y-69410D01*
G01X527678Y-59174D02*
Y-69410D01*
G01X525513Y-59174D02*
Y-69410D01*
G01X524529Y-59174D02*
Y-69410D01*
G01X522363Y-59174D02*
Y-69410D01*
G01X521379Y-59174D02*
Y-69410D01*
G01X519214Y-59174D02*
Y-69410D01*
G01X518229Y-59174D02*
Y-69410D01*
G01X516064Y-59174D02*
Y-69410D01*
G01X515080Y-59174D02*
Y-69410D01*
G01X512914Y-59174D02*
Y-69410D01*
G01X511930Y-59174D02*
Y-69410D01*
G01X509765Y-59174D02*
Y-69410D01*
G01X508780Y-59174D02*
Y-69410D01*
G01X511930D02*
X509765D01*
G01X515080D02*
X512914D01*
G01X518229D02*
X516064D01*
G01X521379D02*
X519214D01*
G01X524529D02*
X522363D01*
G01X527678D02*
X525513D01*
G01X530828D02*
X528662D01*
G01X533977D02*
X531812D01*
G01X537127D02*
X534962D01*
G01X547954Y-73346D02*
X622403D01*
G01X547954D02*
Y-7874D01*
G01X540080Y-71378D02*
Y-3937D01*
G01X538111Y-73346D02*
X540080Y-71378D01*
G01X557509Y6721D02*
G03X558662Y9504I-2784J2784D01*
G01X549158Y0D02*
G03X551941Y1153I-1J3937D01*
G01X544017Y0D02*
G03X540080Y-3937I0J-3937D01*
G01X544017Y0D02*
G03X540080Y-3937I0J-3937D01*
G01X557509Y6721D02*
G03X558662Y9504I-2784J2784D01*
G01X549158Y0D02*
G03X551941Y1153I-1J3937D01*
G01X558662Y9504D02*
Y155374D01*
G01Y103172D02*
Y9504D01*
G01X551941Y1153D02*
X557509Y6721D01*
G01D02*
X551941Y1153D01*
G01X536663Y99291D02*
Y-3937D01*
G01X544017Y0D02*
X549158D01*
G01D02*
X544017D01*
G01X511930Y-59174D02*
X509765D01*
G01X515080D02*
X512914D01*
G01X518229D02*
X516064D01*
G01X521379D02*
X519214D01*
G01X524529D02*
X522363D01*
G01X527678D02*
X525513D01*
G01X530828D02*
X528662D01*
G01X533977D02*
X531812D01*
G01X537127D02*
X534962D01*
G01X558662Y9505D02*
Y155374D01*
G01X557509Y6721D02*
G03X558662Y9505I-2784J2784D01*
G01X551942Y1153D02*
X557509Y6721D01*
G01X549158Y0D02*
G03X551942Y1153I0J3937D01*
G01X544017Y0D02*
X549158D01*
G01X544017D02*
G03X540080Y-3937I0J-3937D01*
G01X547954Y-7874D02*
X549158D01*
G01Y0D02*
G03X551942Y1153I0J3937D01*
G01X549158Y-7875D02*
G03X557510Y-4415I0J11811D01*
G01X551942Y1153D02*
X557509Y6721D01*
G01X557510Y-4414D02*
X563077Y1154D01*
G01X557509Y6721D02*
G03X558662Y9505I-2784J2784D01*
G01X563077Y1153D02*
G03X566536Y9507I-8352J8351D01*
G01X558662Y9505D02*
Y155374D01*
G01X566536Y9505D02*
Y18655D01*
G01D02*
G03X558662I-3937J-1D01*
G01Y153127D02*
G03Y103172I-15748J-24978D01*
G01Y153127D02*
G03Y103172I-15748J-24978D01*
G01Y49363D02*
G03X566536I3937J0D01*
G01D02*
Y151437D01*
G01X536014Y128150D02*
G03X549814I6900J0D01*
G01D02*
G03X536014I-6900J0D01*
G01X562599Y159311D02*
G03X558662Y155374I0J-3937D01*
G01X562599Y159311D02*
G03X558662Y155374I0J-3937D01*
G01X549814Y128149D02*
G03I-6900J0D01*
G01D02*
G03I-6900J0D01*
G01X562599D02*
G03I-19685J0D01*
G01X565355Y179626D02*
Y218996D01*
G01X558662Y103172D02*
Y153127D01*
G01Y155374D02*
Y153127D01*
G01X615749Y179626D02*
X565355D01*
G01X611812Y159311D02*
X562599D01*
G01X611812D02*
X562599D01*
G01D02*
X611812D01*
G01X562599D02*
G03X558662Y155374I0J-3937D01*
G01X562599Y159311D02*
G03X558662Y155374I0J-3937D01*
G01X562599Y159311D02*
X611812D01*
G01X566536Y151437D02*
X574076D01*
G01X549804Y128150D02*
G03X536024I-6890J-1D01*
G01D02*
G03X549804I6890J-1D01*
G01X574076Y151437D02*
G03Y159311I0J3937D01*
G01X561443Y214100D02*
X561532Y214131D01*
G01X561679Y214040D02*
X561561Y213950D01*
G01D02*
X561414Y213920D01*
G01X561532Y214131D02*
X561591Y214191D01*
G01X562659Y214462D02*
X562482Y214251D01*
G01Y214493D02*
X562659Y214704D01*
G01D02*
X562836D01*
G01X560705D02*
X561414D01*
G01X561443Y214553D02*
X560882D01*
G01Y214100D02*
X561443D01*
G01X561414Y213920D02*
X560882D01*
G01Y213286D02*
X560705D01*
G01X562836D02*
X562659D01*
G01X561768Y214161D02*
X561679Y214040D01*
G01X561414Y214704D02*
X561561Y214673D01*
G01X561532Y214523D02*
X561443Y214553D01*
G01X561797Y214251D02*
X561768Y214161D01*
G01X561591Y214191D02*
X561620Y214281D01*
G01X562836Y214704D02*
Y213286D01*
G01X562659D02*
Y214462D01*
G01X562482Y214251D02*
Y214493D01*
G01X561797Y214372D02*
Y214251D01*
G01X561620Y214281D02*
Y214372D01*
G01X560882Y213920D02*
Y213286D01*
G01Y214553D02*
Y214100D01*
G01X560705Y213286D02*
Y214704D01*
G01X561768Y214462D02*
X561797Y214372D01*
G01X561620D02*
X561591Y214462D01*
G01X561679Y214583D02*
X561768Y214462D01*
G01X561591D02*
X561532Y214523D01*
G01X561561Y214673D02*
X561679Y214583D01*
G01X564353Y249862D02*
G03Y241988I0J-3937D01*
G01X521844D02*
G03Y249862I0J3937D01*
G01X580546Y188011D02*
G03X580090Y187796I0J-590D01*
G01Y192715D02*
G03X580546Y192500I456J375D01*
G01Y204547D02*
G03X580090Y204332I0J-591D01*
G01Y209250D02*
G03X580546Y209035I456J376D01*
G01X567914D02*
G03X568505Y209626I0J591D01*
G01Y203956D02*
G03X567914Y204547I-591J0D01*
G01X568505Y187421D02*
G03X567914Y188011I-590J0D01*
G01Y192500D02*
G03X568505Y193090I1J590D01*
G01X579529Y209932D02*
X580090Y209250D01*
G01X579529Y193396D02*
X580090Y192715D01*
G01X579529Y197637D02*
Y182874D01*
G01Y214173D02*
Y199409D01*
G01X568505Y214173D02*
Y182874D01*
G01X566930Y192500D02*
Y188011D01*
G01Y209035D02*
Y204547D01*
G01X566536Y214173D02*
Y182874D01*
G01X562993Y192500D02*
Y188011D01*
G01Y209035D02*
Y204547D01*
G01X562206Y191634D02*
Y188878D01*
G01Y208169D02*
Y205413D01*
G01X559843D02*
Y208169D01*
G01Y188878D02*
Y191634D01*
G01X559056Y204547D02*
Y209035D01*
G01Y188011D02*
Y192500D01*
G01X545277D02*
Y188011D01*
G01Y209035D02*
Y204547D01*
G01X541340Y192500D02*
Y188011D01*
G01Y209035D02*
Y204547D01*
G01X540552Y191634D02*
Y188878D01*
G01Y208169D02*
Y205413D01*
G01X538190D02*
Y208169D01*
G01Y188878D02*
Y191634D01*
G01X537403Y204547D02*
Y209035D01*
G01Y188011D02*
Y192500D01*
G01X559056Y208284D02*
X559843Y208169D01*
G01X562206Y205413D02*
X562993Y205298D01*
G01X537403Y208284D02*
X538190Y208169D01*
G01X541340Y205298D02*
X540552Y205413D01*
G01X559056Y191749D02*
X559843Y191634D01*
G01X562206Y188878D02*
X562993Y188762D01*
G01X537403Y191749D02*
X538190Y191634D01*
G01X541340Y188762D02*
X540552Y188878D01*
G01X565355Y218996D02*
X615749D01*
G01Y217421D02*
X565355D01*
G01X615749Y215846D02*
X565355D01*
G01X615749Y214173D02*
X565355D01*
G01X580090Y187796D02*
X579529Y187115D01*
G01X615355Y210236D02*
X579529D01*
G01X580546Y209035D02*
X599511D01*
G01X537403D02*
X567914D01*
G01X559843Y208169D02*
X562206D01*
G01X538190D02*
X540552D01*
G01Y205413D02*
X538190D01*
G01X562206D02*
X559843D01*
G01X537403Y204547D02*
X567914D01*
G01X599511D02*
X580546D01*
G01X615355Y203346D02*
X579529D01*
G01Y199409D02*
X615355D01*
G01Y197637D02*
X579529D01*
G01X615355Y193700D02*
X579529D01*
G01X580546Y192500D02*
X599511D01*
G01X537403D02*
X567914D01*
G01X559843Y191634D02*
X562206D01*
G01X538190D02*
X540552D01*
G01Y188878D02*
X538190D01*
G01X562206D02*
X559843D01*
G01X537403Y188011D02*
X567914D01*
G01X599511D02*
X580546D01*
G01X615355Y186811D02*
X579529D01*
G01X580090Y204332D02*
X579529Y203650D01*
G01X615749Y182874D02*
X565355D01*
G01Y181200D02*
X615749D01*
G01X540552Y208169D02*
X541340Y208284D01*
G01X538190Y205413D02*
X537403Y205298D01*
G01X562206Y208169D02*
X562993Y208284D01*
G01X559843Y205413D02*
X559056Y205298D01*
G01X540552Y191634D02*
X541340Y191749D01*
G01X538190Y188878D02*
X537403Y188762D01*
G01X562206Y191634D02*
X562993Y191749D01*
G01X559843Y188878D02*
X559056Y188762D01*
G01X542796Y495787D02*
Y563228D01*
G01Y495787D02*
G03X546733Y491850I3937J0D01*
G01X606244D02*
X546733D01*
G01X606244D02*
X546733D01*
G01X542796Y495787D02*
G03X546733Y491850I3937J0D01*
G01X550670Y499724D02*
Y563622D01*
G01X570124Y491850D02*
G03Y499724I0J3937D01*
G01D02*
X550670D01*
G01Y565196D02*
X622403D01*
G01X542796Y563228D02*
X540828Y565196D01*
G01X550670Y563622D02*
Y565196D01*
G01X553543Y772080D02*
X554013Y771555D01*
X554561Y771240D01*
X555266Y771135D01*
X555971Y771345D01*
X556519Y771765D01*
X556911Y772500D01*
X556989Y773340D01*
X556833Y774180D01*
X556441Y774705D01*
X555893Y775125D01*
X555344Y775230D01*
X554796Y775125D01*
X554091Y774705D01*
X554326Y777435D01*
X556441D01*
G01X634530Y-578426D02*
Y-595749D01*
G01X622403Y-73346D02*
G03X637403Y-58346I0J15000D01*
G01Y253799D02*
Y-58346D01*
G01X611812Y159311D02*
G03X615749Y163248I0J3937D01*
G01X611812Y159311D02*
G03X615749Y163248I0J3937D01*
G01D02*
Y228546D01*
G01D02*
Y163248D01*
G01D02*
Y228546D01*
G01X611812Y159311D02*
G03X615749Y163248I0J3937D01*
G01X611812Y159311D02*
G03X615749Y163248I0J3937D01*
G01X611812Y151437D02*
G03X623623Y163248I0J11811D01*
G01X615749D02*
Y228546D01*
G01X623623Y163248D02*
Y228546D01*
G01X604785Y159311D02*
G03Y151437I0J-3937D01*
G01D02*
X611812D01*
G01X615749Y228546D02*
G03X614596Y231330I-3937J0D01*
G01X605091Y240835D02*
G03X602307Y241988I-2784J-2784D01*
G01X605091Y240835D02*
G03X602307Y241988I-2784J-2784D01*
G01X615749Y228546D02*
G03X614596Y231330I-3937J0D01*
G01X603151Y207428D02*
G03X602747Y207989I-591J0D01*
G01Y205593D02*
G03X603151Y206154I-187J561D01*
G01Y190893D02*
G03X602747Y191453I-591J0D01*
G01Y189058D02*
G03X603151Y189618I-187J560D01*
G01X599698Y209005D02*
G03X599511Y209035I-186J-561D01*
G01Y204547D02*
G03X599698Y204577I1J591D01*
G01Y192469D02*
G03X599511Y192500I-189J-560D01*
G01Y188011D02*
G03X599698Y188042I-2J591D01*
G01X614596Y231330D02*
X605091Y240835D01*
G01D02*
X614596Y231330D01*
G01X615355Y199409D02*
X615749Y199015D01*
G01X615355Y182874D02*
X615749Y182480D01*
G01X615355Y197637D02*
Y182874D01*
G01Y214173D02*
Y199409D01*
G01X608325Y191880D02*
Y205265D01*
G01X603544D02*
Y191880D01*
G01X603207Y205265D02*
Y191880D01*
G01X603151Y190893D02*
Y189618D01*
G01Y207428D02*
Y206154D01*
G01X599607Y192492D02*
Y188019D01*
G01Y209027D02*
Y204555D01*
G01X615355Y203346D02*
X615749Y203183D01*
G01Y186648D02*
X615355Y186811D01*
G01X599698Y209005D02*
X602747Y207989D01*
G01X599698Y192469D02*
X602747Y191453D01*
G01X615749Y205265D02*
X603207D01*
G01Y191880D02*
X615749D01*
G01X615355Y197637D02*
X615749Y198031D01*
G01Y214567D02*
X615355Y214173D01*
G01Y193700D02*
X615749Y193864D01*
G01X602747Y189058D02*
X599698Y188042D01*
G01X615355Y210236D02*
X615749Y210399D01*
G01X602747Y205593D02*
X599698Y204577D01*
G01X615749Y253799D02*
Y482345D01*
G01X611812Y249862D02*
G03X615749Y253799I0J3937D01*
G01X605091Y240835D02*
G03X602307Y241988I-2784J-2784D01*
G01X614596Y231330D02*
X605091Y240835D01*
G01X615749Y228546D02*
G03X614596Y231330I-3937J0D01*
G01X615749Y228546D02*
G03X614596Y231330I-3937J0D01*
G01D02*
X605091Y240835D01*
G01D02*
G03X602307Y241988I-2784J-2784D01*
G01X611812Y249862D02*
G03X615749Y253799I0J3937D01*
G01D02*
Y482345D01*
G01X623623Y253799D02*
Y274659D01*
G01X637403Y253799D02*
Y482345D01*
G01X623623Y228546D02*
Y253799D01*
G01Y274659D02*
G03X615749I-3937J0D01*
G01Y305368D02*
G03X623623I3937J0D01*
G01D02*
Y410289D01*
G01X606901Y363700D02*
G03X593101I-6900J0D01*
G01D02*
G03X606901I6900J0D01*
G01D02*
G03I-6900J0D01*
G01D02*
G03I-6900J0D01*
G01X593111D02*
G03X606891I6890J0D01*
G01D02*
G03X593111I-6890J0D01*
G01X606901D02*
G03X593101I-6900J0D01*
G01D02*
G03X606901I6900J0D01*
G01X593111D02*
G03X606891I6890J0D01*
G01D02*
G03X593111I-6890J0D01*
G01X623623Y410289D02*
G03X615749I-3937J0D01*
G01Y476845D02*
Y617102D01*
G01X609028Y490697D02*
G03X606244Y491850I-2784J-2784D01*
G01X614596Y485129D02*
X609028Y490697D01*
G01X615749Y482345D02*
G03X614596Y485129I-3937J0D01*
G01X615749Y482345D02*
G03X614596Y485129I-3937J0D01*
G01X623623Y482345D02*
G03X620164Y490697I-11811J1D01*
G01X614596Y485129D02*
X609028Y490697D01*
G01X620164D02*
X614596Y496265D01*
G01X609028Y490697D02*
G03X606244Y491850I-2784J-2784D01*
G01X614596Y496265D02*
G03X606244Y499724I-8351J-8352D01*
G01D02*
X600833D01*
G01X637403Y482345D02*
Y550196D01*
G01X600833Y499724D02*
G03Y491850I0J-3937D01*
G01X615749Y440998D02*
G03X623623I3937J0D01*
G01D02*
Y482345D01*
G01X637403Y545865D02*
Y617102D01*
G01Y550196D02*
G03X622403Y565196I-15000J0D01*
G01X667682Y626196D02*
X651934D01*
X655083Y623834D01*
G01X667682D02*
Y628558D01*
G01X661121Y638204D02*
X659283Y639582D01*
X658233Y640763D01*
X657708Y642338D01*
X658233Y643716D01*
X659283Y644700D01*
X660858Y645488D01*
X662695Y645685D01*
X664270Y645488D01*
X665845Y644700D01*
X667157Y643519D01*
X667682Y642141D01*
X667157Y640567D01*
X665583Y639189D01*
X663220Y638401D01*
X660595Y638204D01*
X657184Y638598D01*
X655346Y639189D01*
X653509Y640173D01*
X652196Y641551D01*
X651934Y642929D01*
X652459Y644307D01*
X653771Y645291D01*
G01X667682Y657299D02*
X664270Y657692D01*
X661383Y658283D01*
X658758Y659070D01*
X655871Y660055D01*
X651934Y661630D01*
Y653755D01*
G01X668207Y673440D02*
X667944Y673047D01*
X667420D01*
X667157Y673440D01*
X667420Y673834D01*
X667944D01*
X668207Y673440D01*
G01X667682Y691551D02*
X651934D01*
X663220Y684267D01*
Y694110D01*
G01X651934Y704936D02*
X652459Y703361D01*
X653771Y702181D01*
X655346Y701393D01*
X657446Y700803D01*
X659808Y700606D01*
X662170Y700803D01*
X664270Y701393D01*
X665845Y702181D01*
X667157Y703361D01*
X667682Y704936D01*
X667157Y706511D01*
X665845Y707692D01*
X664270Y708480D01*
X662170Y709070D01*
X659808Y709267D01*
X657446Y709070D01*
X655346Y708480D01*
X653771Y707692D01*
X652459Y706511D01*
X651934Y704936D01*
G01X628171Y626196D02*
X612423D01*
X615572Y623834D01*
G01X628171D02*
Y628558D01*
G01X621610Y638204D02*
X619772Y639582D01*
X618722Y640763D01*
X618197Y642338D01*
X618722Y643716D01*
X619772Y644700D01*
X621347Y645488D01*
X623184Y645685D01*
X624759Y645488D01*
X626334Y644700D01*
X627646Y643519D01*
X628171Y642141D01*
X627646Y640567D01*
X626072Y639189D01*
X623709Y638401D01*
X621084Y638204D01*
X617673Y638598D01*
X615835Y639189D01*
X613998Y640173D01*
X612685Y641551D01*
X612423Y642929D01*
X612948Y644307D01*
X614260Y645291D01*
G01X628171Y657692D02*
X612423D01*
X615572Y655330D01*
G01X628171D02*
Y660054D01*
G01X628696Y673440D02*
X628433Y673047D01*
X627909D01*
X627646Y673440D01*
X627909Y673834D01*
X628433D01*
X628696Y673440D01*
G01X626334Y685842D02*
X627646Y687220D01*
X628171Y688795D01*
X627646Y690370D01*
X626072Y691748D01*
X623709Y692732D01*
X621347Y693126D01*
X618460D01*
X616098Y692732D01*
X613998Y691748D01*
X612948Y690566D01*
X612423Y689188D01*
X612948Y687613D01*
X613998Y686433D01*
X615572Y685645D01*
X617673Y685251D01*
X619510Y685645D01*
X621347Y686629D01*
X622397Y687811D01*
X622659Y689188D01*
X622135Y690763D01*
X620822Y691944D01*
X618460Y693126D01*
G01X612423Y704936D02*
X612948Y703361D01*
X614260Y702181D01*
X615835Y701393D01*
X617935Y700803D01*
X620297Y700606D01*
X622659Y700803D01*
X624759Y701393D01*
X626334Y702181D01*
X627646Y703361D01*
X628171Y704936D01*
X627646Y706511D01*
X626334Y707692D01*
X624759Y708480D01*
X622659Y709070D01*
X620297Y709267D01*
X617935Y709070D01*
X615835Y708480D01*
X614260Y707692D01*
X612948Y706511D01*
X612423Y704936D01*
G01X620297Y618520D02*
Y619937D01*
G01X615749Y617102D02*
X620297Y618520D01*
G01X659808D02*
Y619937D01*
G01X637403Y617102D02*
X659808Y618520D01*
G01X634530Y782204D02*
Y764881D01*
G01X727006Y-586870D02*
X727554Y-586135D01*
X728024Y-585715D01*
X728651Y-585505D01*
X729199Y-585715D01*
X729591Y-586135D01*
X729904Y-586765D01*
X729982Y-587500D01*
X729904Y-588130D01*
X729591Y-588760D01*
X729121Y-589285D01*
X728572Y-589495D01*
X727946Y-589285D01*
X727397Y-588655D01*
X727084Y-587710D01*
X727006Y-586660D01*
X727162Y-585295D01*
X727397Y-584560D01*
X727789Y-583825D01*
X728337Y-583300D01*
X728886Y-583195D01*
X729434Y-583405D01*
X729826Y-583930D01*
G01X727006Y773760D02*
X727554Y774495D01*
X728024Y774915D01*
X728651Y775125D01*
X729199Y774915D01*
X729591Y774495D01*
X729904Y773865D01*
X729982Y773130D01*
X729904Y772500D01*
X729591Y771870D01*
X729121Y771345D01*
X728572Y771135D01*
X727946Y771345D01*
X727397Y771975D01*
X727084Y772920D01*
X727006Y773970D01*
X727162Y775335D01*
X727397Y776070D01*
X727789Y776805D01*
X728337Y777330D01*
X728886Y777435D01*
X729434Y777225D01*
X729826Y776700D01*
G01X758940Y-562678D02*
Y-306773D01*
G01Y-562678D02*
X1703822D01*
G01X807759Y-578426D02*
Y-595749D01*
G01X788800Y-474046D02*
X787221Y-472993D01*
X785378Y-472291D01*
X783272D01*
X780903Y-473344D01*
X779061Y-475099D01*
X777744Y-477205D01*
X776691Y-480715D01*
X776428Y-483874D01*
X776955Y-487032D01*
X777744Y-489138D01*
X779324Y-491245D01*
X781167Y-492648D01*
X783009Y-493350D01*
X784851D01*
X786694Y-492648D01*
X788274Y-491595D01*
X789590Y-490192D01*
G01X800383Y-493350D02*
Y-479311D01*
G01Y-482118D02*
X801699Y-480715D01*
X803015Y-479662D01*
X804858Y-479311D01*
X806174Y-479662D01*
X807753Y-480715D01*
G01X821179Y-483874D02*
X829602D01*
X828812Y-481417D01*
X827496Y-480013D01*
X825654Y-479311D01*
X823811Y-479662D01*
X822231Y-480715D01*
X821179Y-483172D01*
X820652Y-485278D01*
Y-487383D01*
X821179Y-489489D01*
X822495Y-491595D01*
X824074Y-492999D01*
X825917Y-493350D01*
X827759Y-492648D01*
X829602Y-490543D01*
G01X850924Y-493350D02*
Y-479311D01*
G01Y-481767D02*
X849871Y-480364D01*
X848292Y-479662D01*
X846449Y-479311D01*
X844607Y-480013D01*
X843027Y-481417D01*
X841974Y-483523D01*
X841448Y-486331D01*
X841974Y-489138D01*
X843027Y-491245D01*
X844607Y-492648D01*
X846449Y-493350D01*
X848292Y-492999D01*
X849871Y-491946D01*
X850924Y-490543D01*
G01X867245Y-472291D02*
Y-493350D01*
G01X863560Y-479311D02*
X870930D01*
G01X884356Y-483874D02*
X892779D01*
X891989Y-481417D01*
X890673Y-480013D01*
X888831Y-479311D01*
X886988Y-479662D01*
X885408Y-480715D01*
X884356Y-483172D01*
X883829Y-485278D01*
Y-487383D01*
X884356Y-489489D01*
X885672Y-491595D01*
X887251Y-492999D01*
X889094Y-493350D01*
X890936Y-492648D01*
X892779Y-490543D01*
G01X914101Y-472291D02*
Y-493350D01*
G01Y-490192D02*
X913048Y-491946D01*
X911469Y-492999D01*
X909626Y-493350D01*
X907521Y-492648D01*
X905941Y-490894D01*
X904888Y-488788D01*
X904625Y-486331D01*
X904888Y-483874D01*
X905941Y-481767D01*
X907521Y-480013D01*
X909626Y-479311D01*
X911469Y-479662D01*
X912785Y-480364D01*
X914101Y-481767D01*
G01X1703822Y-502415D02*
X758940D01*
G01X773726Y-423383D02*
X780307Y-444442D01*
X786888Y-423383D01*
G01X797418Y-434966D02*
X805841D01*
X805051Y-432509D01*
X803735Y-431105D01*
X801893Y-430403D01*
X800050Y-430754D01*
X798470Y-431807D01*
X797418Y-434264D01*
X796891Y-436370D01*
Y-438475D01*
X797418Y-440581D01*
X798734Y-442687D01*
X800313Y-444091D01*
X802156Y-444442D01*
X803998Y-443740D01*
X805841Y-441635D01*
G01X818740Y-444442D02*
Y-430403D01*
G01Y-433210D02*
X820056Y-431807D01*
X821372Y-430754D01*
X823215Y-430403D01*
X824531Y-430754D01*
X826110Y-431807D01*
G01X839536Y-441986D02*
X840852Y-443389D01*
X842694Y-444442D01*
X844274D01*
X845853Y-443740D01*
X846906Y-442687D01*
X847432Y-441284D01*
X847169Y-439177D01*
X846116Y-438124D01*
X841378Y-436019D01*
X840325Y-433561D01*
X840852Y-431807D01*
X841905Y-430754D01*
X843484Y-430403D01*
X845063Y-430754D01*
X846643Y-431807D01*
G01X864543Y-430403D02*
Y-444442D01*
G01Y-424787D02*
X864016Y-424436D01*
Y-423734D01*
X864543Y-423383D01*
X865070Y-423734D01*
Y-424436D01*
X864543Y-424787D01*
G01X885602Y-444442D02*
X884023Y-444091D01*
X882443Y-442687D01*
X881390Y-440230D01*
X880864Y-437423D01*
X881390Y-434615D01*
X882443Y-432158D01*
X884023Y-430754D01*
X885602Y-430403D01*
X887181Y-430754D01*
X888761Y-432158D01*
X889814Y-434615D01*
X890077Y-437423D01*
X889814Y-440230D01*
X888761Y-442687D01*
X887181Y-444091D01*
X885602Y-444442D01*
G01X902186D02*
Y-430403D01*
G01Y-433913D02*
X903239Y-432158D01*
X904819Y-430754D01*
X906924Y-430403D01*
X908767Y-430754D01*
X910346Y-432158D01*
X911136Y-434615D01*
Y-444442D01*
G01X777744Y-400429D02*
Y-379370D01*
X784062D01*
X786168Y-380423D01*
X787747Y-382880D01*
X788274Y-385688D01*
X787747Y-388496D01*
X786431Y-390602D01*
X784062Y-391655D01*
X777744D01*
G01X809859Y-381125D02*
X808280Y-380072D01*
X806437Y-379370D01*
X804331D01*
X801962Y-380423D01*
X800120Y-382178D01*
X798803Y-384284D01*
X797750Y-387794D01*
X797487Y-390953D01*
X798014Y-394111D01*
X798803Y-396217D01*
X800383Y-398324D01*
X802226Y-399727D01*
X804068Y-400429D01*
X805910D01*
X807753Y-399727D01*
X809333Y-398674D01*
X810649Y-397271D01*
G01X827233Y-389197D02*
X828286Y-388145D01*
X829075Y-386390D01*
X829602Y-383932D01*
X829075Y-381827D01*
X828023Y-380423D01*
X826180Y-379370D01*
X819073D01*
Y-400429D01*
X827759D01*
X829602Y-399025D01*
X830655Y-396919D01*
X831181Y-394462D01*
X830655Y-392006D01*
X829075Y-389900D01*
X827233Y-389197D01*
X819073D01*
G01X861191Y-400429D02*
Y-379370D01*
X873299Y-400429D01*
Y-379370D01*
G01X888304Y-400429D02*
X886725Y-400078D01*
X885145Y-398674D01*
X884092Y-396217D01*
X883566Y-393410D01*
X884092Y-390602D01*
X885145Y-388145D01*
X886725Y-386741D01*
X888304Y-386390D01*
X889883Y-386741D01*
X891463Y-388145D01*
X892516Y-390602D01*
X892779Y-393410D01*
X892516Y-396217D01*
X891463Y-398674D01*
X889883Y-400078D01*
X888304Y-400429D01*
G01X909363Y-401131D02*
X908836Y-400780D01*
Y-400078D01*
X909363Y-399727D01*
X909890Y-400078D01*
Y-400780D01*
X909363Y-401131D01*
G01X758940Y-412163D02*
X1703822D01*
G01X758940Y-457289D02*
X1290167D01*
G01X786226Y-356215D02*
Y-327635D01*
X795514Y-351452D01*
X804803Y-327635D01*
Y-356215D01*
G01X824094D02*
X821951Y-355739D01*
X819807Y-353834D01*
X818378Y-350499D01*
X817664Y-346689D01*
X818378Y-342878D01*
X819807Y-339543D01*
X821951Y-337638D01*
X824094Y-337162D01*
X826238Y-337638D01*
X828382Y-339543D01*
X829810Y-342878D01*
X830168Y-346689D01*
X829810Y-350499D01*
X828382Y-353834D01*
X826238Y-355739D01*
X824094Y-356215D01*
G01X859105Y-327635D02*
Y-356215D01*
G01Y-351929D02*
X857676Y-354310D01*
X855532Y-355739D01*
X853032Y-356215D01*
X850174Y-355263D01*
X848030Y-352881D01*
X846601Y-350023D01*
X846244Y-346689D01*
X846601Y-343354D01*
X848030Y-340496D01*
X850174Y-338115D01*
X853032Y-337162D01*
X855532Y-337638D01*
X857319Y-338591D01*
X859105Y-340496D01*
G01X875896Y-343354D02*
X887328D01*
X886256Y-340020D01*
X884470Y-338115D01*
X881969Y-337162D01*
X879468Y-337638D01*
X877325Y-339067D01*
X875896Y-342402D01*
X875181Y-345260D01*
Y-348117D01*
X875896Y-350976D01*
X877682Y-353834D01*
X879825Y-355739D01*
X882326Y-356215D01*
X884827Y-355263D01*
X887328Y-352405D01*
G01X909834Y-356215D02*
Y-327635D01*
G01X758940Y-306773D02*
X1703822D01*
G01X758940Y-367037D02*
X1703822D01*
G01X807759Y782204D02*
Y764881D01*
G01X901566Y-589495D02*
X901723Y-588130D01*
X901958Y-586975D01*
X902271Y-585925D01*
X902663Y-584770D01*
X903290Y-583195D01*
X900156D01*
G01X901566Y771135D02*
X901723Y772500D01*
X901958Y773655D01*
X902271Y774705D01*
X902663Y775860D01*
X903290Y777435D01*
X900156D01*
G01X955791Y-516041D02*
X961713Y-549885D01*
X968482Y-516041D01*
X975251Y-549885D01*
X981174Y-516041D01*
G01X1002326Y-527323D02*
Y-549885D01*
G01Y-518298D02*
X1001480Y-517734D01*
Y-516605D01*
X1002326Y-516041D01*
X1003173Y-516605D01*
Y-517734D01*
X1002326Y-518298D01*
G01X1029825Y-545937D02*
X1031940Y-548193D01*
X1034901Y-549885D01*
X1037440D01*
X1039978Y-548757D01*
X1041670Y-547065D01*
X1042516Y-544809D01*
X1042093Y-541424D01*
X1040401Y-539732D01*
X1032786Y-536348D01*
X1031094Y-532399D01*
X1031940Y-529579D01*
X1033632Y-527887D01*
X1036170Y-527323D01*
X1038709Y-527887D01*
X1041247Y-529579D01*
G01X1070014Y-516041D02*
Y-549885D01*
G01X1064092Y-527323D02*
X1075937D01*
G01X1097936Y-549885D02*
Y-527323D01*
G01Y-531835D02*
X1100051Y-529579D01*
X1102166Y-527887D01*
X1105128Y-527323D01*
X1107243Y-527887D01*
X1109781Y-529579D01*
G01X1137702Y-549885D02*
X1135164Y-549321D01*
X1132626Y-547065D01*
X1130933Y-543117D01*
X1130087Y-538604D01*
X1130933Y-534091D01*
X1132626Y-530143D01*
X1135164Y-527887D01*
X1137702Y-527323D01*
X1140241Y-527887D01*
X1142779Y-530143D01*
X1144471Y-534091D01*
X1144895Y-538604D01*
X1144471Y-543117D01*
X1142779Y-547065D01*
X1140241Y-549321D01*
X1137702Y-549885D01*
G01X1164354D02*
Y-527323D01*
G01Y-532964D02*
X1166047Y-530143D01*
X1168585Y-527887D01*
X1171970Y-527323D01*
X1174931Y-527887D01*
X1177469Y-530143D01*
X1178739Y-534091D01*
Y-549885D01*
G01X1248542Y-518862D02*
X1246003Y-517169D01*
X1243042Y-516041D01*
X1239658D01*
X1235850Y-517734D01*
X1232889Y-520554D01*
X1230773Y-523938D01*
X1229081Y-529579D01*
X1228658Y-534655D01*
X1229504Y-539732D01*
X1230773Y-543117D01*
X1233312Y-546501D01*
X1236273Y-548757D01*
X1239234Y-549885D01*
X1242196D01*
X1245157Y-548757D01*
X1247696Y-547065D01*
X1249811Y-544809D01*
G01X1273078Y-549885D02*
X1270540Y-549321D01*
X1268002Y-547065D01*
X1266309Y-543117D01*
X1265463Y-538604D01*
X1266309Y-534091D01*
X1268002Y-530143D01*
X1270540Y-527887D01*
X1273078Y-527323D01*
X1275617Y-527887D01*
X1278155Y-530143D01*
X1279847Y-534091D01*
X1280271Y-538604D01*
X1279847Y-543117D01*
X1278155Y-547065D01*
X1275617Y-549321D01*
X1273078Y-549885D01*
G01X1301000D02*
Y-527323D01*
G01Y-531835D02*
X1303115Y-529579D01*
X1305230Y-527887D01*
X1308192Y-527323D01*
X1310307Y-527887D01*
X1312845Y-529579D01*
G01X1333151Y-561166D02*
Y-527323D01*
G01Y-532399D02*
X1335267Y-529579D01*
X1337382Y-527887D01*
X1340766Y-527323D01*
X1343728Y-527887D01*
X1346689Y-530707D01*
X1347959Y-534655D01*
X1348382Y-538604D01*
X1347959Y-542553D01*
X1346689Y-546501D01*
X1344151Y-548757D01*
X1340766Y-549885D01*
X1337805Y-549321D01*
X1334844Y-547629D01*
X1333151Y-545373D01*
G01X1374610Y-549885D02*
X1372072Y-549321D01*
X1369534Y-547065D01*
X1367841Y-543117D01*
X1366995Y-538604D01*
X1367841Y-534091D01*
X1369534Y-530143D01*
X1372072Y-527887D01*
X1374610Y-527323D01*
X1377149Y-527887D01*
X1379687Y-530143D01*
X1381379Y-534091D01*
X1381803Y-538604D01*
X1381379Y-543117D01*
X1379687Y-547065D01*
X1377149Y-549321D01*
X1374610Y-549885D01*
G01X1402532D02*
Y-527323D01*
G01Y-531835D02*
X1404647Y-529579D01*
X1406762Y-527887D01*
X1409724Y-527323D01*
X1411839Y-527887D01*
X1414377Y-529579D01*
G01X1449914Y-549885D02*
Y-527323D01*
G01Y-531271D02*
X1448221Y-529015D01*
X1445683Y-527887D01*
X1442722Y-527323D01*
X1439760Y-528451D01*
X1437222Y-530707D01*
X1435529Y-534091D01*
X1434683Y-538604D01*
X1435529Y-543117D01*
X1437222Y-546501D01*
X1439760Y-548757D01*
X1442722Y-549885D01*
X1445683Y-549321D01*
X1448221Y-547629D01*
X1449914Y-545373D01*
G01X1476142Y-516041D02*
Y-549885D01*
G01X1470220Y-527323D02*
X1482065D01*
G01X1509986D02*
Y-549885D01*
G01Y-518298D02*
X1509140Y-517734D01*
Y-516605D01*
X1509986Y-516041D01*
X1510833Y-516605D01*
Y-517734D01*
X1509986Y-518298D01*
G01X1543830Y-549885D02*
X1541292Y-549321D01*
X1538754Y-547065D01*
X1537061Y-543117D01*
X1536215Y-538604D01*
X1537061Y-534091D01*
X1538754Y-530143D01*
X1541292Y-527887D01*
X1543830Y-527323D01*
X1546369Y-527887D01*
X1548907Y-530143D01*
X1550599Y-534091D01*
X1551023Y-538604D01*
X1550599Y-543117D01*
X1548907Y-547065D01*
X1546369Y-549321D01*
X1543830Y-549885D01*
G01X1570482D02*
Y-527323D01*
G01Y-532964D02*
X1572175Y-530143D01*
X1574713Y-527887D01*
X1578098Y-527323D01*
X1581059Y-527887D01*
X1583597Y-530143D01*
X1584867Y-534091D01*
Y-549885D01*
G01X980987Y-578426D02*
Y-595749D01*
G01X978882Y-491375D02*
X985463Y-470316D01*
X992044Y-491375D01*
G01X989675Y-484005D02*
X981251D01*
G01X1001257Y-470316D02*
Y-491375D01*
X1011787D01*
G01X1024422Y-470316D02*
X1030739D01*
G01X1027581D02*
Y-491375D01*
G01X1024422D02*
X1030739D01*
G01X1043112Y-488568D02*
X1045218Y-490322D01*
X1047587Y-491375D01*
X1049693D01*
X1051799Y-490322D01*
X1053378Y-488568D01*
X1054168Y-486110D01*
X1053642Y-483654D01*
X1052325Y-481548D01*
X1049956Y-480143D01*
X1046798Y-479442D01*
X1044955Y-478038D01*
X1044165Y-475581D01*
X1044692Y-473124D01*
X1046008Y-471369D01*
X1047850Y-470316D01*
X1049693D01*
X1051536Y-471018D01*
X1053115Y-472773D01*
G01X1063118Y-491375D02*
X1069699Y-470316D01*
X1076280Y-491375D01*
G01X1073911Y-484005D02*
X1065487D01*
G01X947917Y-502415D02*
Y-306893D01*
G01X991211Y-398454D02*
Y-377395D01*
X988052Y-381607D01*
G01Y-398454D02*
X994369D01*
G01X1006479Y-395296D02*
X1008058Y-397050D01*
X1009901Y-398103D01*
X1012270Y-398454D01*
X1014639Y-397752D01*
X1016482Y-396349D01*
X1017798Y-393892D01*
X1018061Y-391084D01*
X1017535Y-388276D01*
X1016218Y-386521D01*
X1014376Y-385117D01*
X1012533Y-384766D01*
X1010691Y-385117D01*
X1008322Y-386521D01*
X1009111Y-377395D01*
X1016218D01*
G01X1028854Y-395998D02*
X1030697Y-397752D01*
X1032802Y-398454D01*
X1034908Y-397752D01*
X1036751Y-395647D01*
X1038067Y-392487D01*
X1038594Y-389328D01*
Y-385468D01*
X1038067Y-382309D01*
X1036751Y-379501D01*
X1035171Y-378097D01*
X1033329Y-377395D01*
X1031223Y-378097D01*
X1029644Y-379501D01*
X1028591Y-381607D01*
X1028064Y-384415D01*
X1028591Y-386871D01*
X1029907Y-389328D01*
X1031487Y-390733D01*
X1033329Y-391084D01*
X1035435Y-390382D01*
X1037014Y-388627D01*
X1038594Y-385468D01*
G01X1049386Y-389680D02*
X1051229Y-387222D01*
X1052809Y-385819D01*
X1054915Y-385117D01*
X1056757Y-385819D01*
X1058073Y-387222D01*
X1059126Y-389328D01*
X1059390Y-391785D01*
X1059126Y-393892D01*
X1058073Y-395998D01*
X1056494Y-397752D01*
X1054651Y-398454D01*
X1052546Y-397752D01*
X1050703Y-395647D01*
X1049650Y-392487D01*
X1049386Y-388978D01*
X1049913Y-384415D01*
X1050703Y-381957D01*
X1052019Y-379501D01*
X1053861Y-377746D01*
X1055704Y-377395D01*
X1057547Y-378097D01*
X1058863Y-379852D01*
G01X1075447Y-398454D02*
X1077289Y-398103D01*
X1079395Y-397050D01*
X1080712Y-395296D01*
X1081238Y-392838D01*
X1080712Y-390382D01*
X1079132Y-388276D01*
X1076763Y-387222D01*
X1074131D01*
X1072551Y-386521D01*
X1071235Y-384766D01*
X1070709Y-382309D01*
X1071499Y-379852D01*
X1073341Y-378097D01*
X1075447Y-377395D01*
X1077553Y-378097D01*
X1079395Y-379852D01*
X1080185Y-382309D01*
X1079659Y-384766D01*
X1078343Y-386521D01*
X1076763Y-387222D01*
X1074131D01*
X1071762Y-388276D01*
X1070182Y-390382D01*
X1069656Y-392838D01*
X1070182Y-395296D01*
X1071499Y-397050D01*
X1073605Y-398103D01*
X1075447Y-398454D01*
G01X974057Y-352509D02*
Y-323567D01*
X981292D01*
X984186Y-325015D01*
X986357Y-326944D01*
X988166Y-329837D01*
X989613Y-333215D01*
X989975Y-338038D01*
X989613Y-342862D01*
X988166Y-346239D01*
X986357Y-349133D01*
X984186Y-351062D01*
X981292Y-352509D01*
X974057D01*
G01X1001912Y-323567D02*
X1010957Y-352509D01*
X1020002Y-323567D01*
G01X1039898D02*
Y-352509D01*
G01X1031577Y-323567D02*
X1048219D01*
G01X1090545Y-352509D02*
Y-323567D01*
X1099589D01*
X1102483Y-325015D01*
X1104292Y-326944D01*
X1105015Y-330803D01*
X1104292Y-334662D01*
X1102121Y-337073D01*
X1099589Y-338521D01*
X1090545D01*
G01X1099589D02*
X1105015Y-352509D01*
G01X1126721Y-333215D02*
Y-352509D01*
G01Y-325497D02*
X1125997Y-325015D01*
Y-324049D01*
X1126721Y-323567D01*
X1127445Y-324049D01*
Y-325015D01*
X1126721Y-325497D01*
G01X1150236Y-349133D02*
X1152044Y-351062D01*
X1154577Y-352509D01*
X1156747D01*
X1158918Y-351544D01*
X1160365Y-350098D01*
X1161088Y-348169D01*
X1160727Y-345273D01*
X1159280Y-343826D01*
X1152767Y-340933D01*
X1151321Y-337555D01*
X1152044Y-335144D01*
X1153492Y-333697D01*
X1155662Y-333215D01*
X1157832Y-333697D01*
X1160003Y-335144D01*
G01X1179177Y-339485D02*
X1190753D01*
X1189668Y-336109D01*
X1187859Y-334179D01*
X1185327Y-333215D01*
X1182794Y-333697D01*
X1180623Y-335144D01*
X1179177Y-338521D01*
X1178453Y-341415D01*
Y-344309D01*
X1179177Y-347203D01*
X1180985Y-350098D01*
X1183156Y-352027D01*
X1185688Y-352509D01*
X1188221Y-351544D01*
X1190753Y-348651D01*
G01X1208479Y-352509D02*
Y-333215D01*
G01Y-337073D02*
X1210288Y-335144D01*
X1212097Y-333697D01*
X1214629Y-333215D01*
X1216438Y-333697D01*
X1218609Y-335144D01*
G01X1279385Y-325979D02*
X1277214Y-324532D01*
X1274682Y-323567D01*
X1271788D01*
X1268531Y-325015D01*
X1266000Y-327426D01*
X1264191Y-330320D01*
X1262743Y-335144D01*
X1262381Y-339485D01*
X1263105Y-343826D01*
X1264191Y-346721D01*
X1266361Y-349615D01*
X1268894Y-351544D01*
X1271426Y-352509D01*
X1273958D01*
X1276491Y-351544D01*
X1278661Y-350098D01*
X1280471Y-348169D01*
G01X1306879Y-352509D02*
Y-333215D01*
G01Y-336591D02*
X1305432Y-334662D01*
X1303261Y-333697D01*
X1300729Y-333215D01*
X1298197Y-334179D01*
X1296026Y-336109D01*
X1294578Y-339003D01*
X1293855Y-342862D01*
X1294578Y-346721D01*
X1296026Y-349615D01*
X1298197Y-351544D01*
X1300729Y-352509D01*
X1303261Y-352027D01*
X1305432Y-350580D01*
X1306879Y-348651D01*
G01X1324243Y-352509D02*
Y-333215D01*
G01Y-337073D02*
X1326052Y-335144D01*
X1327861Y-333697D01*
X1330393Y-333215D01*
X1332202Y-333697D01*
X1334373Y-335144D01*
G01X1364761Y-323567D02*
Y-352509D01*
G01Y-348169D02*
X1363314Y-350580D01*
X1361143Y-352027D01*
X1358611Y-352509D01*
X1355717Y-351544D01*
X1353546Y-349133D01*
X1352099Y-346239D01*
X1351737Y-342862D01*
X1352099Y-339485D01*
X1353546Y-336591D01*
X1355717Y-334179D01*
X1358611Y-333215D01*
X1361143Y-333697D01*
X1362952Y-334662D01*
X1364761Y-336591D01*
G01X1376337Y-362156D02*
X1398043D01*
G01X1408534Y-348651D02*
X1411428Y-351062D01*
X1414684Y-352509D01*
X1417578D01*
X1420472Y-351062D01*
X1422643Y-348651D01*
X1423728Y-345273D01*
X1423005Y-341897D01*
X1421196Y-339003D01*
X1417940Y-337073D01*
X1413599Y-336109D01*
X1411066Y-334179D01*
X1409981Y-330803D01*
X1410705Y-327426D01*
X1412513Y-325015D01*
X1415046Y-323567D01*
X1417578D01*
X1420111Y-324532D01*
X1422281Y-326944D01*
G01X1437475Y-348651D02*
X1440369Y-351062D01*
X1443625Y-352509D01*
X1446519D01*
X1449413Y-351062D01*
X1451584Y-348651D01*
X1452669Y-345273D01*
X1451946Y-341897D01*
X1450137Y-339003D01*
X1446881Y-337073D01*
X1442540Y-336109D01*
X1440007Y-334179D01*
X1438922Y-330803D01*
X1439646Y-327426D01*
X1441454Y-325015D01*
X1443987Y-323567D01*
X1446519D01*
X1449052Y-324532D01*
X1451222Y-326944D01*
G01X1496080Y-328391D02*
X1498251Y-325497D01*
X1500784Y-324049D01*
X1503678Y-323567D01*
X1507295Y-324532D01*
X1509828Y-326944D01*
X1510551Y-329837D01*
X1510189Y-332733D01*
X1508742Y-335144D01*
X1501507Y-339967D01*
X1498251Y-343344D01*
X1496080Y-348169D01*
X1495357Y-352509D01*
X1510551D01*
G01X1555410Y-349133D02*
X1557218Y-351062D01*
X1559751Y-352509D01*
X1561921D01*
X1564092Y-351544D01*
X1565539Y-350098D01*
X1566262Y-348169D01*
X1565901Y-345273D01*
X1564454Y-343826D01*
X1557941Y-340933D01*
X1556495Y-337555D01*
X1557218Y-335144D01*
X1558666Y-333697D01*
X1560836Y-333215D01*
X1563006Y-333697D01*
X1565177Y-335144D01*
G01X1589777Y-352509D02*
Y-323567D01*
G01X1618718Y-352509D02*
X1616548Y-352027D01*
X1614377Y-350098D01*
X1612929Y-346721D01*
X1612206Y-342862D01*
X1612929Y-339003D01*
X1614377Y-335626D01*
X1616548Y-333697D01*
X1618718Y-333215D01*
X1620888Y-333697D01*
X1623059Y-335626D01*
X1624506Y-339003D01*
X1624868Y-342862D01*
X1624506Y-346721D01*
X1623059Y-350098D01*
X1620888Y-352027D01*
X1618718Y-352509D01*
G01X1647659Y-323567D02*
Y-352509D01*
G01X1642594Y-333215D02*
X1652724D01*
G01X1671174Y-349133D02*
X1672982Y-351062D01*
X1675515Y-352509D01*
X1677685D01*
X1679856Y-351544D01*
X1681303Y-350098D01*
X1682026Y-348169D01*
X1681665Y-345273D01*
X1680218Y-343826D01*
X1673705Y-340933D01*
X1672259Y-337555D01*
X1672982Y-335144D01*
X1674430Y-333697D01*
X1676600Y-333215D01*
X1678770Y-333697D01*
X1680941Y-335144D01*
G01X973884Y-145573D02*
X974540Y-145130D01*
G01Y-145573D02*
X973884D01*
G01X974540Y-145130D02*
Y-145573D01*
G01X973884Y-151331D02*
X974540Y-152216D01*
G01X973228Y-150888D02*
X973884Y-151331D01*
G01X971916Y-150445D02*
X973228Y-150888D01*
G01X969291Y-150445D02*
X971916D01*
G01X967979Y-150888D02*
X969291Y-150445D01*
G01X967322Y-151331D02*
X967979Y-150888D01*
G01X966666Y-152216D02*
X967322Y-151331D01*
G01Y-153102D02*
X966666Y-152216D01*
G01X967979Y-153545D02*
X967322Y-153102D01*
G01X969291Y-153988D02*
X967979Y-153545D01*
G01X971916Y-153988D02*
X969291D01*
G01X973228Y-153545D02*
X971916Y-153988D01*
G01X973884Y-153102D02*
X973228Y-153545D01*
G01X974540Y-152216D02*
X973884Y-153102D01*
G01X980446Y-94648D02*
X959085D01*
G01X976509Y-89080D02*
Y-123476D01*
G01X931231Y-92023D02*
X930345Y-92679D01*
G01X931674Y-91367D02*
X931231Y-92023D01*
G01X932117Y-90054D02*
X931674Y-91367D01*
G01X932117Y-87430D02*
Y-90054D01*
G01X931674Y-86117D02*
X932117Y-87430D01*
G01X931231Y-85461D02*
X931674Y-86117D01*
G01X930345Y-84805D02*
X931231Y-85461D01*
G01X929459D02*
X930345Y-84805D01*
G01X929016Y-86117D02*
X929459Y-85461D01*
G01X928573Y-87430D02*
X929016Y-86117D01*
G01X928573Y-90054D02*
Y-87430D01*
G01X929016Y-91367D02*
X928573Y-90054D01*
G01X929459Y-92023D02*
X929016Y-91367D01*
G01X930345Y-92679D02*
X929459Y-92023D01*
G01X945404D02*
X944518Y-92679D01*
G01X945847Y-91367D02*
X945404Y-92023D01*
G01X946290Y-90054D02*
X945847Y-91367D01*
G01X946290Y-87430D02*
Y-90054D01*
G01X945847Y-86117D02*
X946290Y-87430D01*
G01X945404Y-85461D02*
X945847Y-86117D01*
G01X944518Y-84805D02*
X945404Y-85461D01*
G01X943632D02*
X944518Y-84805D01*
G01X943190Y-86117D02*
X943632Y-85461D01*
G01X942747Y-87430D02*
X943190Y-86117D01*
G01X942747Y-90054D02*
Y-87430D01*
G01X943190Y-91367D02*
X942747Y-90054D01*
G01X943632Y-92023D02*
X943190Y-91367D01*
G01X944518Y-92679D02*
X943632Y-92023D01*
G01X952491D02*
X951605Y-92679D01*
G01X952934Y-91367D02*
X952491Y-92023D01*
G01X953377Y-90054D02*
X952934Y-91367D01*
G01X953377Y-87430D02*
Y-90054D01*
G01X952934Y-86117D02*
X953377Y-87430D01*
G01X952491Y-85461D02*
X952934Y-86117D01*
G01X951605Y-84805D02*
X952491Y-85461D01*
G01X950719D02*
X951605Y-84805D01*
G01X950276Y-86117D02*
X950719Y-85461D01*
G01X949833Y-87430D02*
X950276Y-86117D01*
G01X949833Y-90054D02*
Y-87430D01*
G01X950276Y-91367D02*
X949833Y-90054D01*
G01X950719Y-92023D02*
X950276Y-91367D01*
G01X951605Y-92679D02*
X950719Y-92023D01*
G01X973884Y-130071D02*
X974540Y-130957D01*
G01X973228Y-129628D02*
X973884Y-130071D01*
G01X971916Y-129185D02*
X973228Y-129628D01*
G01X969291Y-129185D02*
X971916D01*
G01X967979Y-129628D02*
X969291Y-129185D01*
G01X967322Y-130071D02*
X967979Y-129628D01*
G01X966666Y-130957D02*
X967322Y-130071D01*
G01Y-131842D02*
X966666Y-130957D01*
G01X967979Y-132285D02*
X967322Y-131842D01*
G01X969291Y-132728D02*
X967979Y-132285D01*
G01X971916Y-132728D02*
X969291D01*
G01X973228Y-132285D02*
X971916Y-132728D01*
G01X973884Y-131842D02*
X973228Y-132285D01*
G01X974540Y-130957D02*
X973884Y-131842D01*
G01Y-137157D02*
X974540Y-138043D01*
G01X973228Y-136714D02*
X973884Y-137157D01*
G01X971916Y-136272D02*
X973228Y-136714D01*
G01X969291Y-136272D02*
X971916D01*
G01X967979Y-136714D02*
X969291Y-136272D01*
G01X967322Y-137157D02*
X967979Y-136714D01*
G01X966666Y-138043D02*
X967322Y-137157D01*
G01Y-138929D02*
X966666Y-138043D01*
G01X967979Y-139372D02*
X967322Y-138929D01*
G01X969291Y-139815D02*
X967979Y-139372D01*
G01X971916Y-139815D02*
X969291D01*
G01X973228Y-139372D02*
X971916Y-139815D01*
G01X973884Y-138929D02*
X973228Y-139372D01*
G01X974540Y-138043D02*
X973884Y-138929D01*
G01X936989Y-92023D02*
X937432Y-92679D01*
G01X936989D02*
Y-92023D01*
G01X937432Y-92679D02*
X936989D01*
G01X983230Y-93495D02*
G03X986014Y-94648I2784J2784D01*
G01X983230Y-93495D02*
G03X986014Y-94648I2784J2784D01*
G01X976509Y-85143D02*
G03X977662Y-87927I3937J0D01*
G01X976509Y-85692D02*
G03X977662Y-87927I4076J688D01*
G01X986014Y-94648D02*
X1083556D01*
G01X1045525D02*
X986014D01*
G01X983230Y-93495D02*
X977662Y-87927D01*
G01X983230Y-93495D02*
X977662Y-87927D01*
G01X976509Y-85692D02*
Y17239D01*
G01Y143404D02*
Y-85143D01*
G01X983786Y-50356D02*
X984278D01*
G01X980997D02*
X981489D01*
G01X984934Y-51613D02*
X986246D01*
G01X981489Y-51948D02*
X983786D01*
G01X986246D02*
X984934D01*
G01X983786Y-52450D02*
X981489D01*
G01X984934Y-52618D02*
X986246D01*
G01Y-52953D02*
X984934D01*
G01X981489Y-54293D02*
X980997D01*
G01X984278D02*
X983786D01*
G01X987477Y-50691D02*
X987231Y-50943D01*
G01X987723Y-51026D02*
X987395Y-51529D01*
G01X987231Y-53707D02*
X987477Y-53958D01*
G01X987231Y-50943D02*
X987067Y-51278D01*
G01X987395Y-53121D02*
X987723Y-53623D01*
G01X987067Y-51278D02*
X986985Y-51529D01*
G01Y-53121D02*
X987067Y-53372D01*
G01D02*
X987231Y-53707D01*
G01X986985Y-51529D02*
X986903Y-51948D01*
G01X987395Y-51529D02*
X987313Y-52032D01*
G01D02*
Y-52618D01*
G01X986903Y-51948D02*
Y-52702D01*
G01X986246Y-52618D02*
Y-52953D01*
G01Y-51613D02*
Y-51948D01*
G01X987313Y-52618D02*
X987395Y-53121D01*
G01X986903Y-52702D02*
X986985Y-53121D01*
G01X984934Y-51948D02*
Y-51613D01*
G01Y-52953D02*
Y-52618D01*
G01X984278Y-50356D02*
Y-54293D01*
G01X983786Y-51948D02*
Y-50356D01*
G01Y-54293D02*
Y-52450D01*
G01X981489D02*
Y-54293D01*
G01Y-50356D02*
Y-51948D01*
G01X980997Y-54293D02*
Y-50356D01*
G01X1010958Y33502D02*
G03I-18701J0D01*
G01X976509Y17239D02*
G03Y49764I15748J16263D01*
G01X988320Y33502D02*
X968486D01*
G01X931331Y36127D02*
X930888Y36783D01*
G01X932217Y35470D02*
X931331Y36127D01*
G01X933103Y35470D02*
X932217D01*
G01X933988Y36127D02*
X933103Y35470D01*
G01X934431Y36783D02*
X933988Y36127D01*
G01X934874Y37439D02*
X934431Y36783D01*
G01X934874Y38095D02*
Y37439D01*
G01X941075Y40064D02*
X939303Y38751D01*
G01X941518Y40720D02*
X941075Y40064D01*
G01X941518Y42032D02*
Y40720D01*
G01X941075Y42688D02*
X941518Y42032D01*
G01X940189Y43344D02*
X941075Y42688D01*
G01X939303Y43344D02*
X940189D01*
G01X938418Y42688D02*
X939303Y43344D01*
G01X937975Y42032D02*
X938418Y42688D01*
G01X937975Y35470D02*
X941518D01*
G01X938418Y37439D02*
X937975Y35470D01*
G01X939303Y38751D02*
X938418Y37439D01*
G01X933988Y39408D02*
X934874Y38095D01*
G01X933103Y40064D02*
X933988Y39408D01*
G01Y40720D02*
X933103Y40064D01*
G01X934431Y41376D02*
X933988Y40720D01*
G01X934431Y42032D02*
Y41376D01*
G01X933988Y42688D02*
X934431Y42032D01*
G01X933103Y43344D02*
X933988Y42688D01*
G01X932217Y43344D02*
X933103D01*
G01X931331Y42688D02*
X932217Y43344D01*
G01X946390Y36127D02*
X946833Y35470D01*
G01X946390D02*
Y36127D01*
G01X946833Y35470D02*
X946390D01*
G01X959677Y36127D02*
X959235Y36783D01*
G01X960563Y35470D02*
X959677Y36127D01*
G01X961449Y35470D02*
X960563D01*
G01X962335Y36127D02*
X961449Y35470D01*
G01X962778Y36783D02*
X962335Y36127D01*
G01X963221Y38095D02*
X962778Y36783D01*
G01Y39408D02*
X963221Y38095D01*
G01X962335Y40064D02*
X962778Y39408D01*
G01X961449Y40720D02*
X962335Y40064D01*
G01X960563Y40720D02*
X961449D01*
G01X959677Y40064D02*
X960563Y40720D01*
G01X960120Y43344D02*
X959677Y40064D01*
G01X962778Y43344D02*
X960120D01*
G01X952591Y36127D02*
X952148Y36783D01*
G01X953477Y35470D02*
X952591Y36127D01*
G01X954363Y35470D02*
X953477D01*
G01X955248Y36127D02*
X954363Y35470D01*
G01X955691Y36783D02*
X955248Y36127D01*
G01X956134Y38095D02*
X955691Y36783D01*
G01Y39408D02*
X956134Y38095D01*
G01X955248Y40064D02*
X955691Y39408D01*
G01X954363Y40720D02*
X955248Y40064D01*
G01X953477Y40720D02*
X954363D01*
G01X952591Y40064D02*
X953477Y40720D01*
G01X953034Y43344D02*
X952591Y40064D01*
G01X955691Y43344D02*
X953034D01*
G01X999157Y33502D02*
G03I-6900J0D01*
G01X932217Y40064D02*
X933103D01*
G01X976509Y49764D02*
Y143404D01*
G01X982414Y94685D02*
X988320Y91585D01*
G01X990288Y94685D02*
X982414D01*
G01X985039Y116388D02*
X987664D01*
G01X983727Y115945D02*
X985039Y116388D01*
G01X983071Y115502D02*
X983727Y115945D01*
G01X982414Y114616D02*
X983071Y115502D01*
G01Y113730D02*
X982414Y114616D01*
G01X983727Y113288D02*
X983071Y113730D01*
G01X985039Y112845D02*
X983727Y113288D01*
G01X987664Y112845D02*
X985039D01*
G01Y109301D02*
X987664D01*
G01X983727Y108858D02*
X985039Y109301D01*
G01X983071Y108416D02*
X983727Y108858D01*
G01X982414Y107530D02*
X983071Y108416D01*
G01Y106644D02*
X982414Y107530D01*
G01X983727Y106201D02*
X983071Y106644D01*
G01X985039Y105758D02*
X983727Y106201D01*
G01X987664Y105758D02*
X985039D01*
G01X980446Y147341D02*
G03X976509Y143404I0J-3937D01*
G01X980446Y147341D02*
G03X976509Y143404I0J-3937D01*
G01X980446Y147341D02*
X1578815D01*
G01D02*
X980446D01*
G01X975113Y339426D02*
X975835Y339913D01*
G01Y339426D02*
X975113D01*
G01X975835Y339913D02*
Y339426D01*
G01X975113Y333092D02*
X975835Y332117D01*
G01X974391Y333579D02*
X975113Y333092D01*
G01X972948Y334066D02*
X974391Y333579D01*
G01X970060Y334066D02*
X972948D01*
G01X968617Y333579D02*
X970060Y334066D01*
G01X967895Y333092D02*
X968617Y333579D01*
G01X967173Y332117D02*
X967895Y333092D01*
G01Y331143D02*
X967173Y332117D01*
G01X968617Y330656D02*
X967895Y331143D01*
G01X970060Y330169D02*
X968617Y330656D01*
G01X972948Y330169D02*
X970060D01*
G01X974391Y330656D02*
X972948Y330169D01*
G01X975113Y331143D02*
X974391Y330656D01*
G01X975835Y332117D02*
X975113Y331143D01*
G01X981937Y374000D02*
X967373D01*
G01X978000Y379568D02*
Y363732D01*
G01X939519Y376625D02*
X938633Y375969D01*
G01X939962Y377281D02*
X939519Y376625D01*
G01X940404Y378593D02*
X939962Y377281D01*
G01X940404Y381218D02*
Y378593D01*
G01X939962Y382530D02*
X940404Y381218D01*
G01X939519Y383186D02*
X939962Y382530D01*
G01X938633Y383843D02*
X939519Y383186D01*
G01X953692Y376625D02*
X952806Y375969D01*
G01X954135Y377281D02*
X953692Y376625D01*
G01X954578Y378593D02*
X954135Y377281D01*
G01X954578Y381218D02*
Y378593D01*
G01X954135Y382530D02*
X954578Y381218D01*
G01X953692Y383186D02*
X954135Y382530D01*
G01X952806Y383843D02*
X953692Y383186D01*
G01X951920D02*
X952806Y383843D01*
G01X951477Y382530D02*
X951920Y383186D01*
G01X951034Y381218D02*
X951477Y382530D01*
G01X951034Y378593D02*
Y381218D01*
G01X951477Y377281D02*
X951034Y378593D01*
G01X951920Y376625D02*
X951477Y377281D01*
G01X952806Y375969D02*
X951920Y376625D01*
G01X960778D02*
X959893Y375969D01*
G01X961221Y377281D02*
X960778Y376625D01*
G01X961664Y378593D02*
X961221Y377281D01*
G01X961664Y381218D02*
Y378593D01*
G01X961221Y382530D02*
X961664Y381218D01*
G01X960778Y383186D02*
X961221Y382530D01*
G01X959893Y383843D02*
X960778Y383186D01*
G01X959007D02*
X959893Y383843D01*
G01X958564Y382530D02*
X959007Y383186D01*
G01X958121Y381218D02*
X958564Y382530D01*
G01X958121Y378593D02*
Y381218D01*
G01X958564Y377281D02*
X958121Y378593D01*
G01X959007Y376625D02*
X958564Y377281D01*
G01X959893Y375969D02*
X959007Y376625D01*
G01X975113Y356478D02*
X975835Y355503D01*
G01X974391Y356965D02*
X975113Y356478D01*
G01X972948Y357452D02*
X974391Y356965D01*
G01X970060Y357452D02*
X972948D01*
G01X968617Y356965D02*
X970060Y357452D01*
G01X967895Y356478D02*
X968617Y356965D01*
G01X967173Y355503D02*
X967895Y356478D01*
G01Y354529D02*
X967173Y355503D01*
G01X968617Y354042D02*
X967895Y354529D01*
G01X970060Y353554D02*
X968617Y354042D01*
G01X972948Y353554D02*
X970060D01*
G01X974391Y354042D02*
X972948Y353554D01*
G01X975113Y354529D02*
X974391Y354042D01*
G01X975835Y355503D02*
X975113Y354529D01*
G01Y348682D02*
X975835Y347708D01*
G01X974391Y349170D02*
X975113Y348682D01*
G01X972948Y349657D02*
X974391Y349170D01*
G01X970060Y349657D02*
X972948D01*
G01X968617Y349170D02*
X970060Y349657D01*
G01X967895Y348682D02*
X968617Y349170D01*
G01X967173Y347708D02*
X967895Y348682D01*
G01Y346734D02*
X967173Y347708D01*
G01X968617Y346246D02*
X967895Y346734D01*
G01X970060Y345759D02*
X968617Y346246D01*
G01X972948Y345759D02*
X970060D01*
G01X974391Y346246D02*
X972948Y345759D01*
G01X975113Y346734D02*
X974391Y346246D01*
G01X975835Y347708D02*
X975113Y346734D01*
G01X945276Y376625D02*
X945719Y375969D01*
G01X945276D02*
Y376625D01*
G01X945719Y375969D02*
X945276D01*
G01X984721Y375153D02*
G03X987505Y374000I2784J2784D01*
G01X978000Y383505D02*
G03X979153Y380721I3937J0D01*
G01X984721Y375153D02*
G03X987505Y374000I2784J2784D01*
G01X978000Y383505D02*
G03X979153Y380721I3937J0D01*
G01D02*
X984721Y375153D01*
G01X979153Y380721D02*
X984721Y375153D01*
G01X978000Y612051D02*
Y383505D01*
G01Y612051D02*
Y383505D01*
G01X987994Y417566D02*
X987351Y417457D01*
G01X981996Y417566D02*
X982638D01*
G01X978354D02*
X978997D01*
G01X983495Y415925D02*
X985209D01*
G01X978997Y415488D02*
X981996D01*
G01X985209D02*
X983495D01*
G01X981996Y414832D02*
X978997D01*
G01X983495Y414613D02*
X985209D01*
G01Y414175D02*
X983495D01*
G01X978997Y412425D02*
X978354D01*
G01X982638D02*
X981996D01*
G01X987351Y412535D02*
X987994Y412425D01*
G01X987351Y417457D02*
X986815Y417129D01*
G01X987458Y416910D02*
X987137Y416691D01*
G01Y413300D02*
X987458Y413081D01*
G01X986815Y412863D02*
X987351Y412535D01*
G01X986815Y417129D02*
X986494Y416800D01*
G01Y413191D02*
X986815Y412863D01*
G01X987137Y416691D02*
X986708Y416035D01*
G01X986494Y416800D02*
X986280Y416363D01*
G01D02*
X986173Y416035D01*
G01X986280Y413628D02*
X986494Y413191D01*
G01X986708Y413957D02*
X987137Y413300D01*
G01X986173Y416035D02*
X986066Y415488D01*
G01X986708Y416035D02*
X986601Y415378D01*
G01Y414613D02*
X986708Y413957D01*
G01X986066Y414503D02*
X986173Y413957D01*
G01D02*
X986280Y413628D01*
G01X986601Y415378D02*
Y414613D01*
G01X986066Y415488D02*
Y414503D01*
G01X985209Y414613D02*
Y414175D01*
G01Y415925D02*
Y415488D01*
G01X983495Y414175D02*
Y414613D01*
G01Y415488D02*
Y415925D01*
G01X982638Y417566D02*
Y412425D01*
G01X981996Y415488D02*
Y417566D01*
G01Y412425D02*
Y414832D01*
G01X978997D02*
Y412425D01*
G01Y417566D02*
Y415488D01*
G01X978354Y412425D02*
Y417566D01*
G01X937747Y383186D02*
X938633Y383843D01*
G01X937304Y382530D02*
X937747Y383186D01*
G01Y376625D02*
X937304Y377281D01*
G01X938633Y375969D02*
X937747Y376625D01*
G01X936861Y381218D02*
X937304Y382530D01*
G01X936861Y378593D02*
Y381218D01*
G01X937304Y377281D02*
X936861Y378593D01*
G01X1000648Y502150D02*
G03I-6900J0D01*
G01D02*
G03I-6900J0D01*
G01X1013433D02*
G03I-19685J0D01*
G01X978000Y477172D02*
G03Y527127I15748J24977D01*
G01X983061Y572271D02*
X982475Y572189D01*
G01X981386Y578587D02*
X985323D01*
G01X983229Y578094D02*
X981386D01*
G01X985323D02*
X983731D01*
G01Y575798D02*
X985323D01*
G01X981386D02*
X983229D01*
G01X985323Y575306D02*
X981386D01*
G01X983648Y572271D02*
X983061D01*
G01X983480Y571861D02*
X983648D01*
G01X982810Y571779D02*
X982559D01*
G01Y569728D02*
X982810D01*
G01X982475Y569318D02*
X982894D01*
G01X981386Y568662D02*
X984066D01*
G01X983480Y568252D02*
X981386D01*
G01X984066D02*
X983815D01*
G01X981386Y567350D02*
X983396D01*
G01Y566940D02*
X981386D01*
G01Y566037D02*
X983396D01*
G01Y565627D02*
X981386D01*
G01Y564971D02*
X984066D01*
G01X983480Y564561D02*
X981386D01*
G01X984066D02*
X983815D01*
G01X981386Y563659D02*
X983396D01*
G01Y563249D02*
X981386D01*
G01Y562346D02*
X983396D01*
G01Y561936D02*
X981386D01*
G01X983648Y571861D02*
X984150Y571779D01*
G01X984234Y572189D02*
X983648Y572271D01*
G01X984150Y571779D02*
X984401Y571697D01*
G01X983061D02*
X982810Y571779D01*
G01X982307Y569810D02*
X982559Y569728D01*
G01X984653Y572025D02*
X984234Y572189D01*
G01X982056Y569482D02*
X982475Y569318D01*
G01X983564Y566858D02*
X983396Y566940D01*
G01X983564Y563167D02*
X983396Y563249D01*
G01X982810Y572927D02*
X982559Y573091D01*
G01X984401Y571697D02*
X984653Y571533D01*
G01X982056Y569974D02*
X982307Y569810D01*
G01X984988Y571779D02*
X984653Y572025D01*
G01X981721Y569728D02*
X982056Y569482D01*
G01X983229Y571533D02*
X983061Y571697D01*
G01X983815Y568252D02*
X983983Y568088D01*
G01X983648D02*
X983480Y568252D01*
G01X983731Y567022D02*
X983983Y566776D01*
G01X983648D02*
X983564Y566858D01*
G01X983815Y564561D02*
X983983Y564397D01*
G01X983648D02*
X983480Y564561D01*
G01X983731Y563331D02*
X983983Y563085D01*
G01X983648D02*
X983564Y563167D01*
G01X985239Y571369D02*
X984988Y571779D01*
G01X984653Y571533D02*
X984820Y571287D01*
G01X983815Y571369D02*
X983480Y571861D01*
G01X983396Y571287D02*
X983229Y571533D01*
G01X981888Y570220D02*
X982056Y569974D01*
G01X984401Y569482D02*
X984653Y569564D01*
G01X982810Y569728D02*
X983061Y569810D01*
G01X982559Y571779D02*
X982307Y571697D01*
G01X983815Y562100D02*
X983396Y561936D01*
G01X983815Y565791D02*
X983396Y565627D01*
G01X983983Y572927D02*
X983396Y574075D01*
G01X983731Y566612D02*
X983648Y566776D01*
G01X983731Y562921D02*
X983648Y563085D01*
G01X983396Y574650D02*
X984234Y573091D01*
G01X981470Y570138D02*
X981721Y569728D01*
G01X982894Y569318D02*
X983312Y569482D01*
G01X982475Y572189D02*
X982056Y572025D01*
G01X983396Y562346D02*
X983564Y562428D01*
G01X983396Y563659D02*
X983564Y563741D01*
G01X983396Y566037D02*
X983564Y566119D01*
G01X983396Y567350D02*
X983564Y567432D01*
G01X984820Y571287D02*
X984904Y571041D01*
G01X983480D02*
X983396Y571287D01*
G01X983983Y568088D02*
X984066Y567842D01*
G01X983731D02*
X983648Y568088D01*
G01X983983Y566776D02*
X984066Y566530D01*
G01X983983Y564397D02*
X984066Y564151D01*
G01X981805Y570467D02*
X981888Y570220D01*
G01X983731Y564151D02*
X983648Y564397D01*
G01X983983Y563085D02*
X984066Y562839D01*
G01X984653Y570056D02*
X984401Y569892D01*
G01X982307Y571697D02*
X982056Y571533D01*
G01X984234Y573091D02*
X983983Y572927D01*
G01X984653Y569564D02*
X984988Y569810D01*
G01X982056Y572025D02*
X981721Y571779D01*
G01X985323Y570959D02*
X985239Y571369D01*
G01X983899Y570959D02*
X983815Y571369D01*
G01X981386Y570549D02*
X981470Y570138D01*
G01X983983Y562264D02*
X983815Y562100D01*
G01X983564Y562428D02*
X983648Y562510D01*
G01X983983Y563577D02*
X983731Y563331D01*
G01X983564Y563741D02*
X983648Y563823D01*
G01X983983Y565955D02*
X983815Y565791D01*
G01X983564Y566119D02*
X983648Y566201D01*
G01X983983Y567268D02*
X983731Y567022D01*
G01X983564Y567432D02*
X983648Y567514D01*
G01X983312Y569482D02*
X983564Y569728D01*
G01X983061Y569810D02*
X983229Y569974D01*
G01X984820Y570302D02*
X984653Y570056D01*
G01X983229Y569974D02*
X983396Y570220D01*
G01X982056Y571533D02*
X981888Y571287D01*
G01X984988Y569810D02*
X985239Y570220D01*
G01X983564Y569728D02*
X983815Y570138D01*
G01X981721Y571779D02*
X981470Y571369D01*
G01X982559Y573091D02*
X983396Y574650D01*
G01X983648Y562510D02*
X983731Y562675D01*
G01X983648Y563823D02*
X983731Y563987D01*
G01X983648Y566201D02*
X983731Y566365D01*
G01X983648Y567514D02*
X983731Y567678D01*
G01X983396Y574075D02*
X982810Y572927D01*
G01X984066Y562510D02*
X983983Y562264D01*
G01X984066Y563823D02*
X983983Y563577D01*
G01X984066Y566201D02*
X983983Y565955D01*
G01X984066Y567514D02*
X983983Y567268D01*
G01X984904Y570549D02*
X984820Y570302D01*
G01X985239Y570220D02*
X985323Y570631D01*
G01X983815Y570138D02*
X983899Y570549D01*
G01X985323Y570631D02*
Y570959D01*
G01Y575798D02*
Y575306D01*
G01Y578587D02*
Y578094D01*
G01X984904Y571041D02*
Y570549D01*
G01X984401Y569892D02*
Y569482D01*
G01X984066Y562839D02*
Y562510D01*
G01Y564151D02*
Y563823D01*
G01Y564971D02*
Y564561D01*
G01Y566530D02*
Y566201D01*
G01Y567842D02*
Y567514D01*
G01Y568662D02*
Y568252D01*
G01X983899Y570549D02*
Y570959D01*
G01X983731Y567678D02*
Y567842D01*
G01Y566365D02*
Y566612D01*
G01Y563987D02*
Y564151D01*
G01Y562675D02*
Y562921D01*
G01Y578094D02*
Y575798D01*
G01X983480Y570467D02*
Y571041D01*
G01X983229Y575798D02*
Y578094D01*
G01X981805Y571041D02*
Y570467D01*
G01X981386Y578094D02*
Y578587D01*
G01Y575306D02*
Y575798D01*
G01Y568252D02*
Y568662D01*
G01Y566940D02*
Y567350D01*
G01Y564561D02*
Y564971D01*
G01Y565627D02*
Y566037D01*
G01Y563249D02*
Y563659D01*
G01Y561936D02*
Y562346D01*
G01Y570959D02*
Y570549D01*
G01X983396Y570220D02*
X983480Y570467D01*
G01X981888Y571287D02*
X981805Y571041D01*
G01X981470Y571369D02*
X981386Y570959D01*
G01X978000Y615988D02*
X975201D01*
G01X940260Y625175D02*
X940703Y624518D01*
G01X939375Y625831D02*
X940260Y625175D01*
G01X938489D02*
X939375Y625831D01*
G01X938046Y624518D02*
X938489Y625175D01*
G01Y618613D02*
X938046Y619269D01*
G01X939375Y617957D02*
X938489Y618613D01*
G01X940260D02*
X939375Y617957D01*
G01X940703Y619269D02*
X940260Y618613D01*
G01X941146Y620581D02*
X940703Y619269D01*
G01Y621894D02*
X941146Y620581D01*
G01X939375Y622550D02*
X940703Y621894D01*
G01X938046D02*
X939375Y622550D01*
G01X969493Y625831D02*
X965949D01*
G01X968607Y623206D02*
X969493Y625831D01*
G01X958863Y619925D02*
X962849D01*
G01X961963Y625831D02*
X958863Y619925D01*
G01X961963Y617957D02*
Y625831D01*
G01X968164Y621238D02*
X968607Y623206D01*
G01X967721Y617957D02*
X968164Y621238D01*
G01X953105Y618613D02*
X953548Y617957D01*
G01X953105D02*
Y618613D01*
G01X953548Y617957D02*
X953105D01*
G01X981937Y615988D02*
G03X978000Y612051I0J-3937D01*
G01X981937Y615988D02*
G03X978000Y612051I0J-3937D01*
G01X1080717Y615988D02*
X981937D01*
G01X1580306D02*
X981937D01*
G01X946461Y625831D02*
Y617957D01*
G01X980987Y782204D02*
Y764881D01*
G01X1005240Y-449336D02*
Y-428277D01*
X1002081Y-432489D01*
G01Y-449336D02*
X1008398D01*
G01X1019718D02*
X1026299Y-428277D01*
X1032880Y-449336D01*
G01X1030511Y-441966D02*
X1022087D01*
G01X1065032Y-164057D02*
X1067198D01*
G01X1061883D02*
X1064048D01*
G01X1058733D02*
X1060899D01*
G01X1055584D02*
X1057749D01*
G01X1052434D02*
X1054599D01*
G01X1051430Y-167994D02*
X1152336D01*
G01X1051430D02*
X1152336D01*
G01X1067198Y-164057D02*
Y-153033D01*
G01X1065032D02*
Y-164057D01*
G01X1064048D02*
Y-153033D01*
G01X1061883D02*
Y-164057D01*
G01X1060899D02*
Y-153033D01*
G01X1058733D02*
Y-164057D01*
G01X1057749D02*
Y-153033D01*
G01X1055584D02*
Y-164057D01*
G01X1054599D02*
Y-153033D01*
G01X1052434D02*
Y-164057D01*
G01X1049462Y-166026D02*
Y-99296D01*
G01Y-98585D02*
Y-166026D01*
G01D02*
X1051430Y-167994D01*
G01D02*
X1049462Y-166026D01*
G01X1053168Y-152135D02*
X1053244Y-152110D01*
G01X1053829Y-151694D02*
X1053931Y-151642D01*
G01X1053956Y-151772D02*
X1053880Y-151824D01*
G01X1053372Y-152187D02*
X1053270Y-152265D01*
G01X1054516Y-152135D02*
X1053880Y-152707D01*
G01X1053677D02*
X1054389Y-152058D01*
G01X1053727Y-151798D02*
X1053829Y-151694D01*
G01X1053244Y-152110D02*
X1053295Y-152058D01*
G01X1053931Y-151642D02*
X1054109Y-151616D01*
G01X1054083Y-151746D02*
X1053956Y-151772D01*
G01X1053270Y-152265D02*
X1053143Y-152291D01*
G01X1053448Y-152084D02*
X1053372Y-152187D01*
G01X1054567Y-152058D02*
X1054516Y-152135D01*
G01X1053880Y-151824D02*
X1053829Y-151902D01*
G01X1054109Y-151616D02*
X1054211D01*
G01X1052532D02*
X1053143D01*
G01X1054185Y-151746D02*
X1054083D01*
G01X1053168D02*
X1052685D01*
G01X1053829Y-151902D02*
X1053702D01*
G01X1052685Y-152135D02*
X1053168D01*
G01X1053143Y-152291D02*
X1052685D01*
G01X1053880Y-152707D02*
X1054592D01*
G01X1052685Y-152837D02*
X1052532D01*
G01X1054592D02*
X1053677D01*
G01X1054599Y-153033D02*
X1052434D01*
G01X1057749D02*
X1055584D01*
G01X1060899D02*
X1058733D01*
G01X1064048D02*
X1061883D01*
G01X1067198D02*
X1065032D01*
G01X1054389Y-152058D02*
X1054439Y-151954D01*
G01X1054211Y-151616D02*
X1054363Y-151642D01*
G01X1053473Y-152006D02*
X1053448Y-152084D01*
G01X1053295Y-152058D02*
X1053321Y-151980D01*
G01X1054312Y-151772D02*
X1054185Y-151746D01*
G01X1053143Y-151616D02*
X1053270Y-151642D01*
G01X1054592Y-151954D02*
X1054567Y-152058D01*
G01X1053702Y-151902D02*
X1053727Y-151798D01*
G01X1053244Y-151772D02*
X1053168Y-151746D01*
G01X1054592Y-152707D02*
Y-152837D01*
G01Y-151902D02*
Y-151954D01*
G01X1054389Y-151824D02*
X1054312Y-151772D01*
G01X1054363Y-151642D02*
X1054465Y-151694D01*
G01X1054439Y-151954D02*
Y-151902D01*
G01X1053677Y-152837D02*
Y-152707D01*
G01X1053473Y-151902D02*
Y-152006D01*
G01X1053321Y-151980D02*
Y-151902D01*
G01X1052685Y-151746D02*
Y-152135D01*
G01Y-152291D02*
Y-152837D01*
G01X1052532D02*
Y-151616D01*
G01X1054567Y-151798D02*
X1054592Y-151902D01*
G01X1053448Y-151824D02*
X1053473Y-151902D01*
G01X1053321D02*
X1053295Y-151824D01*
G01X1054439Y-151902D02*
X1054389Y-151824D01*
G01X1053372Y-151720D02*
X1053448Y-151824D01*
G01X1054465Y-151694D02*
X1054567Y-151798D01*
G01X1053295Y-151824D02*
X1053244Y-151772D01*
G01X1053270Y-151642D02*
X1053372Y-151720D01*
G01X1049462Y-98585D02*
G03X1045525Y-94648I-3937J0D01*
G01X1049462Y-98585D02*
G03X1045525Y-94648I-3937J0D01*
G01X998517D02*
Y-8191D01*
G01X998508Y11744D02*
Y-94648D01*
G01X1034563Y-63602D02*
X1035413Y-63385D01*
G01X1035625Y-64470D02*
X1034563Y-64687D01*
G01X1036475Y-62084D02*
X1037750D01*
G01X1033289Y-63602D02*
X1034563D01*
G01X1052833Y-64687D02*
X1054107D01*
G01X1045610D02*
X1046884D01*
G01X1027341D02*
X1028403D01*
G01X1023942D02*
X1025004D01*
G01X1020543D02*
X1021605D01*
G01X1017781D02*
X1018843D01*
G01X1014382D02*
X1015444D01*
G01X1010983D02*
X1012045D01*
G01X1034563D02*
X1033289D01*
G01X1042423Y-59480D02*
X1039449Y-60999D01*
G01X1039874Y-61650D02*
X1043910Y-59480D01*
G01X1036688Y-63819D02*
X1035625Y-64470D01*
G01X1033289Y-64687D02*
X1032226Y-64470D01*
G01X1035413Y-63385D02*
X1036050Y-62951D01*
G01X1032439Y-63385D02*
X1033289Y-63602D01*
G01X1032226Y-64470D02*
X1031164Y-63819D01*
G01X1037325Y-62951D02*
X1036688Y-63819D01*
G01X1031802Y-62951D02*
X1032439Y-63385D01*
G01X1031802Y-59914D02*
X1031377Y-60565D01*
G01X1037750Y-62084D02*
X1037325Y-62951D01*
G01X1036050D02*
X1036475Y-62084D01*
G01X1030102Y-60999D02*
X1030527Y-59914D01*
G01X1031377Y-60565D02*
X1031164Y-61216D01*
G01X1039449Y-60999D02*
X1039874Y-61650D01*
G01X1031377Y-62300D02*
X1031802Y-62951D01*
G01X1031164Y-63819D02*
X1030527Y-62951D01*
G01X1054107Y-64687D02*
Y-54490D01*
G01X1052833Y-59914D02*
Y-64687D01*
G01X1046884D02*
Y-59914D01*
G01X1045610Y-54490D02*
Y-64687D01*
G01X1031164Y-61650D02*
X1031377Y-62300D01*
G01X1030527Y-62951D02*
X1030102Y-61867D01*
G01X1031164Y-61216D02*
Y-61650D01*
G01X1030102Y-61867D02*
Y-60999D01*
G01X1028403Y-64687D02*
Y-57744D01*
G01X1027341Y-59263D02*
Y-64687D01*
G01X1025004D02*
Y-59480D01*
G01X1023942D02*
Y-64687D01*
G01X1021605D02*
Y-59480D01*
G01X1020543D02*
Y-64687D01*
G01X1018843D02*
Y-57744D01*
G01X1017781Y-59263D02*
Y-64687D01*
G01X1015444D02*
Y-59480D01*
G01X1014382D02*
Y-64687D01*
G01X1012045D02*
Y-59480D01*
G01X1010983D02*
Y-64687D01*
G01X988379Y-50356D02*
X987887Y-50440D01*
G01X988379Y-54293D02*
X988871Y-54210D01*
G01X988379Y-50775D02*
X987969Y-50859D01*
G01X988379Y-53874D02*
X988789Y-53791D01*
G01X988871Y-50440D02*
X988379Y-50356D01*
G01X988789Y-50859D02*
X988379Y-50775D01*
G01X987969Y-53791D02*
X988379Y-53874D01*
G01X987887Y-54210D02*
X988379Y-54293D01*
G01X988871Y-54210D02*
X989281Y-53958D01*
G01X987887Y-50440D02*
X987477Y-50691D01*
G01X988789Y-53791D02*
X989035Y-53623D01*
G01X987969Y-50859D02*
X987723Y-51026D01*
G01X989281Y-53958D02*
X989527Y-53707D01*
G01X989035Y-51026D02*
X988789Y-50859D01*
G01X987723Y-53623D02*
X987969Y-53791D01*
G01X989281Y-50691D02*
X988871Y-50440D01*
G01X987477Y-53958D02*
X987887Y-54210D01*
G01X989035Y-53623D02*
X989363Y-53121D01*
G01X989527Y-50943D02*
X989281Y-50691D01*
G01X989527Y-53707D02*
X989691Y-53372D01*
G01X989363Y-51529D02*
X989035Y-51026D01*
G01X989691Y-53372D02*
X989773Y-53121D01*
G01X989445Y-52032D02*
X989363Y-51529D01*
G01X989855Y-51948D02*
X989773Y-51529D01*
G01D02*
X989691Y-51278D01*
G01D02*
X989527Y-50943D01*
G01X989773Y-53121D02*
X989855Y-52702D01*
G01X989363Y-53121D02*
X989445Y-52618D01*
G01X989855Y-52702D02*
Y-51948D01*
G01X989445Y-52618D02*
Y-52032D01*
G01X1048714Y2257D02*
X1047483Y2006D01*
G01X1056341D02*
X1057818D01*
G01X1053143D02*
X1054373D01*
G01X1039117D02*
X1040347D01*
G01X1035180D02*
X1036410D01*
G01X1031243D02*
X1032473D01*
G01X1028044D02*
X1029275D01*
G01X1024107D02*
X1025338D01*
G01X1020170D02*
X1021401D01*
G01X1047483D02*
X1046007D01*
G01X1033289Y-59263D02*
X1032439Y-59480D01*
G01X1065446Y-15888D02*
X998517Y-15868D01*
G01D02*
X1083989D01*
G01X998508Y-15888D02*
X1083987D01*
G01X1032226Y-58395D02*
X1033289Y-58178D01*
G01X1046007Y2006D02*
X1044777Y2257D01*
G01X1025429Y-57744D02*
X1024791Y-57961D01*
G01X1022030Y-57744D02*
X1021392Y-57961D01*
G01X1015869Y-57744D02*
X1015232Y-57961D01*
G01X1012470Y-57744D02*
X1011833Y-57961D01*
G01X1030527Y-54490D02*
X1037750D01*
G01X1046884D02*
X1045610D01*
G01X1054107D02*
X1052833D01*
G01X1036688Y-55575D02*
X1030527D01*
G01X1013320Y-57744D02*
X1012470D01*
G01X1016719D02*
X1015869D01*
G01X1018843D02*
X1017781D01*
G01X1022879D02*
X1022030D01*
G01X1026278D02*
X1025429D01*
G01X1028403D02*
X1027341D01*
G01X1033289Y-58178D02*
X1034563D01*
G01X1025853Y-58612D02*
X1026278D01*
G01X1022455D02*
X1023092D01*
G01X1016294D02*
X1016719D01*
G01X1012895D02*
X1013532D01*
G01X1052833D02*
X1046884D01*
G01X1034563Y-59263D02*
X1033289D01*
G01X1046884Y-59914D02*
X1052833D01*
G01X1037750Y-60131D02*
X1036263D01*
G01X1025429Y-58829D02*
X1025853Y-58612D01*
G01X1022030Y-58829D02*
X1022455Y-58612D01*
G01X1015869Y-58829D02*
X1016294Y-58612D01*
G01X1012470Y-58829D02*
X1012895Y-58612D01*
G01X1035413Y-59480D02*
X1034563Y-59263D01*
G01Y-58178D02*
X1035625Y-58395D01*
G01X1031164Y-59046D02*
X1032226Y-58395D01*
G01X1032439Y-59480D02*
X1031802Y-59914D01*
G01X1026916Y-57961D02*
X1026278Y-57744D01*
G01Y-58612D02*
X1026916Y-58829D01*
G01X1023517Y-57961D02*
X1022879Y-57744D01*
G01X1017356Y-57961D02*
X1016719Y-57744D01*
G01Y-58612D02*
X1017356Y-58829D01*
G01X1013957Y-57961D02*
X1013320Y-57744D01*
G01X1043910Y-59480D02*
X1039874Y-57311D01*
G01X1039449Y-57961D02*
X1042423Y-59480D01*
G01X1025216Y-59046D02*
X1025429Y-58829D01*
G01X1024791Y-57961D02*
X1024154Y-58612D01*
G01X1021817Y-59046D02*
X1022030Y-58829D01*
G01X1021392Y-57961D02*
X1020967Y-58395D01*
G01X1015657Y-59046D02*
X1015869Y-58829D01*
G01X1015232Y-57961D02*
X1014594Y-58612D01*
G01X1035625Y-58395D02*
X1036688Y-59046D01*
G01X1023092Y-58612D02*
X1023517Y-58829D01*
G01X1013532Y-58612D02*
X1013957Y-58829D01*
G01X1012258Y-59046D02*
X1012470Y-58829D01*
G01X1011833Y-57961D02*
X1011408Y-58395D01*
G01X1030527Y-59914D02*
X1031164Y-59046D01*
G01X1039874Y-57311D02*
X1039449Y-57961D01*
G01X1036263Y-60131D02*
X1035413Y-59480D01*
G01X1027341Y-58395D02*
X1026916Y-57961D01*
G01Y-58829D02*
X1027341Y-59263D01*
G01X1024154Y-58612D02*
X1023517Y-57961D01*
G01Y-58829D02*
X1023729Y-59046D01*
G01X1017781Y-58395D02*
X1017356Y-57961D01*
G01Y-58829D02*
X1017781Y-59263D01*
G01X1014594Y-58612D02*
X1013957Y-57961D01*
G01Y-58829D02*
X1014170Y-59046D01*
G01X1025004Y-59480D02*
X1025216Y-59046D01*
G01X1021605Y-59480D02*
X1021817Y-59046D01*
G01X1015444Y-59480D02*
X1015657Y-59046D01*
G01X1012045Y-59480D02*
X1012258Y-59046D01*
G01X1020967Y-58395D02*
X1020543Y-59480D01*
G01X1057818Y2006D02*
Y11807D01*
G01X1056341Y13817D02*
Y2006D01*
G01X998508Y-8211D02*
X1027167Y42911D01*
G01X998517Y-8191D02*
X1027178Y42951D01*
G01X1011408Y-58395D02*
X1010983Y-59480D01*
G01X1054373Y2006D02*
Y3262D01*
G01X1053143D02*
Y2006D01*
G01X1052833Y-54490D02*
Y-58612D01*
G01X1046884D02*
Y-54490D01*
G01X1040347Y2006D02*
Y10047D01*
G01X1039117Y8288D02*
Y2006D01*
G01X1037750Y-54490D02*
Y-60131D01*
G01X1036688Y-59046D02*
Y-55575D01*
G01X1036410Y2006D02*
Y8037D01*
G01X1035180D02*
Y2006D01*
G01X1032473D02*
Y8037D01*
G01X1023729Y-59046D02*
X1023942Y-59480D01*
G01X1014170Y-59046D02*
X1014382Y-59480D01*
G01X1031243Y8037D02*
Y2006D01*
G01X1030527Y-55575D02*
Y-54490D01*
G01X1029275Y2006D02*
Y10047D01*
G01X1028044Y8288D02*
Y2006D01*
G01X1027341Y-57744D02*
Y-58395D01*
G01X1025338Y2006D02*
Y8037D01*
G01X1024107D02*
Y2006D01*
G01X1021401D02*
Y8037D01*
G01X1020170D02*
Y2006D01*
G01X1017781Y-57744D02*
Y-58395D01*
G01X1046007Y8288D02*
X1045023Y8037D01*
G01X1044777Y9294D02*
X1046007Y9545D01*
G01X1047483Y3262D02*
X1048467Y3514D01*
G01X1042808Y13817D02*
X1051174D01*
G01X1057818D02*
X1056341D01*
G01X1049944Y12560D02*
X1042808D01*
G01X1022877Y10047D02*
X1021893D01*
G01X1026814D02*
X1025830D01*
G01X1029275D02*
X1028044D01*
G01X1033950D02*
X1032966D01*
G01X1037887D02*
X1036903D01*
G01X1040347D02*
X1039117D01*
G01X1046007Y9545D02*
X1047483D01*
G01X1037395Y9042D02*
X1037887D01*
G01X1033458D02*
X1034196D01*
G01X1026322D02*
X1026814D01*
G01X1022385D02*
X1023123D01*
G01X1047483Y8288D02*
X1046007D01*
G01X1051174Y7283D02*
X1049452D01*
G01X1049698Y5021D02*
X1051174D01*
G01X1046007Y3262D02*
X1047483D01*
G01X1054373D02*
X1053143D01*
G01X1048467Y8037D02*
X1047483Y8288D01*
G01Y9545D02*
X1048714Y9294D01*
G01X1038625Y9796D02*
X1037887Y10047D01*
G01Y9042D02*
X1038625Y8791D01*
G01X1034688Y9796D02*
X1033950Y10047D01*
G01X1027552Y9796D02*
X1026814Y10047D01*
G01Y9042D02*
X1027552Y8791D01*
G01X1023615Y9796D02*
X1022877Y10047D01*
G01X1045023Y3514D02*
X1046007Y3262D01*
G01X1066430Y8037D02*
X1061755Y10550D01*
G01X1061263Y9796D02*
X1064708Y8037D01*
G01X1048714Y9294D02*
X1049944Y8540D01*
G01X1034196Y9042D02*
X1034688Y8791D01*
G01X1023123Y9042D02*
X1023615Y8791D01*
G01X1036903Y10047D02*
X1036164Y9796D01*
G01X1032966Y10047D02*
X1032227Y9796D01*
G01X1025830Y10047D02*
X1025091Y9796D01*
G01X1021893Y10047D02*
X1021154Y9796D01*
G01X1049452Y7283D02*
X1048467Y8037D01*
G01X1044284Y4016D02*
X1045023Y3514D01*
G01X1044777Y2257D02*
X1043546Y3011D01*
G01X1064708Y8037D02*
X1061263Y6278D01*
G01X1036903Y8791D02*
X1037395Y9042D01*
G01X1032966Y8791D02*
X1033458Y9042D01*
G01X1025830Y8791D02*
X1026322Y9042D01*
G01X1021893Y8791D02*
X1022385Y9042D01*
G01X1061755Y5524D02*
X1066430Y8037D01*
G01X1049944Y3011D02*
X1048714Y2257D01*
G01X1059294Y12058D02*
X1057818Y13817D01*
G01Y11807D02*
X1059294Y10047D01*
G01X1043546Y8540D02*
X1044777Y9294D01*
G01X1048467Y3514D02*
X1049206Y4016D01*
G01X1045023Y8037D02*
X1044284Y7534D01*
G01X1061263Y6278D02*
X1061755Y5524D01*
G01X1039117Y9294D02*
X1038625Y9796D01*
G01Y8791D02*
X1039117Y8288D01*
G01X1035426Y9042D02*
X1034688Y9796D01*
G01Y8791D02*
X1034934Y8540D01*
G01X1028044Y9294D02*
X1027552Y9796D01*
G01Y8791D02*
X1028044Y8288D01*
G01X1024353Y9042D02*
X1023615Y9796D01*
G01Y8791D02*
X1023861Y8540D01*
G01X1043792Y4770D02*
X1044284Y4016D01*
G01X1043546Y3011D02*
X1042808Y4016D01*
G01X1036656Y8540D02*
X1036903Y8791D01*
G01X1036164Y9796D02*
X1035426Y9042D01*
G01X1032719Y8540D02*
X1032966Y8791D01*
G01X1032227Y9796D02*
X1031735Y9294D01*
G01X1025584Y8540D02*
X1025830Y8791D01*
G01X1025091Y9796D02*
X1024353Y9042D01*
G01X1021647Y8540D02*
X1021893Y8791D01*
G01X1021154Y9796D02*
X1020662Y9294D01*
G01X1050682Y4016D02*
X1049944Y3011D01*
G01X1042808Y7534D02*
X1043546Y8540D01*
G01X1061755Y10550D02*
X1061263Y9796D01*
G01X1043546Y5524D02*
X1043792Y4770D01*
G01X1042808Y4016D02*
X1042316Y5273D01*
G01X1034934Y8540D02*
X1035180Y8037D01*
G01X1023861Y8540D02*
X1024107Y8037D01*
G01X1044284Y7534D02*
X1043792Y6781D01*
G01X1051174Y5021D02*
X1050682Y4016D01*
G01X1049206D02*
X1049698Y5021D01*
G01X1059294Y10047D02*
Y12058D01*
G01X1036410Y8037D02*
X1036656Y8540D01*
G01X1032473Y8037D02*
X1032719Y8540D01*
G01X1025338Y8037D02*
X1025584Y8540D01*
G01X1021401Y8037D02*
X1021647Y8540D01*
G01X1042316Y6278D02*
X1042808Y7534D01*
G01X1031735Y9294D02*
X1031243Y8037D01*
G01X1020662Y9294D02*
X1020170Y8037D01*
G01X1043792Y6781D02*
X1043546Y6027D01*
G01X1051174Y13817D02*
Y7283D01*
G01X1049944Y8540D02*
Y12560D01*
G01X1043546Y6027D02*
Y5524D01*
G01X1042808Y12560D02*
Y13817D01*
G01X1042316Y5273D02*
Y6278D01*
G01X1039117Y10047D02*
Y9294D01*
G01X1028044Y10047D02*
Y9294D01*
G01X992257Y37439D02*
Y85876D01*
G01X988320Y91585D02*
Y95571D01*
G01X1083989Y42951D02*
X1027178D01*
G01X1246627Y42911D02*
X1027167D01*
G01X989632Y115502D02*
X990288Y114616D01*
G01X988976Y115945D02*
X989632Y115502D01*
G01X987664Y116388D02*
X988976Y115945D01*
G01Y113288D02*
X987664Y112845D01*
G01X989632Y113730D02*
X988976Y113288D01*
G01X990288Y114616D02*
X989632Y113730D01*
G01Y108416D02*
X990288Y107530D01*
G01X988976Y108858D02*
X989632Y108416D01*
G01X987664Y109301D02*
X988976Y108858D01*
G01Y106201D02*
X987664Y105758D01*
G01X989632Y106644D02*
X988976Y106201D01*
G01X990288Y107530D02*
X989632Y106644D01*
G01Y100000D02*
X990288Y100443D01*
G01Y100000D02*
X989632D01*
G01X990288Y100443D02*
Y100000D01*
G01X1040848Y259133D02*
X1040126Y260107D01*
G01X1048066Y259133D02*
X1047344Y258646D01*
G01X1048787Y260107D02*
X1048066Y259133D01*
G01X1043735Y237696D02*
X1044457Y238670D01*
G01X1043735Y236722D02*
Y237696D01*
G01X1044457Y235747D02*
X1043735Y236722D01*
G01X1048787Y237696D02*
Y236722D01*
G01X1048066Y238670D02*
X1048787Y237696D01*
G01X1046622Y239645D02*
X1048066Y238670D01*
G01Y251338D02*
X1047344Y250850D01*
G01X1048787Y252312D02*
X1048066Y251338D01*
G01X1048787Y253286D02*
Y252312D01*
G01X1048066Y254261D02*
X1048787Y253286D01*
G01X1047344Y254748D02*
X1048066Y254261D01*
G01X1045900Y255235D02*
X1047344Y254748D01*
G01X1044457D02*
X1045900Y255235D01*
G01X1043735Y254261D02*
X1044457Y254748D01*
G01X1043013Y253286D02*
X1043735Y254261D01*
G01X1043013Y252312D02*
Y253286D01*
G01X1043735Y251338D02*
X1043013Y252312D01*
G01X1040126Y251825D02*
X1043735Y251338D01*
G01X1040126Y254748D02*
Y251825D01*
G01X1048066Y244517D02*
X1048787Y245004D01*
G01Y244517D02*
X1048066D01*
G01X1048787Y245004D02*
Y244517D01*
G01X1043013Y238670D02*
X1043735Y237696D01*
G01X1042291Y239158D02*
X1043013Y238670D01*
G01X1041570Y239158D02*
X1042291D01*
G01X1040848Y238670D02*
X1041570Y239158D01*
G01X1040126Y237696D02*
X1040848Y238670D01*
G01X1040126Y236722D02*
Y237696D01*
G01X1040848Y235747D02*
X1040126Y236722D01*
G01X1041570Y235260D02*
X1040848Y235747D01*
G01X1042291Y235260D02*
X1041570D01*
G01X1043013Y235747D02*
X1042291Y235260D01*
G01X1043735Y236722D02*
X1043013Y235747D01*
G01X1045900Y239645D02*
X1046622D01*
G01X1044457Y238670D02*
X1045900Y239645D01*
G01Y234773D02*
X1044457Y235747D01*
G01X1046622Y234773D02*
X1045900D01*
G01X1048066Y235747D02*
X1046622Y234773D01*
G01X1048787Y236722D02*
X1048066Y235747D01*
G01X1040126Y229413D02*
X1048787D01*
G01X1052921Y300654D02*
X1153827D01*
G01X1052921D02*
X1153827D01*
G01X1050953Y299785D02*
Y268823D01*
G01X1044457Y262056D02*
X1045900Y263031D01*
G01X1043735Y261082D02*
X1044457Y262056D01*
G01X1043013D02*
X1043735Y261082D01*
G01X1042291Y262543D02*
X1043013Y262056D01*
G01X1041570Y262543D02*
X1042291D01*
G01X1040848Y262056D02*
X1041570Y262543D01*
G01X1040126Y261082D02*
X1040848Y262056D01*
G01X1040126Y260107D02*
Y261082D01*
G01X1048787D02*
Y260107D01*
G01X1048066Y262056D02*
X1048787Y261082D01*
G01X1046622Y263031D02*
X1048066Y262056D01*
G01X1066524Y304591D02*
X1068689D01*
G01X1063374D02*
X1065539D01*
G01X1060224D02*
X1062390D01*
G01X1057075D02*
X1059240D01*
G01X1053925D02*
X1056091D01*
G01X1045900Y263031D02*
X1046622D01*
G01X1066524Y315614D02*
Y304591D01*
G01X1065539D02*
Y315614D01*
G01X1063374D02*
Y304591D01*
G01X1062390D02*
Y315614D01*
G01X1060224D02*
Y304591D01*
G01X1059240D02*
Y315614D01*
G01X1057075D02*
Y304591D01*
G01X1056091D02*
Y315614D01*
G01X1053925D02*
Y304591D01*
G01X1050953Y302622D02*
Y370063D01*
G01D02*
Y302622D01*
G01X1043735Y260107D02*
Y261082D01*
G01X1052921Y300654D02*
X1050953Y302622D01*
G01D02*
X1052921Y300654D01*
G01X1054880Y316625D02*
X1054968Y316655D01*
G01X1055116Y316565D02*
X1054998Y316474D01*
G01D02*
X1054850Y316444D01*
G01X1054968Y316655D02*
X1055028Y316716D01*
G01X1055648Y316987D02*
X1055470Y316776D01*
G01Y317017D02*
X1055648Y317228D01*
G01X1055205Y316686D02*
X1055116Y316565D01*
G01X1055648Y317228D02*
X1055825D01*
G01X1054142D02*
X1054850D01*
G01X1054880Y317078D02*
X1054319D01*
G01Y316625D02*
X1054880D01*
G01X1054850Y316444D02*
X1054319D01*
G01Y315811D02*
X1054142D01*
G01X1055825D02*
X1055648D01*
G01X1056091Y315614D02*
X1053925D01*
G01X1059240D02*
X1057075D01*
G01X1062390D02*
X1060224D01*
G01X1065539D02*
X1063374D01*
G01X1068689D02*
X1066524D01*
G01X1054850Y317228D02*
X1054998Y317198D01*
G01X1054968Y317047D02*
X1054880Y317078D01*
G01X1055234Y316776D02*
X1055205Y316686D01*
G01X1055028Y316716D02*
X1055057Y316806D01*
G01X1054998Y317198D02*
X1055116Y317108D01*
G01X1055825Y317228D02*
Y315811D01*
G01X1055648D02*
Y316987D01*
G01X1055470Y316776D02*
Y317017D01*
G01X1055234Y316897D02*
Y316776D01*
G01X1055057Y316806D02*
Y316897D01*
G01X1054319Y316444D02*
Y315811D01*
G01Y317078D02*
Y316625D01*
G01X1054142Y315811D02*
Y317228D01*
G01X1055205Y316987D02*
X1055234Y316897D01*
G01X1055057D02*
X1055028Y316987D01*
G01X1055116Y317108D02*
X1055205Y316987D01*
G01X1055028D02*
X1054968Y317047D01*
G01X987505Y374000D02*
X999999D01*
G01X1047016D02*
X987505D01*
G01X1050953Y370063D02*
G03X1047016Y374000I-3937J0D01*
G01X1050953Y370063D02*
G03X1047016Y374000I-3937J0D01*
G01X1000008D02*
X1047016D01*
G01X1000008Y461835D02*
Y374000D01*
G01X999999Y473291D02*
Y374000D01*
G01X987994Y412425D02*
X988636Y412535D01*
G01X987994Y417019D02*
X987458Y416910D01*
G01X987994Y412972D02*
X988529Y413081D01*
G01X996669Y415925D02*
X997097D01*
G01X995598D02*
X996133D01*
G01X993563D02*
X993991D01*
G01X991849D02*
X992278D01*
G01X990778D02*
X991314D01*
G01X992063Y415488D02*
X991849D01*
G01X993777D02*
X993456D01*
G01X996883D02*
X996669D01*
G01X991314Y412425D02*
X990778D01*
G01X993027D02*
X992492D01*
G01X994741D02*
X994205D01*
G01X996133D02*
X995598D01*
G01X997847D02*
X997311D01*
G01X996669Y415488D02*
X996347Y415378D01*
G01Y415816D02*
X996669Y415925D01*
G01X993241Y415816D02*
X993563Y415925D01*
G01X991849Y415488D02*
X991528Y415378D01*
G01Y415816D02*
X991849Y415925D01*
G01X988636Y417457D02*
X987994Y417566D01*
G01X988529Y416910D02*
X987994Y417019D01*
G01X987458Y413081D02*
X987994Y412972D01*
G01X993456Y415488D02*
X993241Y415378D01*
G01X997097Y415925D02*
X997418Y415816D01*
G01X993991Y415925D02*
X994313Y415816D01*
G01X992278Y415925D02*
X992599Y415816D01*
G01X988636Y412535D02*
X989172Y412863D01*
G01X988529Y413081D02*
X988850Y413300D01*
G01X997097Y415378D02*
X996883Y415488D01*
G01X993991Y415378D02*
X993777Y415488D01*
G01X992278Y415378D02*
X992063Y415488D01*
G01X997740D02*
X998061Y415816D01*
G01X996347Y415378D02*
X996133Y415160D01*
G01Y415597D02*
X996347Y415816D01*
G01X988850Y416691D02*
X988529Y416910D01*
G01X989172Y417129D02*
X988636Y417457D01*
G01X993241Y415378D02*
X993134Y415269D01*
G01X992920Y415488D02*
X993241Y415816D01*
G01X989172Y412863D02*
X989493Y413191D01*
G01X991528Y415378D02*
X991314Y415160D01*
G01Y415597D02*
X991528Y415816D01*
G01X988850Y413300D02*
X989279Y413957D01*
G01X997418Y415816D02*
X997740Y415488D01*
G01X997204Y415269D02*
X997097Y415378D01*
G01X994313Y415816D02*
X994527Y415597D01*
G01X994098Y415269D02*
X993991Y415378D01*
G01X992599Y415816D02*
X992920Y415488D01*
G01X992385Y415269D02*
X992278Y415378D01*
G01X989493Y416800D02*
X989172Y417129D01*
G01X993134Y415269D02*
X993027Y415050D01*
G01X989493Y413191D02*
X989707Y413628D01*
G01X989279Y416035D02*
X988850Y416691D01*
G01X989707Y413628D02*
X989814Y413957D01*
G01Y416035D02*
X989707Y416363D01*
G01X994527Y415597D02*
X994741Y415050D01*
G01X997311D02*
X997204Y415269D01*
G01X994205Y415050D02*
X994098Y415269D01*
G01X992492Y415050D02*
X992385Y415269D01*
G01X989707Y416363D02*
X989493Y416800D01*
G01X989814Y413957D02*
X989921Y414503D01*
G01X989279Y413957D02*
X989386Y414613D01*
G01X997311Y412425D02*
Y415050D01*
G01X996133Y415160D02*
Y412425D01*
G01Y415925D02*
Y415597D01*
G01X995598Y412425D02*
Y415925D01*
G01X994741Y415050D02*
Y412425D01*
G01X994205D02*
Y415050D01*
G01X993027D02*
Y412425D01*
G01X992492D02*
Y415050D01*
G01X991314Y415160D02*
Y412425D01*
G01Y415925D02*
Y415597D01*
G01X990778Y412425D02*
Y415925D01*
G01X989386Y415378D02*
X989279Y416035D01*
G01X989921Y415488D02*
X989814Y416035D01*
G01X989921Y414503D02*
Y415488D01*
G01X989386Y414613D02*
Y415378D01*
G01X1048219Y419451D02*
X1057382D01*
G01X1022365Y417780D02*
X1020402D01*
G01X1033492D02*
X1031529D01*
G01X1057382D02*
X1045601D01*
G01X1061637D02*
X1060000D01*
G01X1066873D02*
X1065237D01*
G01X998382Y415925D02*
X998811D01*
G01X998597Y415488D02*
X998275D01*
G01X999560Y412425D02*
X999025D01*
G01X998061Y415816D02*
X998382Y415925D01*
G01X998275Y415488D02*
X998061Y415378D01*
G01X998811Y415925D02*
X999132Y415816D01*
G01X1056401Y426804D02*
X1048219Y419451D01*
G01X1045601D02*
X1054764Y427806D01*
G01X998811Y415378D02*
X998597Y415488D01*
G01X998061Y415378D02*
X997954Y415269D01*
G01X1066873Y425801D02*
Y417780D01*
G01X1065237D02*
Y425801D01*
G01X999132Y415816D02*
X999346Y415597D01*
G01X998918Y415269D02*
X998811Y415378D01*
G01X997954Y415269D02*
X997847Y415050D01*
G01X1061637Y426135D02*
Y417780D01*
G01X1060000D02*
Y428475D01*
G01X1057382Y419451D02*
Y417780D01*
G01X1045601D02*
Y419451D01*
G01X1033492Y433488D02*
Y417780D01*
G01X1031529D02*
Y425133D01*
G01X1022365D02*
Y417780D01*
G01X1020402D02*
Y433488D01*
G01X999346Y415597D02*
X999560Y415050D01*
G01X999025D02*
X998918Y415269D01*
G01X999560Y415050D02*
Y412425D01*
G01X999025D02*
Y415050D01*
G01X997847D02*
Y412425D01*
G01X1100835Y343921D02*
X1050953D01*
G01X1048874Y433154D02*
X1051164Y433488D01*
G01X1050837Y431817D02*
X1049201Y431483D01*
G01X1514662Y461835D02*
X999999D01*
G01X1051164Y433488D02*
X1052473D01*
G01X1031529D02*
X1033492D01*
G01X1020402D02*
X1022365D01*
G01X1052146Y431817D02*
X1050837D01*
G01X1047564Y429812D02*
X1045928D01*
G01X1063273Y428475D02*
X1064582D01*
G01X1060000D02*
X1061637D01*
G01X1022365Y427138D02*
X1031529D01*
G01X1063928D02*
X1063273D01*
G01X1031529Y425133D02*
X1022365D01*
G01X1052473Y433488D02*
X1054437Y433154D01*
G01X1063273Y427138D02*
X1062291Y426804D01*
G01Y428141D02*
X1063273Y428475D01*
G01X1053782Y431483D02*
X1052146Y431817D01*
G01X1042983Y428141D02*
X1038401Y425801D01*
G01X1047564Y432486D02*
X1048874Y433154D01*
G01X1064582Y428475D02*
X1065564Y428141D01*
G01X1036110Y425801D02*
X1042328Y429143D01*
G01X1054437Y433154D02*
X1055746Y432486D01*
G01X1064582Y426804D02*
X1063928Y427138D01*
G01X1049201Y431483D02*
X1048219Y430814D01*
G01X1054764D02*
X1053782Y431483D01*
G01X1042328Y422459D02*
X1036110Y425801D01*
G01X1038401D02*
X1042983Y423461D01*
G01X1067528Y426804D02*
X1067200Y426469D01*
G01X1066546Y427138D02*
X1067528Y428141D01*
G01X1062291Y426804D02*
X1061637Y426135D01*
G01Y427472D02*
X1062291Y428141D01*
G01X1046255Y431149D02*
X1047564Y432486D01*
G01X1057055Y427806D02*
X1056401Y426804D01*
G01X1065564Y428141D02*
X1066546Y427138D01*
G01X1064909Y426469D02*
X1064582Y426804D01*
G01X1055746Y432486D02*
X1057055Y431149D01*
G01X1048219Y430814D02*
X1047564Y429812D01*
G01X1042983Y423461D02*
X1042328Y422459D01*
G01X1067200Y426469D02*
X1066873Y425801D01*
G01X1054764Y427806D02*
X1055419Y429143D01*
G01X1065237Y425801D02*
X1064909Y426469D01*
G01X1055419Y429812D02*
X1054764Y430814D01*
G01X1042328Y429143D02*
X1042983Y428141D01*
G01X1057382Y429143D02*
X1057055Y427806D01*
G01Y431149D02*
X1057382Y429812D01*
G01X1045928D02*
X1046255Y431149D01*
G01X1061637Y428475D02*
Y427472D01*
G01X1057382Y429812D02*
Y429143D01*
G01X1055419D02*
Y429812D01*
G01X1031529Y427138D02*
Y433488D01*
G01X1022365D02*
Y427138D01*
G01X995656Y515584D02*
X996050D01*
G01X993425D02*
X993819D01*
G01X996575Y514578D02*
X997625D01*
G01X993819Y514310D02*
X995656D01*
G01X997625D02*
X996575D01*
G01X995656Y513908D02*
X993819D01*
G01X996575Y513774D02*
X997625D01*
G01Y513506D02*
X996575D01*
G01X993819Y512434D02*
X993425D01*
G01X996050D02*
X995656D01*
G01X997625Y513774D02*
Y513506D01*
G01Y514578D02*
Y514310D01*
G01X996575Y513506D02*
Y513774D01*
G01Y514310D02*
Y514578D01*
G01X996050Y515584D02*
Y512434D01*
G01X995656Y514310D02*
Y515584D01*
G01Y512434D02*
Y513908D01*
G01X993819D02*
Y512434D01*
G01Y515584D02*
Y514310D01*
G01X993425Y512434D02*
Y515584D01*
G01X987843Y531081D02*
Y615988D01*
G01X1010933Y524197D02*
X1010441Y524113D01*
G01X1010933Y520260D02*
X1011425Y520344D01*
G01X999331Y515584D02*
X998937Y515517D01*
G01X999331Y512434D02*
X999725Y512501D01*
G01X1010933Y523778D02*
X1010523Y523694D01*
G01X1010933Y520679D02*
X1011343Y520762D01*
G01X999331Y515249D02*
X999003Y515182D01*
G01X999331Y512769D02*
X999659Y512836D01*
G01X1065182Y519079D02*
X1064772Y518995D01*
G01X1060507Y517655D02*
X1060096Y517571D01*
G01X1065592Y516566D02*
X1066002Y516650D01*
G01X1060999Y515142D02*
X1061409Y515226D01*
G01X1065592Y515142D02*
X1066002Y515226D01*
G01X1060178Y517152D02*
X1060507Y517236D01*
G01X1061327Y515644D02*
X1060999Y515561D01*
G01X1080717Y528409D02*
X1044102D01*
G01X1006340Y524197D02*
X1006832D01*
G01X1003551D02*
X1004043D01*
G01X1007488Y522940D02*
X1008801D01*
G01X1004043Y522605D02*
X1006340D01*
G01X1008801D02*
X1007488D01*
G01X1006340Y522103D02*
X1004043D01*
G01X1007488Y521935D02*
X1008801D01*
G01Y521600D02*
X1007488D01*
G01X1004043Y520260D02*
X1003551D01*
G01X1006832D02*
X1006340D01*
G01X1055749Y519079D02*
X1056241D01*
G01X1052961D02*
X1053453D01*
G01X1062065D02*
X1059276D01*
G01X1065592D02*
X1065182D01*
G01X1059686Y518660D02*
X1062065D01*
G01X1065674D02*
X1065100D01*
G01X1060999Y517655D02*
X1060507D01*
G01X1053453Y517487D02*
X1055749D01*
G01X1060507Y517236D02*
X1060999D01*
G01X1065100Y516985D02*
X1065674D01*
G01X1055749D02*
X1053453D01*
G01X1059276Y516901D02*
X1059850D01*
G01X1065182Y516566D02*
X1065592D01*
G01X1059768Y516147D02*
X1059276D01*
G01X1064526Y516063D02*
X1064115D01*
G01X1062885Y515561D02*
X1063295D01*
G01X1060999D02*
X1060507D01*
G01X1065674D02*
X1065182D01*
G01X1065264Y515142D02*
X1065592D01*
G01X1060507D02*
X1060999D01*
G01X1053453D02*
X1052961D01*
G01X1056241D02*
X1055749D01*
G01X1063295D02*
X1062885D01*
G01X1080717Y506362D02*
X1044102D01*
G01X1066002Y518995D02*
X1065592Y519079D01*
G01X1061409Y517571D02*
X1060999Y517655D01*
G01X1064772Y516650D02*
X1065182Y516566D01*
G01X1064854Y515226D02*
X1065264Y515142D01*
G01X1060096Y515226D02*
X1060507Y515142D01*
G01X1011343Y523694D02*
X1010933Y523778D01*
G01X1011425Y524113D02*
X1010933Y524197D01*
G01X1010441Y520344D02*
X1010933Y520260D01*
G01X999725Y515517D02*
X999331Y515584D01*
G01X1065920Y518576D02*
X1065674Y518660D01*
G01X1060999Y517236D02*
X1061327Y517152D01*
G01X1060507Y515561D02*
X1060178Y515644D01*
G01X1010523Y520762D02*
X1010933Y520679D01*
G01X999659Y515182D02*
X999331Y515249D01*
G01X999003Y512836D02*
X999331Y512769D01*
G01X998937Y512501D02*
X999331Y512434D01*
G01X1064854Y517068D02*
X1065100Y516985D01*
G01X1065182Y515561D02*
X1064936Y515644D01*
G01X1058456Y516314D02*
X1056898Y517152D01*
G01X1057472D02*
X1058620Y516566D01*
G01X1066166Y518409D02*
X1065920Y518576D01*
G01X1064608Y517236D02*
X1064854Y517068D01*
G01X1064936Y515644D02*
X1064690Y515812D01*
G01X1061327Y517152D02*
X1061573Y516985D01*
G01X1060178Y515644D02*
X1059932Y515812D01*
G01X1066412Y518744D02*
X1066002Y518995D01*
G01X1064362Y516901D02*
X1064772Y516650D01*
G01X1061819Y517320D02*
X1061409Y517571D01*
G01X1064444Y515477D02*
X1064854Y515226D01*
G01X1059686Y515477D02*
X1060096Y515226D01*
G01X1011589Y523527D02*
X1011343Y523694D01*
G01X1010277Y520930D02*
X1010523Y520762D01*
G01X1011835Y523862D02*
X1011425Y524113D01*
G01X1010031Y520595D02*
X1010441Y520344D01*
G01X1000053Y515316D02*
X999725Y515517D01*
G01X998609Y512702D02*
X998937Y512501D01*
G01X999856Y515048D02*
X999659Y515182D01*
G01X998806Y512970D02*
X999003Y512836D01*
G01X1065920Y515644D02*
X1065674Y515561D01*
G01Y516985D02*
X1065920Y517068D01*
G01X1065100Y518660D02*
X1064854Y518576D01*
G01X1066330Y518157D02*
X1066166Y518409D01*
G01X1066658D02*
X1066412Y518744D01*
G01X1064115Y517236D02*
X1064362Y516901D01*
G01X1064198Y515812D02*
X1064444Y515477D01*
G01X1062065Y516985D02*
X1061819Y517320D01*
G01X1059440Y515812D02*
X1059686Y515477D01*
G01X1012081Y523610D02*
X1011835Y523862D01*
G01X1009785Y520846D02*
X1010031Y520595D01*
G01X1058620Y517738D02*
X1057472Y517152D01*
G01X1064444Y517487D02*
X1064608Y517236D01*
G01X1064690Y515812D02*
X1064526Y516063D01*
G01X1061573Y516985D02*
X1061737Y516733D01*
G01X1058456Y517990D02*
X1058620Y517738D01*
G01X1000250Y515115D02*
X1000053Y515316D01*
G01X998412Y512903D02*
X998609Y512702D01*
G01X1056898Y517152D02*
X1058456Y517990D01*
G01X1066002Y515226D02*
X1066412Y515477D01*
G01X1061409Y515226D02*
X1061819Y515477D01*
G01X1064772Y518995D02*
X1064362Y518744D01*
G01X1060096Y517571D02*
X1059686Y517320D01*
G01X1066166Y515812D02*
X1065920Y515644D01*
G01X1066002Y516650D02*
X1066494Y516985D01*
G01X1065920Y517068D02*
X1066166Y517236D01*
G01X1061573Y515812D02*
X1061327Y515644D01*
G01X1064854Y518576D02*
X1064608Y518409D01*
G01X1066412Y517906D02*
X1066330Y518157D01*
G01X1064362Y517738D02*
X1064444Y517487D01*
G01X1064115Y516063D02*
X1064198Y515812D01*
G01X1061737Y516733D02*
X1061819Y516482D01*
G01X1066822Y517990D02*
X1066658Y518409D01*
G01X1063951Y517655D02*
X1064115Y517236D01*
G01X1062229Y516566D02*
X1062065Y516985D01*
G01X1059932Y515812D02*
X1059768Y516147D01*
G01X1059276D02*
X1059440Y515812D01*
G01X1011917Y523024D02*
X1011589Y523527D01*
G01X1009949Y521433D02*
X1010277Y520930D01*
G01X999725Y512501D02*
X1000053Y512702D01*
G01X1011425Y520344D02*
X1011835Y520595D01*
G01X998937Y515517D02*
X998609Y515316D01*
G01X1010441Y524113D02*
X1010031Y523862D01*
G01X1011343Y520762D02*
X1011589Y520930D01*
G01X999659Y512836D02*
X999856Y512970D01*
G01X1059850Y516901D02*
X1060178Y517152D01*
G01X1066904Y517403D02*
X1066822Y517990D01*
G01X1012245Y523275D02*
X1012081Y523610D01*
G01X1009621Y521181D02*
X1009785Y520846D01*
G01X1000118Y514645D02*
X999856Y515048D01*
G01X998544Y513372D02*
X998806Y512970D01*
G01X999003Y515182D02*
X998806Y515048D01*
G01X1010523Y523694D02*
X1010277Y523527D01*
G01X1066412Y515477D02*
X1066658Y515812D01*
G01X1064362Y518744D02*
X1064115Y518409D01*
G01X1061819Y515477D02*
X1062065Y515812D01*
G01X1066330Y516063D02*
X1066166Y515812D01*
G01Y517236D02*
X1066330Y517487D01*
G01X1064608Y518409D02*
X1064444Y518157D01*
G01X1061737Y516063D02*
X1061573Y515812D01*
G01X1058620Y516566D02*
X1058456Y516314D01*
G01X1066904Y516817D02*
Y517403D01*
G01X1066494Y516985D02*
Y516817D01*
G01X1066412Y517738D02*
Y517906D01*
G01X1064362D02*
Y517738D01*
G01X1063951Y517990D02*
Y517655D01*
G01X1012327Y523024D02*
X1012245Y523275D01*
G01X1009539Y521433D02*
X1009621Y521181D01*
G01X1000381Y514846D02*
X1000250Y515115D01*
G01X998281Y513171D02*
X998412Y512903D01*
G01X1011835Y520595D02*
X1012081Y520846D01*
G01X1000053Y512702D02*
X1000250Y512903D01*
G01X1010031Y523862D02*
X1009785Y523610D01*
G01X998609Y515316D02*
X998412Y515115D01*
G01X1066658Y515812D02*
X1066822Y516231D01*
G01X1064115Y518409D02*
X1063951Y517990D01*
G01X1062065Y515812D02*
X1062229Y516231D01*
G01X1066412Y516314D02*
X1066330Y516063D01*
G01Y517487D02*
X1066412Y517738D01*
G01X1064444Y518157D02*
X1064362Y517906D01*
G01X1061819Y516314D02*
X1061737Y516063D01*
G01X1066494Y516817D02*
X1066412Y516314D01*
G01X1066822Y516231D02*
X1066904Y516817D01*
G01X1063295Y515561D02*
Y515142D01*
G01X1062885D02*
Y515561D01*
G01X1062229Y516231D02*
Y516566D01*
G01X1062065Y518660D02*
Y519079D01*
G01X1061819Y516482D02*
Y516314D01*
G01X1059686Y517320D02*
Y518660D01*
G01X1059276Y519079D02*
Y516901D01*
G01X1056241Y519079D02*
Y515142D01*
G01X1055749Y517487D02*
Y519079D01*
G01Y515142D02*
Y516985D01*
G01X1053453D02*
Y515142D01*
G01Y519079D02*
Y517487D01*
G01X1052961Y515142D02*
Y519079D01*
G01X1044102Y528409D02*
Y506362D01*
G01X1011999Y522522D02*
X1011917Y523024D01*
G01X1009867Y521935D02*
X1009949Y521433D01*
G01X1012409Y522605D02*
X1012327Y523024D01*
G01X1009457Y521851D02*
X1009539Y521433D01*
G01X1000512Y514310D02*
X1000446Y514645D01*
G01D02*
X1000381Y514846D01*
G01X998216Y513372D02*
X998281Y513171D01*
G01X1011589Y520930D02*
X1011917Y521433D01*
G01X1010277Y523527D02*
X1009949Y523024D01*
G01X999856Y512970D02*
X1000118Y513372D01*
G01X998806Y515048D02*
X998544Y514645D01*
G01X1000184Y514243D02*
X1000118Y514645D01*
G01X998478Y513774D02*
X998544Y513372D01*
G01X998150Y513707D02*
X998216Y513372D01*
G01X1012081Y520846D02*
X1012245Y521181D01*
G01X1009785Y523610D02*
X1009621Y523275D01*
G01X1000250Y512903D02*
X1000381Y513171D01*
G01X998412Y515115D02*
X998281Y514846D01*
G01X1012245Y521181D02*
X1012327Y521433D01*
G01X1009621Y523275D02*
X1009539Y523024D01*
G01X1000381Y513171D02*
X1000446Y513372D01*
G01X998281Y514846D02*
X998216Y514645D01*
G01X1012327Y521433D02*
X1012409Y521851D01*
G01X1009539Y523024D02*
X1009457Y522605D01*
G01X1000446Y513372D02*
X1000512Y513707D01*
G01X998216Y514645D02*
X998150Y514310D01*
G01X1011917Y521433D02*
X1011999Y521935D01*
G01X1009949Y523024D02*
X1009867Y522522D01*
G01X1000118Y513372D02*
X1000184Y513774D01*
G01X998544Y514645D02*
X998478Y514243D01*
G01X1012409Y521851D02*
Y522605D01*
G01X1011999Y521935D02*
Y522522D01*
G01X1009867D02*
Y521935D01*
G01X1009457Y522605D02*
Y521851D01*
G01X1008801Y521935D02*
Y521600D01*
G01Y522940D02*
Y522605D01*
G01X1007488D02*
Y522940D01*
G01Y521600D02*
Y521935D01*
G01X1006832Y524197D02*
Y520260D01*
G01X1006340Y522605D02*
Y524197D01*
G01Y520260D02*
Y522103D01*
G01X1004043D02*
Y520260D01*
G01Y524197D02*
Y522605D01*
G01X1003551Y520260D02*
Y524197D01*
G01X1000512Y513707D02*
Y514310D01*
G01X1000184Y513774D02*
Y514243D01*
G01X998478D02*
Y513774D01*
G01X998150Y514310D02*
Y513707D01*
G01X1064946Y598311D02*
X1064535Y598227D01*
G01X1060270Y596887D02*
X1059860Y596803D01*
G01X1065356Y595798D02*
X1065766Y595882D01*
G01X1060762Y594374D02*
X1061173Y594458D01*
G01X1065356Y594374D02*
X1065766Y594458D01*
G01X1059942Y596384D02*
X1060270Y596468D01*
G01X1061091Y594877D02*
X1060762Y594793D01*
G01X1044102Y608311D02*
X1080717D01*
G01X1055513Y598311D02*
X1056005D01*
G01X1052724D02*
X1053217D01*
G01X1061829D02*
X1059040D01*
G01X1065356D02*
X1064946D01*
G01X1059450Y597892D02*
X1061829D01*
G01X1065438D02*
X1064864D01*
G01X1067324Y597055D02*
X1067734D01*
G01X1060762Y596887D02*
X1060270D01*
G01X1053217Y596719D02*
X1055513D01*
G01X1060270Y596468D02*
X1060762D01*
G01X1064864Y596217D02*
X1065438D01*
G01X1055513D02*
X1053217D01*
G01X1059040Y596133D02*
X1059614D01*
G01X1064946Y595798D02*
X1065356D01*
G01X1059532Y595379D02*
X1059040D01*
G01X1064289Y595295D02*
X1063879D01*
G01X1062649Y594793D02*
X1063059D01*
G01X1060762D02*
X1060270D01*
G01X1065438D02*
X1064946D01*
G01X1065028Y594374D02*
X1065356D01*
G01X1060270D02*
X1060762D01*
G01X1053217D02*
X1052724D01*
G01X1056005D02*
X1055513D01*
G01X1063059D02*
X1062649D01*
G01X1067734D02*
X1067324D01*
G01X1044102Y586264D02*
X1080717D01*
G01X1065766Y598227D02*
X1065356Y598311D01*
G01X1061173Y596803D02*
X1060762Y596887D01*
G01X1064535Y595882D02*
X1064946Y595798D01*
G01X1064617Y594458D02*
X1065028Y594374D01*
G01X1059860Y594458D02*
X1060270Y594374D01*
G01X1065684Y597808D02*
X1065438Y597892D01*
G01X1064617Y596301D02*
X1064864Y596217D01*
G01X1060762Y596468D02*
X1061091Y596384D01*
G01X1060270Y594793D02*
X1059942Y594877D01*
G01X1064946Y594793D02*
X1064699Y594877D01*
G01X1058220Y595547D02*
X1056661Y596384D01*
G01X1057236D02*
X1058384Y595798D01*
G01X1065930Y597641D02*
X1065684Y597808D01*
G01X1066176Y597976D02*
X1065766Y598227D01*
G01X1064125Y596133D02*
X1064535Y595882D01*
G01X1061583Y596552D02*
X1061173Y596803D01*
G01X1064207Y594709D02*
X1064617Y594458D01*
G01X1059450Y594709D02*
X1059860Y594458D01*
G01X1064371Y596468D02*
X1064617Y596301D01*
G01X1064699Y594877D02*
X1064453Y595044D01*
G01X1061091Y596384D02*
X1061337Y596217D01*
G01X1059942Y594877D02*
X1059696Y595044D01*
G01X1066422Y597641D02*
X1066176Y597976D01*
G01X1063879Y596468D02*
X1064125Y596133D01*
G01X1063961Y595044D02*
X1064207Y594709D01*
G01X1061829Y596217D02*
X1061583Y596552D01*
G01X1059204Y595044D02*
X1059450Y594709D01*
G01X1066094Y597390D02*
X1065930Y597641D01*
G01X1064207Y596719D02*
X1064371Y596468D01*
G01X1064453Y595044D02*
X1064289Y595295D01*
G01X1061337Y596217D02*
X1061501Y595966D01*
G01X1058220Y597222D02*
X1058384Y596971D01*
G01X1059696Y595044D02*
X1059532Y595379D01*
G01X1059040D02*
X1059204Y595044D01*
G01X1066176Y597138D02*
X1066094Y597390D01*
G01X1064125Y596971D02*
X1064207Y596719D01*
G01X1063879Y595295D02*
X1063961Y595044D01*
G01X1061501Y595966D02*
X1061583Y595714D01*
G01X1066586Y597222D02*
X1066422Y597641D01*
G01X1063715Y596887D02*
X1063879Y596468D01*
G01X1061993Y595798D02*
X1061829Y596217D01*
G01X1065684Y594877D02*
X1065438Y594793D01*
G01Y596217D02*
X1065684Y596301D01*
G01X1064864Y597892D02*
X1064617Y597808D01*
G01X1066668Y596636D02*
X1066586Y597222D01*
G01X1058384Y596971D02*
X1057236Y596384D01*
G01X1056661D02*
X1058220Y597222D01*
G01X1065766Y594458D02*
X1066176Y594709D01*
G01X1067324Y594374D02*
Y597055D01*
G01X1066668Y596049D02*
Y596636D01*
G01X1066258Y596217D02*
Y596049D01*
G01X1066176Y596971D02*
Y597138D01*
G01X1064125D02*
Y596971D01*
G01X1061173Y594458D02*
X1061583Y594709D01*
G01X1064535Y598227D02*
X1064125Y597976D01*
G01X1059860Y596803D02*
X1059450Y596552D01*
G01X1065930Y595044D02*
X1065684Y594877D01*
G01X1065766Y595882D02*
X1066258Y596217D01*
G01X1065684Y596301D02*
X1065930Y596468D01*
G01X1061337Y595044D02*
X1061091Y594877D01*
G01X1064617Y597808D02*
X1064371Y597641D01*
G01X1059614Y596133D02*
X1059942Y596384D01*
G01X1066258Y596049D02*
X1066176Y595547D01*
G01X1066586Y595463D02*
X1066668Y596049D01*
G01X1063715Y597222D02*
Y596887D01*
G01X1063059Y594793D02*
Y594374D01*
G01X1062649D02*
Y594793D01*
G01X1061993Y595463D02*
Y595798D01*
G01X1061829Y597892D02*
Y598311D01*
G01X1061583Y595714D02*
Y595547D01*
G01X1059450Y596552D02*
Y597892D01*
G01X1059040Y598311D02*
Y596133D01*
G01X1056005Y598311D02*
Y594374D01*
G01X1055513Y596719D02*
Y598311D01*
G01Y594374D02*
Y596217D01*
G01X1053217D02*
Y594374D01*
G01Y598311D02*
Y596719D01*
G01X1052724Y594374D02*
Y598311D01*
G01X1044102Y608311D02*
Y586264D01*
G01X1066176Y594709D02*
X1066422Y595044D01*
G01X1064125Y597976D02*
X1063879Y597641D01*
G01X1061583Y594709D02*
X1061829Y595044D01*
G01X1066094Y595295D02*
X1065930Y595044D01*
G01Y596468D02*
X1066094Y596719D01*
G01X1064371Y597641D02*
X1064207Y597390D01*
G01X1061501Y595295D02*
X1061337Y595044D01*
G01X1058384Y595798D02*
X1058220Y595547D01*
G01X1066422Y595044D02*
X1066586Y595463D01*
G01X1063879Y597641D02*
X1063715Y597222D01*
G01X1061829Y595044D02*
X1061993Y595463D01*
G01X1066176Y595547D02*
X1066094Y595295D01*
G01Y596719D02*
X1066176Y596971D01*
G01X1064207Y597390D02*
X1064125Y597138D01*
G01X1061583Y595547D02*
X1061501Y595295D01*
G01X1074951Y-589495D02*
X1075499Y-589390D01*
X1076126Y-589075D01*
X1076518Y-588550D01*
X1076674Y-587815D01*
X1076518Y-587080D01*
X1076048Y-586450D01*
X1075343Y-586135D01*
X1074559D01*
X1074089Y-585925D01*
X1073698Y-585400D01*
X1073541Y-584665D01*
X1073776Y-583930D01*
X1074324Y-583405D01*
X1074951Y-583195D01*
X1075578Y-583405D01*
X1076126Y-583930D01*
X1076361Y-584665D01*
X1076204Y-585400D01*
X1075813Y-585925D01*
X1075343Y-586135D01*
X1074559D01*
X1073854Y-586450D01*
X1073384Y-587080D01*
X1073228Y-587815D01*
X1073384Y-588550D01*
X1073776Y-589075D01*
X1074403Y-589390D01*
X1074951Y-589495D01*
G01X1074481Y-164057D02*
X1076647D01*
G01X1071332D02*
X1073497D01*
G01X1068182D02*
X1070347D01*
G01X1076647D02*
Y-153033D01*
G01X1074481D02*
Y-164057D01*
G01X1073497D02*
Y-153033D01*
G01X1071332D02*
Y-164057D01*
G01X1070347D02*
Y-153033D01*
G01X1068182D02*
Y-164057D01*
G01X1070347Y-153033D02*
X1068182D01*
G01X1073497D02*
X1071332D01*
G01X1076647D02*
X1074481D01*
G01X1146922Y-164057D02*
X1149088D01*
G01X1143773D02*
X1145938D01*
G01X1140623D02*
X1142788D01*
G01X1137473D02*
X1139639D01*
G01X1134324D02*
X1136489D01*
G01X1131174D02*
X1133340D01*
G01X1128025D02*
X1130190D01*
G01X1124875D02*
X1127040D01*
G01X1121725D02*
X1123891D01*
G01X1118576D02*
X1120741D01*
G01X1115426D02*
X1117591D01*
G01X1112277D02*
X1114442D01*
G01X1109127D02*
X1111292D01*
G01X1105977D02*
X1108143D01*
G01X1102828D02*
X1104993D01*
G01X1099678D02*
X1101843D01*
G01X1096528D02*
X1098694D01*
G01X1093379D02*
X1095544D01*
G01X1090229D02*
X1092395D01*
G01X1087080D02*
X1089245D01*
G01X1083930D02*
X1086095D01*
G01X1080780D02*
X1082946D01*
G01X1077631D02*
X1079796D01*
G01X1146922Y-153033D02*
Y-164057D01*
G01X1145938D02*
Y-153033D01*
G01X1143773D02*
Y-164057D01*
G01X1142788D02*
Y-153033D01*
G01X1140623D02*
Y-164057D01*
G01X1139639D02*
Y-153033D01*
G01X1137473D02*
Y-164057D01*
G01X1136489D02*
Y-153033D01*
G01X1134324D02*
Y-164057D01*
G01X1133340D02*
Y-153033D01*
G01X1131174D02*
Y-164057D01*
G01X1130190D02*
Y-153033D01*
G01X1128025D02*
Y-164057D01*
G01X1127040D02*
Y-153033D01*
G01X1124875D02*
Y-164057D01*
G01X1123891D02*
Y-153033D01*
G01X1121725D02*
Y-164057D01*
G01X1120741D02*
Y-153033D01*
G01X1118576D02*
Y-164057D01*
G01X1117591D02*
Y-153033D01*
G01X1115426D02*
Y-164057D01*
G01X1114442D02*
Y-153033D01*
G01X1112277D02*
Y-164057D01*
G01X1111292D02*
Y-153033D01*
G01X1109127D02*
Y-164057D01*
G01X1108143D02*
Y-153033D01*
G01X1105977D02*
Y-164057D01*
G01X1104993D02*
Y-153033D01*
G01X1102828D02*
Y-164057D01*
G01X1101843D02*
Y-153033D01*
G01X1099678D02*
Y-164057D01*
G01X1098694D02*
Y-153033D01*
G01X1096528D02*
Y-164057D01*
G01X1095544D02*
Y-153033D01*
G01X1093379D02*
Y-164057D01*
G01X1092395D02*
Y-153033D01*
G01X1090229D02*
Y-164057D01*
G01X1089245D02*
Y-153033D01*
G01X1087080D02*
Y-164057D01*
G01X1086095D02*
Y-153033D01*
G01X1083930D02*
Y-164057D01*
G01X1082946D02*
Y-153033D01*
G01X1080780D02*
Y-164057D01*
G01X1079796D02*
Y-153033D01*
G01X1077631D02*
Y-164057D01*
G01X1148081Y-147522D02*
X1145666Y-126558D01*
G01X1079796Y-153033D02*
X1077631D01*
G01X1082946D02*
X1080780D01*
G01X1086095D02*
X1083930D01*
G01X1089245D02*
X1087080D01*
G01X1092395D02*
X1090229D01*
G01X1095544D02*
X1093379D01*
G01X1098694D02*
X1096528D01*
G01X1101843D02*
X1099678D01*
G01X1104993D02*
X1102828D01*
G01X1108143D02*
X1105977D01*
G01X1111292D02*
X1109127D01*
G01X1114442D02*
X1112277D01*
G01X1117591D02*
X1115426D01*
G01X1120741D02*
X1118576D01*
G01X1123891D02*
X1121725D01*
G01X1127040D02*
X1124875D01*
G01X1130190D02*
X1128025D01*
G01X1133340D02*
X1131174D01*
G01X1136489D02*
X1134324D01*
G01X1139639D02*
X1137473D01*
G01X1142788D02*
X1140623D01*
G01X1145938D02*
X1143773D01*
G01X1149088D02*
X1146922D01*
G01X1145666Y-126558D02*
X1133660D01*
G01X1104482Y-121506D02*
Y-122227D01*
G01X1103507Y-120062D02*
X1104482Y-121506D01*
G01X1115687Y-122227D02*
X1120072D01*
G01X1119098Y-115731D02*
X1115687Y-122227D01*
G01X1119098Y-124393D02*
Y-115731D01*
G01X1123970Y-123671D02*
X1123483Y-122949D01*
G01X1124944Y-124393D02*
X1123970Y-123671D01*
G01X1125919Y-124393D02*
X1124944D01*
G01X1126893Y-123671D02*
X1125919Y-124393D01*
G01X1127380Y-122949D02*
X1126893Y-123671D01*
G01X1127868Y-122227D02*
X1127380Y-122949D01*
G01X1127868Y-121506D02*
Y-122227D01*
G01X1109354Y-123671D02*
X1109841Y-124393D01*
G01X1109354D02*
Y-123671D01*
G01X1109841Y-124393D02*
X1109354D01*
G01X1100584Y-123671D02*
X1100097Y-122949D01*
G01X1101559Y-124393D02*
X1100584Y-123671D01*
G01X1102533Y-124393D02*
X1101559D01*
G01X1103507Y-123671D02*
X1102533Y-124393D01*
G01X1104482Y-122227D02*
X1103507Y-123671D01*
G01X1102533Y-119340D02*
X1103507Y-120062D01*
G01Y-118619D02*
X1102533Y-119340D01*
G01X1103995Y-117897D02*
X1103507Y-118619D01*
G01X1103995Y-117175D02*
Y-117897D01*
G01X1103507Y-116453D02*
X1103995Y-117175D01*
G01X1102533Y-115731D02*
X1103507Y-116453D01*
G01X1101559Y-115731D02*
X1102533D01*
G01X1100584Y-116453D02*
X1101559Y-115731D01*
G01X1126893Y-120062D02*
X1127868Y-121506D01*
G01X1125919Y-119340D02*
X1126893Y-120062D01*
G01Y-118619D02*
X1125919Y-119340D01*
G01X1127380Y-117897D02*
X1126893Y-118619D01*
G01X1127380Y-117175D02*
Y-117897D01*
G01X1126893Y-116453D02*
X1127380Y-117175D01*
G01X1125919Y-115731D02*
X1126893Y-116453D01*
G01X1124944Y-115731D02*
X1125919D01*
G01X1123970Y-116453D02*
X1124944Y-115731D01*
G01X1138380Y-94305D02*
X1133787Y-96650D01*
G01X1131490D02*
X1137724Y-93300D01*
G01X1144942Y-89279D02*
X1143301Y-90284D01*
G01X1145270Y-90954D02*
X1144286Y-91624D01*
G01X1146910Y-88944D02*
X1144942Y-89279D01*
G01X1146910Y-90619D02*
X1145270Y-90954D01*
G01X1146910Y-103016D02*
X1148551Y-102681D01*
G01X1143301Y-90284D02*
X1142317Y-91289D01*
G01X1126897Y-88944D02*
X1128866D01*
G01X1115742D02*
X1117711D01*
G01Y-95310D02*
X1126897D01*
G01Y-97320D02*
X1117711D01*
G01X1146910Y-104692D02*
X1148879Y-104357D01*
G01X1144286Y-91624D02*
X1142973Y-93635D01*
G01X1138380Y-98996D02*
X1137724Y-100001D01*
G01X1148551Y-90954D02*
X1146910Y-90619D01*
G01X1148879Y-89279D02*
X1146910Y-88944D01*
G01X1117711Y-104692D02*
X1115742D01*
G01X1128866D02*
X1126897D01*
G01X1124944Y-119340D02*
X1125919D01*
G01X1101559D02*
X1102533D01*
G01X1142317Y-91289D02*
X1141661Y-92630D01*
G01D02*
X1141333Y-93635D01*
G01X1145270Y-102681D02*
X1146910Y-103016D01*
G01X1144942Y-104357D02*
X1146910Y-104692D01*
G01X1141333Y-93635D02*
X1141005Y-95310D01*
G01X1142973Y-93635D02*
X1142645Y-95645D01*
G01Y-97991D02*
X1142973Y-100001D01*
G01X1141005Y-98326D02*
X1141333Y-100001D01*
G01X1144286Y-102011D02*
X1145270Y-102681D01*
G01X1143301Y-103352D02*
X1144942Y-104357D01*
G01X1137724Y-100001D02*
X1131490Y-96650D01*
G01X1133787D02*
X1138380Y-98996D01*
G01X1142645Y-95645D02*
Y-97991D01*
G01X1141005Y-95310D02*
Y-98326D01*
G01X1128866Y-88944D02*
Y-104692D01*
G01X1126897Y-95310D02*
Y-88944D01*
G01Y-104692D02*
Y-97320D01*
G01X1141333Y-100001D02*
X1141661Y-101006D01*
G01D02*
X1142317Y-102346D01*
G01X1142973Y-100001D02*
X1144286Y-102011D01*
G01X1137724Y-93300D02*
X1138380Y-94305D01*
G01X1142317Y-102346D02*
X1143301Y-103352D01*
G01X1117711Y-97320D02*
Y-104692D01*
G01Y-88944D02*
Y-95310D01*
G01X1115742Y-104692D02*
Y-88944D01*
G01X1094250Y-115731D02*
Y-124393D01*
G01X1083556Y-15868D02*
Y-94648D01*
G01X1076765Y2006D02*
X1078241D01*
G01X1068399D02*
X1069875D01*
G01X1076765Y7534D02*
Y2006D01*
G01X1069875D02*
Y7534D01*
G01X1068399Y13817D02*
Y2006D01*
G01X1069875Y13817D02*
X1068399D01*
G01X1078241D02*
X1076765D01*
G01Y9042D02*
X1069875D01*
G01Y7534D02*
X1076765D01*
G01Y13817D02*
Y9042D01*
G01X1069875D02*
Y13817D01*
G01X1139698Y-2758D02*
X1371981D01*
G01X1234934Y-39746D02*
X1107434D01*
G01X1107865Y-39766D02*
X1403814D01*
G01X1107865D02*
X1083987Y-15888D01*
G01X1107434Y-39746D02*
X1083556Y-15868D01*
G01X1139698Y38581D02*
Y-2758D01*
G01X1083989Y-15868D02*
Y42951D01*
G01X1078241Y2006D02*
Y13817D01*
G01X1073259Y95156D02*
X1074243D01*
G01X1067681D02*
X1068665D01*
G01Y91973D02*
X1073259D01*
G01Y90967D02*
X1068665D01*
G01Y87282D02*
X1067681D01*
G01X1074243D02*
X1073259D01*
G01X1078672Y89627D02*
X1075555Y91303D01*
G01X1076704D02*
X1079000Y90130D01*
G01Y92475D02*
X1076704Y91303D01*
G01X1075555D02*
X1078672Y92978D01*
G01X1074243Y95156D02*
Y87282D01*
G01X1073259Y91973D02*
Y95156D01*
G01Y87282D02*
Y90967D01*
G01X1068665D02*
Y87282D01*
G01Y95156D02*
Y91973D01*
G01X1067681Y87282D02*
Y95156D01*
G01X1371194Y38581D02*
X1139698D01*
G01X1083265Y94318D02*
X1082445Y94151D01*
G01X1091303Y94988D02*
X1092452Y95156D01*
G01X1083265D02*
X1082281Y94988D01*
G01X1083265Y87282D02*
X1084249Y87449D01*
G01X1092288Y94318D02*
X1091467Y94151D01*
G01X1083265Y88119D02*
X1084085Y88287D01*
G01X1092452Y95156D02*
X1093108D01*
G01X1092944Y94318D02*
X1092288D01*
G01X1090647Y93313D02*
X1089827D01*
G01X1108528Y92643D02*
X1109184D01*
G01X1105903D02*
X1106559D01*
G01X1104263D02*
X1105083D01*
G01X1101146D02*
X1101802D01*
G01X1098521D02*
X1099177D01*
G01X1096881D02*
X1097701D01*
G01X1098849Y91973D02*
X1098521D01*
G01X1101474D02*
X1100982D01*
G01X1106231D02*
X1105903D01*
G01X1108856D02*
X1108364D01*
G01X1090975Y88119D02*
X1095568D01*
G01X1087530D02*
X1088351D01*
G01Y87282D02*
X1087530D01*
G01X1095568D02*
X1089663D01*
G01X1097701D02*
X1096881D01*
G01X1100326D02*
X1099505D01*
G01X1102950D02*
X1102130D01*
G01X1105083D02*
X1104263D01*
G01X1107707D02*
X1106887D01*
G01X1110332D02*
X1109512D01*
G01X1093764Y94151D02*
X1092944Y94318D01*
G01X1084085Y94151D02*
X1083265Y94318D01*
G01X1082445Y88287D02*
X1083265Y88119D01*
G01X1093108Y95156D02*
X1094092Y94988D01*
G01X1084249D02*
X1083265Y95156D01*
G01X1082281Y87449D02*
X1083265Y87282D01*
G01X1109184Y92643D02*
X1109676Y92475D01*
G01X1106559Y92643D02*
X1107051Y92475D01*
G01X1101802Y92643D02*
X1102294Y92475D01*
G01X1099177Y92643D02*
X1099669Y92475D01*
G01X1109184Y91805D02*
X1108856Y91973D01*
G01X1106559Y91805D02*
X1106231Y91973D01*
G01X1101802Y91805D02*
X1101474Y91973D01*
G01X1094092Y94988D02*
X1094748Y94653D01*
G01X1099177Y91805D02*
X1098849Y91973D01*
G01X1085070Y94486D02*
X1084249Y94988D01*
G01X1094256Y93816D02*
X1093764Y94151D01*
G01X1084578Y93816D02*
X1084085Y94151D01*
G01X1081953Y88622D02*
X1082445Y88287D01*
G01X1081461Y87952D02*
X1082281Y87449D01*
G01X1109676Y92475D02*
X1110004Y92140D01*
G01X1109348Y91638D02*
X1109184Y91805D01*
G01X1107051Y92475D02*
X1107543Y91973D01*
G01X1106723Y91638D02*
X1106559Y91805D01*
G01X1102294Y92475D02*
X1102622Y92140D01*
G01X1101966Y91638D02*
X1101802Y91805D01*
G01X1099669Y92475D02*
X1100162Y91973D01*
G01X1099341Y91638D02*
X1099177Y91805D01*
G01X1094748Y94653D02*
X1095404Y93983D01*
G01X1085562D02*
X1085070Y94486D01*
G01X1080969Y88454D02*
X1081461Y87952D01*
G01X1109512Y91303D02*
X1109348Y91638D01*
G01X1094584Y93313D02*
X1094256Y93816D01*
G01X1085234Y92810D02*
X1084578Y93816D01*
G01X1110004Y92140D02*
X1110332Y91303D01*
G01X1102622Y92140D02*
X1102950Y91303D01*
G01X1106887D02*
X1106723Y91638D01*
G01X1102130Y91303D02*
X1101966Y91638D01*
G01X1099505Y91303D02*
X1099341Y91638D01*
G01X1085890Y93313D02*
X1085562Y93983D01*
G01X1081297Y89627D02*
X1081953Y88622D01*
G01X1078672Y92978D02*
X1079000Y92475D01*
G01X1095404Y93983D02*
X1095568Y93313D01*
G01X1086054Y92810D02*
X1085890Y93313D01*
G01X1080641Y89125D02*
X1080969Y88454D01*
G01X1108036Y92475D02*
X1108528Y92643D01*
G01X1105903Y91973D02*
X1105411Y91805D01*
G01Y92475D02*
X1105903Y92643D01*
G01X1100654Y92475D02*
X1101146Y92643D01*
G01X1098521Y91973D02*
X1098029Y91805D01*
G01Y92475D02*
X1098521Y92643D01*
G01X1085398Y91805D02*
X1085234Y92810D01*
G01X1086218Y91973D02*
X1086054Y92810D01*
G01X1080312Y90465D02*
X1080477Y89627D01*
G01D02*
X1080641Y89125D01*
G01X1108364Y91973D02*
X1108036Y91805D01*
G01X1100982Y91973D02*
X1100654Y91805D01*
G01X1090647Y94653D02*
X1091303Y94988D01*
G01X1110332Y91303D02*
Y87282D01*
G01X1109512D02*
Y91303D01*
G01X1107707D02*
Y87282D01*
G01X1106887D02*
Y91303D01*
G01X1105083Y91470D02*
Y87282D01*
G01Y92643D02*
Y92140D01*
G01X1104263Y87282D02*
Y92643D01*
G01X1102950Y91303D02*
Y87282D01*
G01X1102130D02*
Y91303D01*
G01X1081133Y90632D02*
X1081297Y89627D01*
G01X1084249Y87449D02*
X1085070Y87952D01*
G01X1082281Y94988D02*
X1081461Y94486D01*
G01X1084085Y88287D02*
X1084578Y88622D01*
G01X1091467Y94151D02*
X1090975Y93816D01*
G01X1082445Y94151D02*
X1081953Y93816D01*
G01X1095076Y91805D02*
X1090975Y88119D01*
G01X1089663D02*
X1094256Y92308D01*
G01X1108036Y91805D02*
X1107872Y91638D01*
G01X1107543Y91973D02*
X1108036Y92475D01*
G01X1105411Y91805D02*
X1105083Y91470D01*
G01Y92140D02*
X1105411Y92475D01*
G01X1100654Y91805D02*
X1100490Y91638D01*
G01X1100162Y91973D02*
X1100654Y92475D01*
G01X1098029Y91805D02*
X1097701Y91470D01*
G01Y92140D02*
X1098029Y92475D01*
G01X1107872Y91638D02*
X1107707Y91303D01*
G01X1100326D02*
Y87282D01*
G01X1099505D02*
Y91303D01*
G01X1097701Y91470D02*
Y87282D01*
G01Y92643D02*
Y92140D01*
G01X1096881Y87282D02*
Y92643D01*
G01X1095568Y88119D02*
Y87282D01*
G01Y93313D02*
Y92978D01*
G01X1094584D02*
Y93313D01*
G01X1089663Y87282D02*
Y88119D01*
G01X1088351D02*
Y87282D01*
G01X1087530D02*
Y88119D01*
G01X1086218Y90465D02*
Y91973D01*
G01X1085398Y90632D02*
Y91805D01*
G01X1081133D02*
Y90632D01*
G01X1080312Y91973D02*
Y90465D01*
G01X1085070Y87952D02*
X1085562Y88454D01*
G01X1089991Y93983D02*
X1090647Y94653D01*
G01X1081461Y94486D02*
X1080969Y93983D01*
G01X1095404Y92308D02*
X1095076Y91805D01*
G01X1090975Y93816D02*
X1090647Y93313D01*
G01X1084578Y88622D02*
X1085234Y89627D01*
G01X1081953Y93816D02*
X1081297Y92810D01*
G01X1079000Y90130D02*
X1078672Y89627D01*
G01X1100490Y91638D02*
X1100326Y91303D01*
G01X1094256Y92308D02*
X1094584Y92978D01*
G01X1085562Y88454D02*
X1085890Y89125D01*
G01X1080969Y93983D02*
X1080641Y93313D01*
G01X1085890Y89125D02*
X1086054Y89627D01*
G01X1080641Y93313D02*
X1080477Y92810D01*
G01X1095568Y92978D02*
X1095404Y92308D01*
G01X1089827Y93313D02*
X1089991Y93983D01*
G01X1086054Y89627D02*
X1086218Y90465D01*
G01X1080477Y92810D02*
X1080312Y91973D01*
G01X1085234Y89627D02*
X1085398Y90632D01*
G01X1081297Y92810D02*
X1081133Y91805D01*
G01X1145264Y304591D02*
X1147429D01*
G01D02*
Y315614D01*
G01X1145264D02*
Y304591D01*
G01X1147429Y315614D02*
X1145264D01*
G01X1075972Y304591D02*
X1078138D01*
G01X1072823D02*
X1074988D01*
G01X1069673D02*
X1071839D01*
G01X1078138D02*
Y315614D01*
G01X1075972D02*
Y304591D01*
G01X1074988D02*
Y315614D01*
G01X1072823D02*
Y304591D01*
G01X1071839D02*
Y315614D01*
G01X1069673D02*
Y304591D01*
G01X1068689D02*
Y315614D01*
G01X1071839D02*
X1069673D01*
G01X1074988D02*
X1072823D01*
G01X1078138D02*
X1075972D01*
G01X1120067Y304591D02*
X1122232D01*
G01X1116917D02*
X1119083D01*
G01X1113768D02*
X1115933D01*
G01X1110618D02*
X1112783D01*
G01X1107468D02*
X1109634D01*
G01X1104319D02*
X1106484D01*
G01X1101169D02*
X1103335D01*
G01X1098020D02*
X1100185D01*
G01X1094870D02*
X1097035D01*
G01X1091720D02*
X1093886D01*
G01X1088571D02*
X1090736D01*
G01X1085421D02*
X1087587D01*
G01X1082272D02*
X1084437D01*
G01X1079122D02*
X1081287D01*
G01X1120067Y315614D02*
Y304591D01*
G01X1119083D02*
Y315614D01*
G01X1116917D02*
Y304591D01*
G01X1115933D02*
Y315614D01*
G01X1113768D02*
Y304591D01*
G01X1112783D02*
Y315614D01*
G01X1110618D02*
Y304591D01*
G01X1109634D02*
Y315614D01*
G01X1107468D02*
Y304591D01*
G01X1106484D02*
Y315614D01*
G01X1104319D02*
Y304591D01*
G01X1103335D02*
Y315614D01*
G01X1101169D02*
Y304591D01*
G01X1100185D02*
Y315614D01*
G01X1098020D02*
Y304591D01*
G01X1097035D02*
Y315614D01*
G01X1094870D02*
Y304591D01*
G01X1093886D02*
Y315614D01*
G01X1091720D02*
Y304591D01*
G01X1090736D02*
Y315614D01*
G01X1088571D02*
Y304591D01*
G01X1087587D02*
Y315614D01*
G01X1085421D02*
Y304591D01*
G01X1084437D02*
Y315614D01*
G01X1082272D02*
Y304591D01*
G01X1081287D02*
Y315614D01*
G01X1079122D02*
Y304591D01*
G01X1081287Y315614D02*
X1079122D01*
G01X1084437D02*
X1082272D01*
G01X1087587D02*
X1085421D01*
G01X1090736D02*
X1088571D01*
G01X1093886D02*
X1091720D01*
G01X1097035D02*
X1094870D01*
G01X1100185D02*
X1098020D01*
G01X1103335D02*
X1101169D01*
G01X1106484D02*
X1104319D01*
G01X1109634D02*
X1107468D01*
G01X1112783D02*
X1110618D01*
G01X1115933D02*
X1113768D01*
G01X1119083D02*
X1116917D01*
G01X1122232D02*
X1120067D01*
G01X1125382D02*
X1123217D01*
G01X1128531D02*
X1126366D01*
G01X1131681D02*
X1129516D01*
G01X1134831D02*
X1132665D01*
G01X1137980D02*
X1135815D01*
G01X1141130D02*
X1138965D01*
G01X1144280D02*
X1142114D01*
G01X1144280Y304591D02*
Y315614D01*
G01X1142114D02*
Y304591D01*
G01X1141130D02*
Y315614D01*
G01X1138965D02*
Y304591D01*
G01X1137980D02*
Y315614D01*
G01X1135815D02*
Y304591D01*
G01X1134831D02*
Y315614D01*
G01X1132665D02*
Y304591D01*
G01X1131681D02*
Y315614D01*
G01X1129516D02*
Y304591D01*
G01X1128531D02*
Y315614D01*
G01X1126366D02*
Y304591D01*
G01X1125382D02*
Y315614D01*
G01X1123217D02*
Y304591D01*
G01X1122232D02*
Y315614D01*
G01X1142114Y304591D02*
X1144280D01*
G01X1138965D02*
X1141130D01*
G01X1135815D02*
X1137980D01*
G01X1132665D02*
X1134831D01*
G01X1129516D02*
X1131681D01*
G01X1126366D02*
X1128531D01*
G01X1123217D02*
X1125382D01*
G01X1100835Y370063D02*
X1518079D01*
G01X1072109Y417780D02*
X1070473D01*
G01X1076364D02*
X1074727D01*
G01X1076364Y426135D02*
Y417780D01*
G01X1074727D02*
Y428475D01*
G01X1072109Y425801D02*
Y417780D01*
G01X1070473D02*
Y425801D01*
G01X1081600Y417780D02*
X1079964D01*
G01X1086836D02*
X1085200D01*
G01X1100835Y461835D02*
Y343921D01*
G01X1086836Y425801D02*
Y417780D01*
G01X1085200D02*
Y425801D01*
G01X1081600D02*
Y417780D01*
G01X1079964D02*
Y425801D01*
G01X1078000Y428475D02*
X1079309D01*
G01X1074727D02*
X1076364D01*
G01X1068509D02*
X1069818D01*
G01X1069164Y427138D02*
X1068182D01*
G01X1078655D02*
X1078000D01*
G01D02*
X1077018Y426804D01*
G01Y428141D02*
X1078000Y428475D01*
G01X1067528Y428141D02*
X1068509Y428475D01*
G01X1068182Y427138D02*
X1067528Y426804D01*
G01X1069818Y428475D02*
X1070800Y428141D01*
G01X1069818Y426804D02*
X1069164Y427138D01*
G01X1077018Y426804D02*
X1076364Y426135D01*
G01Y427472D02*
X1077018Y428141D01*
G01X1070800D02*
X1071455Y427472D01*
G01X1070146Y426469D02*
X1069818Y426804D01*
G01X1071455Y427472D02*
X1072109Y425801D01*
G01X1070473D02*
X1070146Y426469D01*
G01X1076364Y428475D02*
Y427472D01*
G01X1083236Y428475D02*
X1084545D01*
G01X1083891Y427138D02*
X1082909D01*
G01X1082254Y428141D02*
X1083236Y428475D01*
G01X1082909Y427138D02*
X1082254Y426804D01*
G01X1084545Y428475D02*
X1085527Y428141D01*
G01X1079309Y428475D02*
X1080291Y428141D01*
G01X1084545Y426804D02*
X1083891Y427138D01*
G01X1079309Y426804D02*
X1078655Y427138D01*
G01X1082254Y426804D02*
X1081927Y426469D01*
G01X1081273Y427138D02*
X1082254Y428141D01*
G01X1085527D02*
X1086182Y427472D01*
G01X1084873Y426469D02*
X1084545Y426804D01*
G01X1080291Y428141D02*
X1081273Y427138D01*
G01X1079636Y426469D02*
X1079309Y426804D01*
G01X1081927Y426469D02*
X1081600Y425801D01*
G01X1086182Y427472D02*
X1086836Y425801D01*
G01X1085200D02*
X1084873Y426469D01*
G01X1079964Y425801D02*
X1079636Y426469D01*
G01X1093650Y497341D02*
X1093240Y497257D01*
G01X1088892Y496336D02*
X1088482Y496252D01*
G01X1089385Y493823D02*
X1089795Y493907D01*
G01X1094060Y494242D02*
X1094470Y494325D01*
G01X1088564Y495833D02*
X1088892Y495917D01*
G01X1089713Y494325D02*
X1089385Y494242D01*
G01X1094470Y493907D02*
X1094142Y493823D01*
G01X1093157Y497676D02*
X1093732Y497760D01*
G01D02*
X1093896D01*
G01X1084135D02*
X1084627D01*
G01X1081346D02*
X1081839D01*
G01X1090451D02*
X1087662D01*
G01X1088072Y497341D02*
X1090451D01*
G01X1093978D02*
X1093650D01*
G01X1135835Y497012D02*
X1155520D01*
G01X1112213D02*
X1131898D01*
G01X1108276D02*
X1088591D01*
G01X1092829Y496838D02*
X1092419D01*
G01X1101770Y496503D02*
X1102098D01*
G01X1100457D02*
X1100785D01*
G01X1099637D02*
X1100047D01*
G01X1098079D02*
X1098407D01*
G01X1096766D02*
X1097094D01*
G01X1095946D02*
X1096356D01*
G01X1089385Y496336D02*
X1088892D01*
G01X1081839Y496168D02*
X1084135D01*
G01X1096930D02*
X1096766D01*
G01X1098243D02*
X1097997D01*
G01X1100621D02*
X1100457D01*
G01X1101934D02*
X1101688D01*
G01X1093650Y496001D02*
X1093978D01*
G01X1088892Y495917D02*
X1089385D01*
G01X1084135Y495666D02*
X1081839D01*
G01X1093978D02*
X1093650D01*
G01X1087662Y495582D02*
X1088236D01*
G01X1088154Y494828D02*
X1087662D01*
G01X1092337Y494744D02*
X1092747D01*
G01X1093568Y494242D02*
X1094060D01*
G01X1091271D02*
X1091681D01*
G01X1089385D02*
X1088892D01*
G01Y493823D02*
X1089385D01*
G01X1081839D02*
X1081346D01*
G01X1084627D02*
X1084135D01*
G01X1091681D02*
X1091271D01*
G01X1094142D02*
X1093486D01*
G01X1096356D02*
X1095946D01*
G01X1097669D02*
X1097259D01*
G01X1098981D02*
X1098571D01*
G01X1101360D02*
X1100949D01*
G01X1100047D02*
X1099637D01*
G01X1102672D02*
X1102262D01*
G01X1080717Y493075D02*
X1446858D01*
G01X1093896Y497760D02*
X1094470Y497676D01*
G01X1089385Y495917D02*
X1089713Y495833D01*
G01X1093486Y493823D02*
X1093157Y493907D01*
G01X1088892Y494242D02*
X1088564Y494325D01*
G01X1094388Y497257D02*
X1093978Y497341D01*
G01X1089795Y496252D02*
X1089385Y496336D01*
G01X1093157Y494325D02*
X1093568Y494242D01*
G01X1088482Y493907D02*
X1088892Y493823D01*
G01X1094470Y495582D02*
X1093978Y495666D01*
G01X1094634Y495833D02*
X1095044Y495666D01*
G01X1102098Y496503D02*
X1102344Y496420D01*
G01X1100785Y496503D02*
X1101031Y496420D01*
G01X1098407Y496503D02*
X1098653Y496420D01*
G01X1097094Y496503D02*
X1097341Y496420D01*
G01X1102098Y496085D02*
X1101934Y496168D01*
G01X1100785Y496085D02*
X1100621Y496168D01*
G01X1098407Y496085D02*
X1098243Y496168D01*
G01X1094470Y497676D02*
X1094798Y497509D01*
G01X1097094Y496085D02*
X1096930Y496168D01*
G01X1092993Y494409D02*
X1093157Y494325D01*
G01Y493907D02*
X1092829Y494074D01*
G01X1085858Y495833D02*
X1087006Y495247D01*
G01X1094634Y497090D02*
X1094388Y497257D01*
G01X1094716Y495414D02*
X1094470Y495582D01*
G01X1092829Y494074D02*
X1092583Y494242D01*
G01X1089713Y495833D02*
X1089959Y495666D01*
G01X1088564Y494325D02*
X1088318Y494493D01*
G01X1090205Y496001D02*
X1089795Y496252D01*
G01X1088072Y494158D02*
X1088482Y493907D01*
G01X1086842Y494996D02*
X1085283Y495833D01*
G01X1102344Y496420D02*
X1102508Y496252D01*
G01X1101524Y496420D02*
X1101770Y496503D01*
G01X1100457Y496168D02*
X1100211Y496085D01*
G01Y496420D02*
X1100457Y496503D01*
G01X1097833Y496420D02*
X1098079Y496503D01*
G01X1096766Y496168D02*
X1096520Y496085D01*
G01Y496420D02*
X1096766Y496503D01*
G01X1093978Y496001D02*
X1094470Y496168D01*
G01X1102180Y496001D02*
X1102098Y496085D01*
G01X1101031Y496420D02*
X1101278Y496168D01*
G01X1100867Y496001D02*
X1100785Y496085D01*
G01X1098653Y496420D02*
X1098817Y496252D01*
G01X1098489Y496001D02*
X1098407Y496085D01*
G01X1097341Y496420D02*
X1097587Y496168D01*
G01X1097177Y496001D02*
X1097094Y496085D01*
G01X1094798Y497509D02*
X1095126Y497173D01*
G01X1092829Y494577D02*
X1092993Y494409D01*
G01X1101688Y496168D02*
X1101524Y496085D01*
G01X1094798Y494074D02*
X1094470Y493907D01*
G01Y494325D02*
X1094634Y494409D01*
G01X1097997Y496168D02*
X1097833Y496085D01*
G01X1092829Y497509D02*
X1093157Y497676D01*
G01X1087006Y496420D02*
X1085858Y495833D01*
G01X1085283D02*
X1086842Y496671D01*
G01X1089795Y493907D02*
X1090205Y494158D01*
G01X1102262Y495833D02*
X1102180Y496001D01*
G01X1100949Y495833D02*
X1100867Y496001D01*
G01X1094798Y496838D02*
X1094634Y497090D01*
G01X1095044Y495666D02*
X1095208Y495414D01*
G01X1092583Y494242D02*
X1092419Y494493D01*
G01X1089959Y495666D02*
X1090123Y495414D01*
G01X1086842Y496671D02*
X1087006Y496420D01*
G01X1090451Y495666D02*
X1090205Y496001D01*
G01X1087826Y494493D02*
X1088072Y494158D01*
G01X1088482Y496252D02*
X1088072Y496001D01*
G01X1095044Y494242D02*
X1094798Y494074D01*
G01X1089959Y494493D02*
X1089713Y494325D01*
G01X1093240Y497257D02*
X1092993Y497090D01*
G01X1094962Y496085D02*
X1094634Y495833D01*
G01X1088236Y495582D02*
X1088564Y495833D01*
G01X1138984Y502524D02*
Y497012D01*
G01X1092419Y494493D02*
X1092337Y494744D01*
G01X1102508Y496252D02*
X1102672Y495833D01*
G01X1098817Y496252D02*
X1098981Y495833D01*
G01X1090615Y495247D02*
X1090451Y495666D01*
G01X1098571Y495833D02*
X1098489Y496001D01*
G01X1097259Y495833D02*
X1097177Y496001D01*
G01X1094880Y495079D02*
X1094716Y495414D01*
G01X1092747Y494744D02*
X1092829Y494577D01*
G01X1088318Y494493D02*
X1088154Y494828D01*
G01X1087662D02*
X1087826Y494493D01*
G01X1101524Y496085D02*
X1101442Y496001D01*
G01X1101278Y496168D02*
X1101524Y496420D01*
G01X1100211Y496085D02*
X1100047Y495917D01*
G01Y496252D02*
X1100211Y496420D01*
G01X1097833Y496085D02*
X1097751Y496001D01*
G01X1097587Y496168D02*
X1097833Y496420D01*
G01X1096520Y496085D02*
X1096356Y495917D01*
G01X1094634Y494409D02*
X1094798Y494577D01*
G01X1096356Y496252D02*
X1096520Y496420D01*
G01X1094470Y496168D02*
X1094634Y496336D01*
G01X1092501Y497173D02*
X1092829Y497509D01*
G01X1135835Y502524D02*
Y497012D01*
G01X1131898Y502524D02*
Y497012D01*
G01X1128748Y502524D02*
Y497012D01*
G01X1115362Y502524D02*
Y497012D01*
G01X1095126Y497173D02*
X1095208Y496838D01*
G01Y495414D02*
X1095290Y495079D01*
G01X1090123Y495414D02*
X1090205Y495163D01*
G01Y494158D02*
X1090451Y494493D01*
G01X1095208D02*
X1095044Y494242D01*
G01X1095126Y496336D02*
X1094962Y496085D01*
G01X1092993Y497090D02*
X1092829Y496838D01*
G01X1090123Y494744D02*
X1089959Y494493D01*
G01X1087006Y495247D02*
X1086842Y494996D01*
G01X1101442Y496001D02*
X1101360Y495833D01*
G01X1097751Y496001D02*
X1097669Y495833D01*
G01X1094798Y494577D02*
X1094880Y494744D01*
G01X1094634Y496336D02*
X1094798Y496671D01*
G01X1090451Y494493D02*
X1090615Y494912D01*
G01X1095290Y494744D02*
X1095208Y494493D01*
G01X1090205Y494996D02*
X1090123Y494744D01*
G01X1095208Y496671D02*
X1095126Y496336D01*
G01X1092419Y496838D02*
X1092501Y497173D01*
G01X1112213Y502524D02*
Y497012D01*
G01X1108276Y502524D02*
Y497012D01*
G01X1105126Y502524D02*
Y497012D01*
G01X1102672Y495833D02*
Y493823D01*
G01X1102262D02*
Y495833D01*
G01X1101360D02*
Y493823D01*
G01X1100949D02*
Y495833D01*
G01X1100047Y495917D02*
Y493823D01*
G01Y496503D02*
Y496252D01*
G01X1099637Y493823D02*
Y496503D01*
G01X1098981Y495833D02*
Y493823D01*
G01X1098571D02*
Y495833D01*
G01X1097669D02*
Y493823D01*
G01X1097259D02*
Y495833D01*
G01X1096356Y495917D02*
Y493823D01*
G01Y496503D02*
Y496252D01*
G01X1095946Y493823D02*
Y496503D01*
G01X1095290Y495079D02*
Y494744D01*
G01X1095208Y496838D02*
Y496671D01*
G01X1094880Y494744D02*
Y495079D01*
G01X1094798Y496671D02*
Y496838D01*
G01X1093650Y495666D02*
Y496001D01*
G01X1091740Y502524D02*
Y497012D01*
G01X1091681Y494242D02*
Y493823D01*
G01X1091271D02*
Y494242D01*
G01X1090615Y494912D02*
Y495247D01*
G01X1090451Y497341D02*
Y497760D01*
G01X1090205Y495163D02*
Y494996D01*
G01X1088591Y497012D02*
Y531854D01*
G01X1088072Y496001D02*
Y497341D01*
G01X1087662Y497760D02*
Y495582D01*
G01X1084627Y497760D02*
Y493823D01*
G01X1084135Y496168D02*
Y497760D01*
G01Y493823D02*
Y495666D01*
G01X1081839D02*
Y493823D01*
G01Y497760D02*
Y496168D01*
G01X1081346Y493823D02*
Y497760D01*
G01X1080717Y535791D02*
Y493075D01*
G01X1073384Y517822D02*
X1073712D01*
G01X1072072D02*
X1072400D01*
G01X1071251D02*
X1071661D01*
G01X1069693D02*
X1070021D01*
G01X1068381D02*
X1068709D01*
G01X1067560D02*
X1067970D01*
G01X1068545Y517487D02*
X1068381D01*
G01X1069857D02*
X1069611D01*
G01X1072236D02*
X1072072D01*
G01X1073548D02*
X1073302D01*
G01X1067970Y515142D02*
X1067560D01*
G01X1069283D02*
X1068873D01*
G01X1071661D02*
X1071251D01*
G01X1070595D02*
X1070185D01*
G01X1072974D02*
X1072564D01*
G01X1074286D02*
X1073876D01*
G01X1073712Y517822D02*
X1073958Y517738D01*
G01X1072400Y517822D02*
X1072646Y517738D01*
G01X1070021Y517822D02*
X1070267Y517738D01*
G01X1068709Y517822D02*
X1068955Y517738D01*
G01X1073712Y517403D02*
X1073548Y517487D01*
G01X1072400Y517403D02*
X1072236Y517487D01*
G01X1070021Y517403D02*
X1069857Y517487D01*
G01X1068709Y517403D02*
X1068545Y517487D01*
G01X1073958Y517738D02*
X1074122Y517571D01*
G01X1073794Y517320D02*
X1073712Y517403D01*
G01X1072646Y517738D02*
X1072892Y517487D01*
G01X1072482Y517320D02*
X1072400Y517403D01*
G01X1070267Y517738D02*
X1070431Y517571D01*
G01X1070103Y517320D02*
X1070021Y517403D01*
G01X1068955Y517738D02*
X1069201Y517487D01*
G01X1068791Y517320D02*
X1068709Y517403D01*
G01X1073138Y517738D02*
X1073384Y517822D01*
G01X1072072Y517487D02*
X1071825Y517403D01*
G01Y517738D02*
X1072072Y517822D01*
G01X1069447Y517738D02*
X1069693Y517822D01*
G01X1068381Y517487D02*
X1068135Y517403D01*
G01Y517738D02*
X1068381Y517822D01*
G01X1073302Y517487D02*
X1073138Y517403D01*
G01X1069611Y517487D02*
X1069447Y517403D01*
G01X1073876Y517152D02*
X1073794Y517320D01*
G01X1072564Y517152D02*
X1072482Y517320D01*
G01X1070185Y517152D02*
X1070103Y517320D01*
G01X1068873Y517152D02*
X1068791Y517320D01*
G01X1074122Y517571D02*
X1074286Y517152D01*
G01X1070431Y517571D02*
X1070595Y517152D01*
G01X1073138Y517403D02*
X1073056Y517320D01*
G01X1072892Y517487D02*
X1073138Y517738D01*
G01X1071825Y517403D02*
X1071661Y517236D01*
G01Y517571D02*
X1071825Y517738D01*
G01X1069447Y517403D02*
X1069365Y517320D01*
G01X1069201Y517487D02*
X1069447Y517738D01*
G01X1068135Y517403D02*
X1067970Y517236D01*
G01Y517571D02*
X1068135Y517738D01*
G01X1073056Y517320D02*
X1072974Y517152D01*
G01X1069365Y517320D02*
X1069283Y517152D01*
G01X1074286D02*
Y515142D01*
G01X1073876D02*
Y517152D01*
G01X1072974D02*
Y515142D01*
G01X1072564D02*
Y517152D01*
G01X1071661Y517236D02*
Y515142D01*
G01Y517822D02*
Y517571D01*
G01X1071251Y515142D02*
Y517822D01*
G01X1070595Y517152D02*
Y515142D01*
G01X1070185D02*
Y517152D01*
G01X1069283D02*
Y515142D01*
G01X1068873D02*
Y517152D01*
G01X1067970Y517236D02*
Y515142D01*
G01Y517822D02*
Y517571D01*
G01X1067560Y515142D02*
Y517822D01*
G01X1103579Y510197D02*
X1103578Y510571D01*
G01X1103581Y509887D02*
X1103579Y510197D01*
G01X1103585Y509680D02*
X1103581Y509887D01*
G01X1103589Y509606D02*
X1103585Y509680D01*
G01X1105098Y524181D02*
X1105099Y523807D01*
G01X1105096Y524491D02*
X1105098Y524181D01*
G01X1105092Y524698D02*
X1105096Y524491D01*
G01X1105088Y524772D02*
X1105092Y524698D01*
G01X1099389Y526485D02*
X1099383Y526538D01*
G01X1099395Y526353D02*
X1099389Y526485D01*
G01X1099401Y526147D02*
X1099395Y526353D01*
G01X1101414Y507893D02*
X1101421Y507840D01*
G01X1101408Y508025D02*
X1101414Y507893D01*
G01X1101403Y508231D02*
X1101408Y508025D01*
G01X1103321Y526485D02*
X1103315Y526538D01*
G01X1103327Y526353D02*
X1103321Y526485D01*
G01X1103333Y526147D02*
X1103327Y526353D01*
G01X1105356Y507893D02*
X1105362Y507840D01*
G01X1105350Y508025D02*
X1105356Y507893D01*
G01X1105344Y508231D02*
X1105350Y508025D01*
G01X1107263Y526485D02*
X1107257Y526538D01*
G01X1107269Y526353D02*
X1107263Y526485D01*
G01X1107275Y526147D02*
X1107269Y526353D01*
G01X1109288Y507893D02*
X1109295Y507840D01*
G01X1109282Y508025D02*
X1109288Y507893D01*
G01X1109277Y508231D02*
X1109282Y508025D01*
G01X1099387Y525511D02*
X1099383Y525553D01*
G01X1099392Y525413D02*
X1099387Y525511D01*
G01X1099396Y525261D02*
X1099392Y525413D01*
G01X1101416Y508867D02*
X1101421Y508825D01*
G01X1101412Y508965D02*
X1101416Y508867D01*
G01X1101407Y509117D02*
X1101412Y508965D01*
G01X1103320Y525511D02*
X1103315Y525553D01*
G01X1103324Y525413D02*
X1103320Y525511D01*
G01X1103328Y525261D02*
X1103324Y525413D01*
G01X1105358Y508867D02*
X1105362Y508825D01*
G01X1105353Y508965D02*
X1105358Y508867D01*
G01X1105349Y509117D02*
X1105353Y508965D01*
G01X1107261Y525511D02*
X1107257Y525553D01*
G01X1107266Y525413D02*
X1107261Y525511D01*
G01X1107270Y525261D02*
X1107266Y525413D01*
G01X1109290Y508867D02*
X1109295Y508825D01*
G01X1109286Y508965D02*
X1109290Y508867D01*
G01X1109281Y509117D02*
X1109286Y508965D01*
G01X1099644Y509645D02*
X1099649Y509615D01*
G01X1099640Y509841D02*
X1099644Y509645D01*
G01X1099637Y510169D02*
X1099640Y509841D01*
G01X1099636Y510571D02*
X1099637Y510169D01*
G01X1101159Y524733D02*
X1101154Y524763D01*
G01X1101163Y524537D02*
X1101159Y524733D01*
G01X1101166Y524209D02*
X1101163Y524537D01*
G01X1101167Y523807D02*
X1101166Y524209D01*
G01X1107518Y509645D02*
X1107523Y509615D01*
G01X1107514Y509841D02*
X1107518Y509645D01*
G01X1107511Y510169D02*
X1107514Y509841D01*
G01X1107510Y510571D02*
X1107511Y510169D01*
G01X1109033Y524733D02*
X1109028Y524763D01*
G01X1109037Y524537D02*
X1109033Y524733D01*
G01X1109040Y524209D02*
X1109037Y524537D01*
G01X1109041Y523807D02*
X1109040Y524209D01*
G01X1103580Y508770D02*
X1103589Y508621D01*
G01X1103573Y509184D02*
X1103580Y508770D01*
G01X1103569Y509804D02*
X1103573Y509184D01*
G01X1103567Y510552D02*
X1103569Y509804D01*
G01X1105097Y525608D02*
X1105088Y525757D01*
G01X1105104Y525193D02*
X1105097Y525608D01*
G01X1105108Y524573D02*
X1105104Y525193D01*
G01X1105110Y523826D02*
X1105108Y524573D01*
G01X1111454Y508770D02*
X1111463Y508621D01*
G01X1111447Y509184D02*
X1111454Y508770D01*
G01X1111443Y509804D02*
X1111447Y509184D01*
G01X1111441Y510552D02*
X1111443Y509804D01*
G01X1103585Y524698D02*
X1103589Y524772D01*
G01X1103581Y524491D02*
X1103585Y524698D01*
G01X1103579Y524181D02*
X1103581Y524491D01*
G01X1103578Y523807D02*
X1103579Y524181D01*
G01X1105092Y509680D02*
X1105088Y509606D01*
G01X1105096Y509887D02*
X1105092Y509680D01*
G01X1105098Y510197D02*
X1105096Y509887D01*
G01X1105099Y510571D02*
X1105098Y510197D01*
G01X1111459Y524698D02*
X1111463Y524772D01*
G01X1111455Y524491D02*
X1111459Y524698D01*
G01X1111453Y524181D02*
X1111455Y524491D01*
G01X1111452Y523807D02*
X1111453Y524181D01*
G01X1103569Y524573D02*
X1103567Y523826D01*
G01X1103573Y525193D02*
X1103569Y524573D01*
G01X1103580Y525608D02*
X1103573Y525193D01*
G01X1103589Y525757D02*
X1103580Y525608D01*
G01X1105108Y509804D02*
X1105110Y510552D01*
G01X1105104Y509184D02*
X1105108Y509804D01*
G01X1105097Y508770D02*
X1105104Y509184D01*
G01X1105088Y508621D02*
X1105097Y508770D01*
G01X1111443Y524573D02*
X1111441Y523826D01*
G01X1111447Y525193D02*
X1111443Y524573D01*
G01X1111454Y525608D02*
X1111447Y525193D01*
G01X1111463Y525757D02*
X1111454Y525608D01*
G01X1112982Y509804D02*
X1112984Y510552D01*
G01X1112978Y509184D02*
X1112982Y509804D01*
G01X1112971Y508770D02*
X1112978Y509184D01*
G01X1112962Y508621D02*
X1112971Y508770D01*
G01X1103589Y509607D02*
Y509606D01*
G01X1103590Y509610D02*
X1103589Y509607D01*
G01X1103591Y509617D02*
X1103590Y509610D01*
G01X1105088Y524771D02*
Y524772D01*
G01X1105087Y524768D02*
X1105088Y524771D01*
G01X1105087Y524761D02*
Y524768D01*
G01X1111463Y509607D02*
Y509606D01*
G01X1111464Y509610D02*
X1111463Y509607D01*
G01X1111465Y509617D02*
X1111464Y509610D01*
G01X1112962Y524771D02*
Y524772D01*
G01X1112961Y524768D02*
X1112962Y524771D01*
G01X1112961Y524761D02*
Y524768D01*
G01X1099382Y508965D02*
X1099386Y509117D01*
G01X1099378Y508867D02*
X1099382Y508965D01*
G01X1099373Y508825D02*
X1099378Y508867D01*
G01X1101421Y525413D02*
X1101417Y525261D01*
G01X1101425Y525511D02*
X1101421Y525413D01*
G01X1101430Y525553D02*
X1101425Y525511D01*
G01X1103324Y508965D02*
X1103328Y509117D01*
G01X1103320Y508867D02*
X1103324Y508965D01*
G01X1103315Y508825D02*
X1103320Y508867D01*
G01X1105353Y525413D02*
X1105349Y525261D01*
G01X1105358Y525511D02*
X1105353Y525413D01*
G01X1105362Y525553D02*
X1105358Y525511D01*
G01X1107256Y508965D02*
X1107261Y509117D01*
G01X1107252Y508867D02*
X1107256Y508965D01*
G01X1107247Y508825D02*
X1107252Y508867D01*
G01X1109295Y525413D02*
X1109291Y525261D01*
G01X1109299Y525511D02*
X1109295Y525413D01*
G01X1109304Y525553D02*
X1109299Y525511D01*
G01X1111198Y508965D02*
X1111202Y509117D01*
G01X1111194Y508867D02*
X1111198Y508965D01*
G01X1111189Y508825D02*
X1111194Y508867D01*
G01X1113227Y525413D02*
X1113223Y525261D01*
G01X1113232Y525511D02*
X1113227Y525413D01*
G01X1113236Y525553D02*
X1113232Y525511D01*
G01X1115130Y508965D02*
X1115135Y509117D01*
G01X1115126Y508867D02*
X1115130Y508965D01*
G01X1115121Y508825D02*
X1115126Y508867D01*
G01X1117169Y525413D02*
X1117165Y525261D01*
G01X1117173Y525511D02*
X1117169Y525413D01*
G01X1117178Y525553D02*
X1117173Y525511D01*
G01X1101418Y526353D02*
X1101412Y526147D01*
G01X1101424Y526485D02*
X1101418Y526353D01*
G01X1101430Y526538D02*
X1101424Y526485D01*
G01X1099386Y508025D02*
X1099391Y508231D01*
G01X1099379Y507893D02*
X1099386Y508025D01*
G01X1099373Y507840D02*
X1099379Y507893D01*
G01X1105350Y526353D02*
X1105344Y526147D01*
G01X1105356Y526485D02*
X1105350Y526353D01*
G01X1105362Y526538D02*
X1105356Y526485D01*
G01X1103327Y508025D02*
X1103333Y508231D01*
G01X1103321Y507893D02*
X1103327Y508025D01*
G01X1103315Y507840D02*
X1103321Y507893D01*
G01X1109292Y526353D02*
X1109286Y526147D01*
G01X1109298Y526485D02*
X1109292Y526353D01*
G01X1109304Y526538D02*
X1109298Y526485D01*
G01X1107260Y508025D02*
X1107265Y508231D01*
G01X1107253Y507893D02*
X1107260Y508025D01*
G01X1107247Y507840D02*
X1107253Y507893D01*
G01X1113224Y526353D02*
X1113218Y526147D01*
G01X1113230Y526485D02*
X1113224Y526353D01*
G01X1113236Y526538D02*
X1113230Y526485D01*
G01X1111201Y508025D02*
X1111207Y508231D01*
G01X1111195Y507893D02*
X1111201Y508025D01*
G01X1111189Y507840D02*
X1111195Y507893D01*
G01X1117166Y526353D02*
X1117160Y526147D01*
G01X1117172Y526485D02*
X1117166Y526353D01*
G01X1117178Y526538D02*
X1117172Y526485D01*
G01X1115134Y508025D02*
X1115139Y508231D01*
G01X1115127Y507893D02*
X1115134Y508025D01*
G01X1115121Y507840D02*
X1115127Y507893D01*
G01X1099647Y524209D02*
X1099646Y523807D01*
G01X1099649Y524537D02*
X1099647Y524209D01*
G01X1099653Y524733D02*
X1099649Y524537D01*
G01X1099658Y524763D02*
X1099653Y524733D01*
G01X1101157Y510169D02*
X1101158Y510571D01*
G01X1101154Y509841D02*
X1101157Y510169D01*
G01X1101150Y509645D02*
X1101154Y509841D01*
G01X1101145Y509615D02*
X1101150Y509645D01*
G01X1107521Y524209D02*
X1107520Y523807D01*
G01X1107523Y524537D02*
X1107521Y524209D01*
G01X1107527Y524733D02*
X1107523Y524537D01*
G01X1107532Y524763D02*
X1107527Y524733D01*
G01X1109031Y510169D02*
X1109032Y510571D01*
G01X1109028Y509841D02*
X1109031Y510169D01*
G01X1109024Y509645D02*
X1109028Y509841D01*
G01X1109019Y509615D02*
X1109024Y509645D01*
G01X1115395Y524209D02*
X1115394Y523807D01*
G01X1115397Y524537D02*
X1115395Y524209D01*
G01X1115401Y524733D02*
X1115397Y524537D01*
G01X1115406Y524763D02*
X1115401Y524733D01*
G01X1116905Y510169D02*
X1116906Y510571D01*
G01X1116902Y509841D02*
X1116905Y510169D01*
G01X1116898Y509645D02*
X1116902Y509841D01*
G01X1116893Y509615D02*
X1116898Y509645D01*
G01X1105087Y525754D02*
Y525751D01*
G01X1105088Y525756D02*
X1105087Y525754D01*
G01X1105088Y525757D02*
Y525756D01*
G01X1111453Y510197D02*
X1111452Y510571D01*
G01X1111455Y509887D02*
X1111453Y510197D01*
G01X1111459Y509680D02*
X1111455Y509887D01*
G01X1111463Y509606D02*
X1111459Y509680D01*
G01X1112972Y524181D02*
X1112973Y523807D01*
G01X1112970Y524491D02*
X1112972Y524181D01*
G01X1112967Y524698D02*
X1112970Y524491D01*
G01X1112962Y524772D02*
X1112967Y524698D01*
G01X1119327Y510197D02*
X1119326Y510571D01*
G01X1119329Y509887D02*
X1119327Y510197D01*
G01X1119333Y509680D02*
X1119329Y509887D01*
G01X1119337Y509606D02*
X1119333Y509680D01*
G01X1120846Y524181D02*
X1120847Y523807D01*
G01X1120844Y524491D02*
X1120846Y524181D01*
G01X1120841Y524698D02*
X1120844Y524491D01*
G01X1120836Y524772D02*
X1120841Y524698D01*
G01X1127201Y510197D02*
X1127200Y510571D01*
G01X1127203Y509887D02*
X1127201Y510197D01*
G01X1127207Y509680D02*
X1127203Y509887D01*
G01X1127211Y509606D02*
X1127207Y509680D01*
G01X1128720Y524181D02*
X1128721Y523807D01*
G01X1128718Y524491D02*
X1128720Y524181D01*
G01X1128715Y524698D02*
X1128718Y524491D01*
G01X1128710Y524772D02*
X1128715Y524698D01*
G01X1111195Y526485D02*
X1111189Y526538D01*
G01X1111201Y526353D02*
X1111195Y526485D01*
G01X1111207Y526147D02*
X1111201Y526353D01*
G01X1113230Y507893D02*
X1113236Y507840D01*
G01X1113224Y508025D02*
X1113230Y507893D01*
G01X1113218Y508231D02*
X1113224Y508025D01*
G01X1115137Y526485D02*
X1115131Y526538D01*
G01X1115143Y526353D02*
X1115137Y526485D01*
G01X1115149Y526147D02*
X1115143Y526353D01*
G01X1117162Y507893D02*
X1117169Y507840D01*
G01X1117156Y508025D02*
X1117162Y507893D01*
G01X1117151Y508231D02*
X1117156Y508025D01*
G01X1119069Y526485D02*
X1119063Y526538D01*
G01X1119075Y526353D02*
X1119069Y526485D01*
G01X1119081Y526147D02*
X1119075Y526353D01*
G01X1121104Y507893D02*
X1121110Y507840D01*
G01X1121098Y508025D02*
X1121104Y507893D01*
G01X1121092Y508231D02*
X1121098Y508025D01*
G01X1123011Y526485D02*
X1123005Y526538D01*
G01X1123017Y526353D02*
X1123011Y526485D01*
G01X1123023Y526147D02*
X1123017Y526353D01*
G01X1125036Y507893D02*
X1125043Y507840D01*
G01X1125030Y508025D02*
X1125036Y507893D01*
G01X1125025Y508231D02*
X1125030Y508025D01*
G01X1126943Y526485D02*
X1126937Y526538D01*
G01X1126949Y526353D02*
X1126943Y526485D01*
G01X1126955Y526147D02*
X1126949Y526353D01*
G01X1128978Y507893D02*
X1128984Y507840D01*
G01X1128972Y508025D02*
X1128978Y507893D01*
G01X1128966Y508231D02*
X1128972Y508025D01*
G01X1130885Y526485D02*
X1130879Y526538D01*
G01X1130891Y526353D02*
X1130885Y526485D01*
G01X1130897Y526147D02*
X1130891Y526353D01*
G01X1132910Y507893D02*
X1132917Y507840D01*
G01X1132904Y508025D02*
X1132910Y507893D01*
G01X1132899Y508231D02*
X1132904Y508025D01*
G01X1134817Y526485D02*
X1134811Y526538D01*
G01X1134823Y526353D02*
X1134817Y526485D01*
G01X1134829Y526147D02*
X1134823Y526353D01*
G01X1111194Y525511D02*
X1111189Y525553D01*
G01X1111198Y525413D02*
X1111194Y525511D01*
G01X1111202Y525261D02*
X1111198Y525413D01*
G01X1113232Y508867D02*
X1113236Y508825D01*
G01X1113227Y508965D02*
X1113232Y508867D01*
G01X1113223Y509117D02*
X1113227Y508965D01*
G01X1115135Y525511D02*
X1115131Y525553D01*
G01X1115140Y525413D02*
X1115135Y525511D01*
G01X1115144Y525261D02*
X1115140Y525413D01*
G01X1117164Y508867D02*
X1117169Y508825D01*
G01X1117160Y508965D02*
X1117164Y508867D01*
G01X1117155Y509117D02*
X1117160Y508965D01*
G01X1119068Y525511D02*
X1119063Y525553D01*
G01X1119072Y525413D02*
X1119068Y525511D01*
G01X1119076Y525261D02*
X1119072Y525413D01*
G01X1121106Y508867D02*
X1121110Y508825D01*
G01X1121101Y508965D02*
X1121106Y508867D01*
G01X1121097Y509117D02*
X1121101Y508965D01*
G01X1123009Y525511D02*
X1123005Y525553D01*
G01X1123014Y525413D02*
X1123009Y525511D01*
G01X1123018Y525261D02*
X1123014Y525413D01*
G01X1125038Y508867D02*
X1125043Y508825D01*
G01X1125034Y508965D02*
X1125038Y508867D01*
G01X1125029Y509117D02*
X1125034Y508965D01*
G01X1126942Y525511D02*
X1126937Y525553D01*
G01X1126946Y525413D02*
X1126942Y525511D01*
G01X1126950Y525261D02*
X1126946Y525413D01*
G01X1128980Y508867D02*
X1128984Y508825D01*
G01X1128975Y508965D02*
X1128980Y508867D01*
G01X1128971Y509117D02*
X1128975Y508965D01*
G01X1130883Y525511D02*
X1130879Y525553D01*
G01X1130888Y525413D02*
X1130883Y525511D01*
G01X1130892Y525261D02*
X1130888Y525413D01*
G01X1132912Y508867D02*
X1132917Y508825D01*
G01X1132908Y508965D02*
X1132912Y508867D01*
G01X1132903Y509117D02*
X1132908Y508965D01*
G01X1134816Y525511D02*
X1134811Y525553D01*
G01X1134820Y525413D02*
X1134816Y525511D01*
G01X1134824Y525261D02*
X1134820Y525413D01*
G01X1115392Y509645D02*
X1115397Y509615D01*
G01X1115388Y509841D02*
X1115392Y509645D01*
G01X1115385Y510169D02*
X1115388Y509841D01*
G01X1115384Y510571D02*
X1115385Y510169D01*
G01X1116907Y524733D02*
X1116902Y524763D01*
G01X1116911Y524537D02*
X1116907Y524733D01*
G01X1116914Y524209D02*
X1116911Y524537D01*
G01X1116915Y523807D02*
X1116914Y524209D01*
G01X1123266Y509645D02*
X1123271Y509615D01*
G01X1123262Y509841D02*
X1123266Y509645D01*
G01X1123259Y510169D02*
X1123262Y509841D01*
G01X1123258Y510571D02*
X1123259Y510169D01*
G01X1124781Y524733D02*
X1124777Y524763D01*
G01X1124785Y524537D02*
X1124781Y524733D01*
G01X1124788Y524209D02*
X1124785Y524537D01*
G01X1124789Y523807D02*
X1124788Y524209D01*
G01X1131140Y509645D02*
X1131145Y509615D01*
G01X1131136Y509841D02*
X1131140Y509645D01*
G01X1131133Y510169D02*
X1131136Y509841D01*
G01X1131132Y510571D02*
X1131133Y510169D01*
G01X1132655Y524733D02*
X1132651Y524763D01*
G01X1132659Y524537D02*
X1132655Y524733D01*
G01X1132662Y524209D02*
X1132659Y524537D01*
G01X1132663Y523807D02*
X1132662Y524209D01*
G01X1112971Y525608D02*
X1112962Y525757D01*
G01X1112978Y525193D02*
X1112971Y525608D01*
G01X1112982Y524573D02*
X1112978Y525193D01*
G01X1112984Y523826D02*
X1112982Y524573D01*
G01X1119329Y508770D02*
X1119337Y508621D01*
G01X1119322Y509184D02*
X1119329Y508770D01*
G01X1119317Y509804D02*
X1119322Y509184D01*
G01X1119315Y510552D02*
X1119317Y509804D01*
G01X1120845Y525608D02*
X1120836Y525757D01*
G01X1120852Y525193D02*
X1120845Y525608D01*
G01X1120856Y524573D02*
X1120852Y525193D01*
G01X1120858Y523826D02*
X1120856Y524573D01*
G01X1127203Y508770D02*
X1127211Y508621D01*
G01X1127196Y509184D02*
X1127203Y508770D01*
G01X1127191Y509804D02*
X1127196Y509184D01*
G01X1127189Y510552D02*
X1127191Y509804D01*
G01X1128719Y525608D02*
X1128710Y525757D01*
G01X1128726Y525193D02*
X1128719Y525608D01*
G01X1128730Y524573D02*
X1128726Y525193D01*
G01X1128732Y523826D02*
X1128730Y524573D01*
G01X1135077Y508770D02*
X1135085Y508621D01*
G01X1135070Y509184D02*
X1135077Y508770D01*
G01X1135065Y509804D02*
X1135070Y509184D01*
G01X1135063Y510552D02*
X1135065Y509804D01*
G01X1136593Y525608D02*
X1136584Y525757D01*
G01X1136600Y525193D02*
X1136593Y525608D01*
G01X1136604Y524573D02*
X1136600Y525193D01*
G01X1136606Y523826D02*
X1136604Y524573D01*
G01X1112967Y509680D02*
X1112962Y509606D01*
G01X1112970Y509887D02*
X1112967Y509680D01*
G01X1112972Y510197D02*
X1112970Y509887D01*
G01X1112973Y510571D02*
X1112972Y510197D01*
G01X1119333Y524698D02*
X1119337Y524772D01*
G01X1119329Y524491D02*
X1119333Y524698D01*
G01X1119327Y524181D02*
X1119329Y524491D01*
G01X1119326Y523807D02*
X1119327Y524181D01*
G01X1120841Y509680D02*
X1120836Y509606D01*
G01X1120844Y509887D02*
X1120841Y509680D01*
G01X1120846Y510197D02*
X1120844Y509887D01*
G01X1120847Y510571D02*
X1120846Y510197D01*
G01X1127207Y524698D02*
X1127211Y524772D01*
G01X1127203Y524491D02*
X1127207Y524698D01*
G01X1127201Y524181D02*
X1127203Y524491D01*
G01X1127200Y523807D02*
X1127201Y524181D01*
G01X1128715Y509680D02*
X1128710Y509606D01*
G01X1128718Y509887D02*
X1128715Y509680D01*
G01X1128720Y510197D02*
X1128718Y509887D01*
G01X1128721Y510571D02*
X1128720Y510197D01*
G01X1135081Y524698D02*
X1135085Y524772D01*
G01X1135077Y524491D02*
X1135081Y524698D01*
G01X1135075Y524181D02*
X1135077Y524491D01*
G01X1135074Y523807D02*
X1135075Y524181D01*
G01X1136589Y509680D02*
X1136584Y509606D01*
G01X1136592Y509887D02*
X1136589Y509680D01*
G01X1136594Y510197D02*
X1136592Y509887D01*
G01X1136595Y510571D02*
X1136594Y510197D01*
G01X1119317Y524573D02*
X1119315Y523826D01*
G01X1119322Y525193D02*
X1119317Y524573D01*
G01X1119329Y525608D02*
X1119322Y525193D01*
G01X1119337Y525757D02*
X1119329Y525608D01*
G01X1120856Y509804D02*
X1120858Y510552D01*
G01X1120852Y509184D02*
X1120856Y509804D01*
G01X1120845Y508770D02*
X1120852Y509184D01*
G01X1120836Y508621D02*
X1120845Y508770D01*
G01X1127191Y524573D02*
X1127189Y523826D01*
G01X1127196Y525193D02*
X1127191Y524573D01*
G01X1127203Y525608D02*
X1127196Y525193D01*
G01X1127211Y525757D02*
X1127203Y525608D01*
G01X1128730Y509804D02*
X1128732Y510552D01*
G01X1128726Y509184D02*
X1128730Y509804D01*
G01X1128719Y508770D02*
X1128726Y509184D01*
G01X1128710Y508621D02*
X1128719Y508770D01*
G01X1135065Y524573D02*
X1135063Y523826D01*
G01X1135070Y525193D02*
X1135065Y524573D01*
G01X1135077Y525608D02*
X1135070Y525193D01*
G01X1135085Y525757D02*
X1135077Y525608D01*
G01X1136604Y509804D02*
X1136606Y510552D01*
G01X1136600Y509184D02*
X1136604Y509804D01*
G01X1136593Y508770D02*
X1136600Y509184D01*
G01X1136584Y508621D02*
X1136593Y508770D01*
G01X1119337Y509607D02*
Y509606D01*
G01X1119338Y509610D02*
X1119337Y509607D01*
G01X1119339Y509617D02*
X1119338Y509610D01*
G01X1120836Y524771D02*
Y524772D01*
G01X1120835Y524768D02*
X1120836Y524771D01*
G01X1120835Y524761D02*
Y524768D01*
G01X1127211Y509607D02*
Y509606D01*
G01X1127212Y509610D02*
X1127211Y509607D01*
G01X1127213Y509617D02*
X1127212Y509610D01*
G01X1128710Y524771D02*
Y524772D01*
G01X1128709Y524768D02*
X1128710Y524771D01*
G01X1128709Y524761D02*
Y524768D01*
G01X1135085Y509607D02*
Y509606D01*
G01X1135086Y509610D02*
X1135085Y509607D01*
G01X1135087Y509617D02*
X1135086Y509610D01*
G01X1136584Y524771D02*
Y524772D01*
G01X1136583Y524768D02*
X1136584Y524771D01*
G01X1136583Y524761D02*
Y524768D01*
G01X1119072Y508965D02*
X1119076Y509117D01*
G01X1119068Y508867D02*
X1119072Y508965D01*
G01X1119063Y508825D02*
X1119068Y508867D01*
G01X1121101Y525413D02*
X1121097Y525261D01*
G01X1121106Y525511D02*
X1121101Y525413D01*
G01X1121110Y525553D02*
X1121106Y525511D01*
G01X1123004Y508965D02*
X1123009Y509117D01*
G01X1123000Y508867D02*
X1123004Y508965D01*
G01X1122995Y508825D02*
X1123000Y508867D01*
G01X1125043Y525413D02*
X1125039Y525261D01*
G01X1125047Y525511D02*
X1125043Y525413D01*
G01X1125052Y525553D02*
X1125047Y525511D01*
G01X1126946Y508965D02*
X1126950Y509117D01*
G01X1126942Y508867D02*
X1126946Y508965D01*
G01X1126937Y508825D02*
X1126942Y508867D01*
G01X1128975Y525413D02*
X1128971Y525261D01*
G01X1128980Y525511D02*
X1128975Y525413D01*
G01X1128984Y525553D02*
X1128980Y525511D01*
G01X1130878Y508965D02*
X1130883Y509117D01*
G01X1130874Y508867D02*
X1130878Y508965D01*
G01X1130869Y508825D02*
X1130874Y508867D01*
G01X1132917Y525413D02*
X1132913Y525261D01*
G01X1132921Y525511D02*
X1132917Y525413D01*
G01X1132926Y525553D02*
X1132921Y525511D01*
G01X1134820Y508965D02*
X1134824Y509117D01*
G01X1134816Y508867D02*
X1134820Y508965D01*
G01X1134811Y508825D02*
X1134816Y508867D01*
G01X1136849Y525413D02*
X1136845Y525261D01*
G01X1136854Y525511D02*
X1136849Y525413D01*
G01X1136858Y525553D02*
X1136854Y525511D01*
G01X1138752Y508965D02*
X1138757Y509117D01*
G01X1138748Y508867D02*
X1138752Y508965D01*
G01X1138743Y508825D02*
X1138748Y508867D01*
G01X1140791Y525413D02*
X1140787Y525261D01*
G01X1140795Y525511D02*
X1140791Y525413D01*
G01X1140800Y525553D02*
X1140795Y525511D01*
G01X1121098Y526353D02*
X1121092Y526147D01*
G01X1121104Y526485D02*
X1121098Y526353D01*
G01X1121110Y526538D02*
X1121104Y526485D01*
G01X1119075Y508025D02*
X1119081Y508231D01*
G01X1119069Y507893D02*
X1119075Y508025D01*
G01X1119063Y507840D02*
X1119069Y507893D01*
G01X1125040Y526353D02*
X1125034Y526147D01*
G01X1125046Y526485D02*
X1125040Y526353D01*
G01X1125052Y526538D02*
X1125046Y526485D01*
G01X1123008Y508025D02*
X1123013Y508231D01*
G01X1123002Y507893D02*
X1123008Y508025D01*
G01X1122995Y507840D02*
X1123002Y507893D01*
G01X1128972Y526353D02*
X1128966Y526147D01*
G01X1128978Y526485D02*
X1128972Y526353D01*
G01X1128984Y526538D02*
X1128978Y526485D01*
G01X1126949Y508025D02*
X1126955Y508231D01*
G01X1126943Y507893D02*
X1126949Y508025D01*
G01X1126937Y507840D02*
X1126943Y507893D01*
G01X1132914Y526353D02*
X1132908Y526147D01*
G01X1132920Y526485D02*
X1132914Y526353D01*
G01X1132926Y526538D02*
X1132920Y526485D01*
G01X1130882Y508025D02*
X1130887Y508231D01*
G01X1130876Y507893D02*
X1130882Y508025D01*
G01X1130869Y507840D02*
X1130876Y507893D01*
G01X1136846Y526353D02*
X1136840Y526147D01*
G01X1136852Y526485D02*
X1136846Y526353D01*
G01X1136858Y526538D02*
X1136852Y526485D01*
G01X1134823Y508025D02*
X1134829Y508231D01*
G01X1134817Y507893D02*
X1134823Y508025D01*
G01X1134811Y507840D02*
X1134817Y507893D01*
G01X1140788Y526353D02*
X1140782Y526147D01*
G01X1140794Y526485D02*
X1140788Y526353D01*
G01X1140800Y526538D02*
X1140794Y526485D01*
G01X1138756Y508025D02*
X1138761Y508231D01*
G01X1138750Y507893D02*
X1138756Y508025D01*
G01X1138743Y507840D02*
X1138750Y507893D01*
G01X1123269Y524209D02*
X1123268Y523807D01*
G01X1123271Y524537D02*
X1123269Y524209D01*
G01X1123275Y524733D02*
X1123271Y524537D01*
G01X1123280Y524763D02*
X1123275Y524733D01*
G01X1124779Y510169D02*
X1124780Y510571D01*
G01X1124776Y509841D02*
X1124779Y510169D01*
G01X1124772Y509645D02*
X1124776Y509841D01*
G01X1124767Y509615D02*
X1124772Y509645D01*
G01X1131143Y524209D02*
X1131142Y523807D01*
G01X1131145Y524537D02*
X1131143Y524209D01*
G01X1131150Y524733D02*
X1131145Y524537D01*
G01X1131154Y524763D02*
X1131150Y524733D01*
G01X1132653Y510169D02*
X1132654Y510571D01*
G01X1132650Y509841D02*
X1132653Y510169D01*
G01X1132646Y509645D02*
X1132650Y509841D01*
G01X1132641Y509615D02*
X1132646Y509645D01*
G01X1139017Y524209D02*
X1139016Y523807D01*
G01X1139019Y524537D02*
X1139017Y524209D01*
G01X1139024Y524733D02*
X1139019Y524537D01*
G01X1139028Y524763D02*
X1139024Y524733D01*
G01X1140527Y510169D02*
X1140528Y510571D01*
G01X1140524Y509841D02*
X1140527Y510169D01*
G01X1140520Y509645D02*
X1140524Y509841D01*
G01X1140515Y509615D02*
X1140520Y509645D01*
G01X1112961Y525754D02*
Y525751D01*
G01X1112962Y525756D02*
X1112961Y525754D01*
G01X1112962Y525757D02*
Y525756D01*
G01X1103590Y508624D02*
X1103591Y508627D01*
G01X1103589Y508622D02*
X1103590Y508624D01*
G01X1103589Y508621D02*
Y508622D01*
G01X1120835Y525754D02*
Y525751D01*
G01X1120836Y525756D02*
X1120835Y525754D01*
G01X1120836Y525757D02*
Y525756D01*
G01X1111464Y508624D02*
X1111465Y508627D01*
G01X1111463Y508622D02*
X1111464Y508624D01*
G01X1111463Y508621D02*
Y508622D01*
G01X1128709Y525754D02*
Y525751D01*
G01X1128710Y525756D02*
X1128709Y525754D01*
G01X1128710Y525757D02*
Y525756D01*
G01X1119338Y508624D02*
X1119339Y508627D01*
G01X1119337Y508622D02*
X1119338Y508624D01*
G01X1119337Y508621D02*
Y508622D01*
G01X1136583Y525754D02*
Y525751D01*
G01X1136584Y525756D02*
X1136583Y525754D01*
G01X1136584Y525757D02*
Y525756D01*
G01X1105088Y508622D02*
Y508621D01*
G01X1105087Y508624D02*
X1105088Y508622D01*
G01X1105087Y508627D02*
Y508624D01*
G01X1103589Y525756D02*
Y525757D01*
G01X1103590Y525754D02*
X1103589Y525756D01*
G01X1103591Y525751D02*
X1103590Y525754D01*
G01X1112962Y508622D02*
Y508621D01*
G01X1112961Y508624D02*
X1112962Y508622D01*
G01X1112961Y508627D02*
Y508624D01*
G01X1111463Y525756D02*
Y525757D01*
G01X1111464Y525754D02*
X1111463Y525756D01*
G01X1111465Y525751D02*
X1111464Y525754D01*
G01X1120836Y508622D02*
Y508621D01*
G01X1120835Y508624D02*
X1120836Y508622D01*
G01X1120835Y508627D02*
Y508624D01*
G01X1119337Y525756D02*
Y525757D01*
G01X1119338Y525754D02*
X1119337Y525756D01*
G01X1119339Y525751D02*
X1119338Y525754D01*
G01X1135075Y510197D02*
X1135074Y510571D01*
G01X1135077Y509887D02*
X1135075Y510197D01*
G01X1135081Y509680D02*
X1135077Y509887D01*
G01X1135085Y509606D02*
X1135081Y509680D01*
G01X1136594Y524181D02*
X1136595Y523807D01*
G01X1136592Y524491D02*
X1136594Y524181D01*
G01X1136589Y524698D02*
X1136592Y524491D01*
G01X1136584Y524772D02*
X1136589Y524698D01*
G01X1136852Y507893D02*
X1136858Y507840D01*
G01X1136846Y508025D02*
X1136852Y507893D01*
G01X1136840Y508231D02*
X1136846Y508025D01*
G01X1138759Y526485D02*
X1138753Y526538D01*
G01X1138765Y526353D02*
X1138759Y526485D01*
G01X1138771Y526147D02*
X1138765Y526353D01*
G01X1140784Y507893D02*
X1140791Y507840D01*
G01X1140778Y508025D02*
X1140784Y507893D01*
G01X1140773Y508231D02*
X1140778Y508025D01*
G01X1136854Y508867D02*
X1136858Y508825D01*
G01X1136849Y508965D02*
X1136854Y508867D01*
G01X1136845Y509117D02*
X1136849Y508965D01*
G01X1138757Y525511D02*
X1138753Y525553D01*
G01X1138762Y525413D02*
X1138757Y525511D01*
G01X1138766Y525261D02*
X1138762Y525413D01*
G01X1140786Y508867D02*
X1140791Y508825D01*
G01X1140782Y508965D02*
X1140786Y508867D01*
G01X1140777Y509117D02*
X1140782Y508965D01*
G01X1139014Y509645D02*
X1139019Y509615D01*
G01X1139010Y509841D02*
X1139014Y509645D01*
G01X1139007Y510169D02*
X1139010Y509841D01*
G01X1139006Y510571D02*
X1139007Y510169D01*
G01X1140529Y524733D02*
X1140525Y524763D01*
G01X1140533Y524537D02*
X1140529Y524733D01*
G01X1140536Y524209D02*
X1140533Y524537D01*
G01X1140537Y523807D02*
X1140536Y524209D01*
G01X1127212Y508624D02*
X1127213Y508627D01*
G01X1127211Y508622D02*
X1127212Y508624D01*
G01X1127211Y508621D02*
Y508622D01*
G01X1135086Y508624D02*
X1135087Y508627D01*
G01X1135085Y508622D02*
X1135086Y508624D01*
G01X1135085Y508621D02*
Y508622D01*
G01X1105087Y509610D02*
Y509617D01*
G01X1105088Y509607D02*
X1105087Y509610D01*
G01X1105088Y509606D02*
Y509607D01*
G01X1103590Y524768D02*
X1103591Y524761D01*
G01X1103589Y524771D02*
X1103590Y524768D01*
G01X1103589Y524772D02*
Y524771D01*
G01X1112961Y509610D02*
Y509617D01*
G01X1112962Y509607D02*
X1112961Y509610D01*
G01X1112962Y509606D02*
Y509607D01*
G01X1111464Y524768D02*
X1111465Y524761D01*
G01X1111463Y524771D02*
X1111464Y524768D01*
G01X1111463Y524772D02*
Y524771D01*
G01X1120835Y509610D02*
Y509617D01*
G01X1120836Y509607D02*
X1120835Y509610D01*
G01X1120836Y509606D02*
Y509607D01*
G01X1128710Y508622D02*
Y508621D01*
G01X1128709Y508624D02*
X1128710Y508622D01*
G01X1128709Y508627D02*
Y508624D01*
G01X1127211Y525756D02*
Y525757D01*
G01X1127212Y525754D02*
X1127211Y525756D01*
G01X1127213Y525751D02*
X1127212Y525754D01*
G01X1136584Y508622D02*
Y508621D01*
G01X1136583Y508624D02*
X1136584Y508622D01*
G01X1136583Y508627D02*
Y508624D01*
G01X1135085Y525756D02*
Y525757D01*
G01X1135086Y525754D02*
X1135085Y525756D01*
G01X1135087Y525751D02*
X1135086Y525754D01*
G01X1119338Y524768D02*
X1119339Y524761D01*
G01X1119337Y524771D02*
X1119338Y524768D01*
G01X1119337Y524772D02*
Y524771D01*
G01X1128709Y509610D02*
Y509617D01*
G01X1128710Y509607D02*
X1128709Y509610D01*
G01X1128710Y509606D02*
Y509607D01*
G01X1127212Y524768D02*
X1127213Y524761D01*
G01X1127211Y524771D02*
X1127212Y524768D01*
G01X1127211Y524772D02*
Y524771D01*
G01X1136583Y509610D02*
Y509617D01*
G01X1136584Y509607D02*
X1136583Y509610D01*
G01X1136584Y509606D02*
Y509607D01*
G01X1135086Y524768D02*
X1135087Y524761D01*
G01X1135085Y524771D02*
X1135086Y524768D01*
G01X1135085Y524772D02*
Y524771D01*
G01X1145457Y510714D02*
X1145677Y510693D01*
G01X1145234Y510771D02*
X1145457Y510714D01*
G01X1145014Y510864D02*
X1145234Y510771D01*
G01X1144800Y510998D02*
X1145014Y510864D01*
G01X1144599Y511177D02*
X1144800Y510998D01*
G01X1144420Y511402D02*
X1144599Y511177D01*
G01X1145897Y523663D02*
X1145677Y523685D01*
G01X1146120Y523607D02*
X1145897Y523663D01*
G01X1146340Y523514D02*
X1146120Y523607D01*
G01X1146554Y523380D02*
X1146340Y523514D01*
G01X1146755Y523201D02*
X1146554Y523380D01*
G01X1146935Y522976D02*
X1146755Y523201D01*
G01X1101436Y507839D02*
X1101421Y507840D01*
G01X1101451Y507839D02*
X1101436D01*
G01X1101466D02*
X1101451D01*
G01X1105377D02*
X1105362Y507840D01*
G01X1105392Y507839D02*
X1105377D01*
G01X1105407D02*
X1105392D01*
G01X1109310D02*
X1109295Y507840D01*
G01X1109325Y507839D02*
X1109310D01*
G01X1109340D02*
X1109325D01*
G01X1113251D02*
X1113236Y507840D01*
G01X1113266Y507839D02*
X1113251D01*
G01X1113281D02*
X1113266D01*
G01X1117184D02*
X1117169Y507840D01*
G01X1117199Y507839D02*
X1117184D01*
G01X1117214D02*
X1117199D01*
G01X1121125D02*
X1121110Y507840D01*
G01X1121140Y507839D02*
X1121125D01*
G01X1121155D02*
X1121140D01*
G01X1125058D02*
X1125043Y507840D01*
G01X1125073Y507839D02*
X1125058D01*
G01X1125088D02*
X1125073D01*
G01X1128999D02*
X1128984Y507840D01*
G01X1129014Y507839D02*
X1128999D01*
G01X1129029D02*
X1129014D01*
G01X1132932D02*
X1132917Y507840D01*
G01X1132947Y507839D02*
X1132932D01*
G01X1132962D02*
X1132947D01*
G01X1136873D02*
X1136858Y507840D01*
G01X1136888Y507839D02*
X1136873D01*
G01X1136903D02*
X1136888D01*
G01X1140806D02*
X1140791Y507840D01*
G01X1140821Y507839D02*
X1140806D01*
G01X1140836D02*
X1140821D01*
G01X1101436Y508824D02*
X1101421Y508825D01*
G01X1101451Y508823D02*
X1101436Y508824D01*
G01X1101466Y508823D02*
X1101451D01*
G01X1105377Y508824D02*
X1105362Y508825D01*
G01X1105392Y508823D02*
X1105377Y508824D01*
G01X1105407Y508823D02*
X1105392D01*
G01X1113251Y508824D02*
X1113236Y508825D01*
G01X1113266Y508823D02*
X1113251Y508824D01*
G01X1113281Y508823D02*
X1113266D01*
G01X1121125Y508824D02*
X1121110Y508825D01*
G01X1121140Y508823D02*
X1121125Y508824D01*
G01X1121155Y508823D02*
X1121140D01*
G01X1125058Y508824D02*
X1125043Y508825D01*
G01X1125073Y508823D02*
X1125058Y508824D01*
G01X1125088Y508823D02*
X1125073D01*
G01X1128999Y508824D02*
X1128984Y508825D01*
G01X1129014Y508823D02*
X1128999Y508824D01*
G01X1129029Y508823D02*
X1129014D01*
G01X1132932Y508824D02*
X1132917Y508825D01*
G01X1132947Y508823D02*
X1132932Y508824D01*
G01X1132962Y508823D02*
X1132947D01*
G01X1136873Y508824D02*
X1136858Y508825D01*
G01X1136888Y508823D02*
X1136873Y508824D01*
G01X1136903Y508823D02*
X1136888D01*
G01X1140806Y508824D02*
X1140791Y508825D01*
G01X1140821Y508823D02*
X1140806Y508824D01*
G01X1140836Y508823D02*
X1140821D01*
G01X1109325D02*
X1109340D01*
G01X1109310Y508824D02*
X1109325Y508823D01*
G01X1109295Y508825D02*
X1109310Y508824D01*
G01X1117199Y508823D02*
X1117214D01*
G01X1117184Y508824D02*
X1117199Y508823D01*
G01X1117169Y508825D02*
X1117184Y508824D01*
G01X1146755Y511177D02*
X1146935Y511402D01*
G01X1146555Y510999D02*
X1146755Y511177D01*
G01X1146341Y510864D02*
X1146555Y510999D01*
G01X1146121Y510771D02*
X1146341Y510864D01*
G01X1145898Y510714D02*
X1146121Y510771D01*
G01X1145677Y510693D02*
X1145898Y510714D01*
G01X1134781Y508823D02*
X1134766D01*
G01X1134796Y508824D02*
X1134781Y508823D01*
G01X1134811Y508825D02*
X1134796Y508824D01*
G01X1126907Y508823D02*
X1126892D01*
G01X1126922Y508824D02*
X1126907Y508823D01*
G01X1126937Y508825D02*
X1126922Y508824D01*
G01X1119033Y508823D02*
X1119018D01*
G01X1119048Y508824D02*
X1119033Y508823D01*
G01X1119063Y508825D02*
X1119048Y508824D01*
G01X1111159Y508823D02*
X1111144D01*
G01X1111174Y508824D02*
X1111159Y508823D01*
G01X1111189Y508825D02*
X1111174Y508824D01*
G01X1103285Y508823D02*
X1103270D01*
G01X1103300Y508824D02*
X1103285Y508823D01*
G01X1103315Y508825D02*
X1103300Y508824D01*
G01X1138713Y507839D02*
X1138698D01*
G01X1138728D02*
X1138713D01*
G01X1138743Y507840D02*
X1138728Y507839D01*
G01X1130839D02*
X1130824D01*
G01X1130854D02*
X1130839D01*
G01X1130869Y507840D02*
X1130854Y507839D01*
G01X1122965D02*
X1122950D01*
G01X1122980D02*
X1122965D01*
G01X1122995Y507840D02*
X1122980Y507839D01*
G01X1115091D02*
X1115076D01*
G01X1115106D02*
X1115091D01*
G01X1115121Y507840D02*
X1115106Y507839D01*
G01X1107217D02*
X1107202D01*
G01X1107232D02*
X1107217D01*
G01X1107247Y507840D02*
X1107232Y507839D01*
G01X1099343D02*
X1099328D01*
G01X1099358D02*
X1099343D01*
G01X1099373Y507840D02*
X1099358Y507839D01*
G01X1140830Y526539D02*
X1140845D01*
G01X1140815D02*
X1140830D01*
G01X1140800Y526538D02*
X1140815Y526539D01*
G01X1132956D02*
X1132971D01*
G01X1132941D02*
X1132956D01*
G01X1132926Y526538D02*
X1132941Y526539D01*
G01X1125082D02*
X1125097D01*
G01X1125067D02*
X1125082D01*
G01X1125052Y526538D02*
X1125067Y526539D01*
G01X1099368D02*
X1099383Y526538D01*
G01X1099353Y526539D02*
X1099368D01*
G01X1099338D02*
X1099353D01*
G01X1103300D02*
X1103315Y526538D01*
G01X1103285Y526539D02*
X1103300D01*
G01X1103270D02*
X1103285D01*
G01X1107242D02*
X1107257Y526538D01*
G01X1107227Y526539D02*
X1107242D01*
G01X1107212D02*
X1107227D01*
G01X1111174D02*
X1111189Y526538D01*
G01X1111159Y526539D02*
X1111174D01*
G01X1111144D02*
X1111159D01*
G01X1115116D02*
X1115131Y526538D01*
G01X1115101Y526539D02*
X1115116D01*
G01X1115086D02*
X1115101D01*
G01X1119048D02*
X1119063Y526538D01*
G01X1119033Y526539D02*
X1119048D01*
G01X1119018D02*
X1119033D01*
G01X1122990D02*
X1123005Y526538D01*
G01X1122975Y526539D02*
X1122990D01*
G01X1122960D02*
X1122975D01*
G01X1126922D02*
X1126937Y526538D01*
G01X1126907Y526539D02*
X1126922D01*
G01X1126892D02*
X1126907D01*
G01X1130864D02*
X1130879Y526538D01*
G01X1130849Y526539D02*
X1130864D01*
G01X1130834D02*
X1130849D01*
G01X1134796D02*
X1134811Y526538D01*
G01X1134781Y526539D02*
X1134796D01*
G01X1134766D02*
X1134781D01*
G01X1138738D02*
X1138753Y526538D01*
G01X1138723Y526539D02*
X1138738D01*
G01X1138708D02*
X1138723D01*
G01X1103300Y525554D02*
X1103315Y525553D01*
G01X1103285Y525555D02*
X1103300Y525554D01*
G01X1103270Y525555D02*
X1103285D01*
G01X1107242Y525554D02*
X1107257Y525553D01*
G01X1107227Y525555D02*
X1107242Y525554D01*
G01X1107212Y525555D02*
X1107227D01*
G01X1111174Y525554D02*
X1111189Y525553D01*
G01X1111159Y525555D02*
X1111174Y525554D01*
G01X1111144Y525555D02*
X1111159D01*
G01X1115116Y525554D02*
X1115131Y525553D01*
G01X1115101Y525555D02*
X1115116Y525554D01*
G01X1115086Y525555D02*
X1115101D01*
G01X1119048Y525554D02*
X1119063Y525553D01*
G01X1119033Y525555D02*
X1119048Y525554D01*
G01X1119018Y525555D02*
X1119033D01*
G01X1126922Y525554D02*
X1126937Y525553D01*
G01X1126907Y525555D02*
X1126922Y525554D01*
G01X1126892Y525555D02*
X1126907D01*
G01X1134796Y525554D02*
X1134811Y525553D01*
G01X1134781Y525555D02*
X1134796Y525554D01*
G01X1134766Y525555D02*
X1134781D01*
G01X1099353D02*
X1099338D01*
G01X1099368Y525554D02*
X1099353Y525555D01*
G01X1099383Y525553D02*
X1099368Y525554D01*
G01X1122975Y525555D02*
X1122960D01*
G01X1122990Y525554D02*
X1122975Y525555D01*
G01X1123005Y525553D02*
X1122990Y525554D01*
G01X1130849Y525555D02*
X1130834D01*
G01X1130864Y525554D02*
X1130849Y525555D01*
G01X1130879Y525553D02*
X1130864Y525554D01*
G01X1138723Y525555D02*
X1138708D01*
G01X1138738Y525554D02*
X1138723Y525555D01*
G01X1138753Y525553D02*
X1138738Y525554D01*
G01X1144599Y523201D02*
X1144420Y522976D01*
G01X1144800Y523379D02*
X1144599Y523201D01*
G01X1145014Y523514D02*
X1144800Y523379D01*
G01X1145234Y523607D02*
X1145014Y523514D01*
G01X1145457Y523663D02*
X1145234Y523607D01*
G01X1145677Y523685D02*
X1145457Y523663D01*
G01X1140830Y525555D02*
X1140845D01*
G01X1140815Y525554D02*
X1140830Y525555D01*
G01X1140800Y525553D02*
X1140815Y525554D01*
G01X1136888Y525555D02*
X1136903D01*
G01X1136873Y525554D02*
X1136888Y525555D01*
G01X1136858Y525553D02*
X1136873Y525554D01*
G01X1132956Y525555D02*
X1132971D01*
G01X1132941Y525554D02*
X1132956Y525555D01*
G01X1132926Y525553D02*
X1132941Y525554D01*
G01X1129014Y525555D02*
X1129029D01*
G01X1128999Y525554D02*
X1129014Y525555D01*
G01X1128984Y525553D02*
X1128999Y525554D01*
G01X1125082Y525555D02*
X1125097D01*
G01X1125067Y525554D02*
X1125082Y525555D01*
G01X1125052Y525553D02*
X1125067Y525554D01*
G01X1121140Y525555D02*
X1121155D01*
G01X1121125Y525554D02*
X1121140Y525555D01*
G01X1121110Y525553D02*
X1121125Y525554D01*
G01X1117208Y525555D02*
X1117223D01*
G01X1117193Y525554D02*
X1117208Y525555D01*
G01X1117178Y525553D02*
X1117193Y525554D01*
G01X1113266Y525555D02*
X1113281D01*
G01X1113251Y525554D02*
X1113266Y525555D01*
G01X1113236Y525553D02*
X1113251Y525554D01*
G01X1109334Y525555D02*
X1109349D01*
G01X1109319Y525554D02*
X1109334Y525555D01*
G01X1109304Y525553D02*
X1109319Y525554D01*
G01X1105392Y525555D02*
X1105407D01*
G01X1105377Y525554D02*
X1105392Y525555D01*
G01X1105362Y525553D02*
X1105377Y525554D01*
G01X1101460Y525555D02*
X1101475D01*
G01X1101445Y525554D02*
X1101460Y525555D01*
G01X1101430Y525553D02*
X1101445Y525554D01*
G01X1101460Y526539D02*
X1101475D01*
G01X1101445D02*
X1101460D01*
G01X1101430Y526538D02*
X1101445Y526539D01*
G01X1148020Y519783D02*
G03Y514595I-1752J-2594D01*
G01X1149122Y520314D02*
G03Y514064I-2854J-3125D01*
G01X1150894Y517189D02*
G03I-4626J0D01*
G01X1093020Y537189D02*
X1093512D01*
G01X1089903D02*
X1090559D01*
G01X1446858Y535791D02*
X1080717D01*
G01X1090969Y534592D02*
X1089493D01*
G01X1091051Y534257D02*
X1089411D01*
G01X1089083Y533252D02*
X1088591D01*
G01X1091871D02*
X1091379D01*
G01X1093512D02*
X1093020D01*
G01X1438984Y531854D02*
X1088591D01*
G01X1101583Y530476D02*
X1099220D01*
G01X1105520D02*
X1103157D01*
G01X1109457D02*
X1107094D01*
G01X1113394D02*
X1111031D01*
G01X1117331D02*
X1114968D01*
G01X1121268D02*
X1118906D01*
G01X1125205D02*
X1122843D01*
G01X1129142D02*
X1126780D01*
G01X1133079D02*
X1130717D01*
G01X1137016D02*
X1134654D01*
G01X1140953D02*
X1138591D01*
G01X1105008Y529492D02*
X1103669D01*
G01X1112882D02*
X1111543D01*
G01X1120756D02*
X1119417D01*
G01X1128630D02*
X1127291D01*
G01X1136504D02*
X1135165D01*
G01X1148177D02*
X1143177D01*
G01X1135008Y529394D02*
X1136661D01*
G01X1127134D02*
X1128787D01*
G01X1119260D02*
X1120913D01*
G01X1111386D02*
X1113039D01*
G01X1103512D02*
X1105165D01*
G01X1094240Y529295D02*
X1089516D01*
G01X1101583D02*
X1099220D01*
G01X1105520D02*
X1103157D01*
G01X1109457D02*
X1107094D01*
G01X1113394D02*
X1111031D01*
G01X1117331D02*
X1114968D01*
G01X1121268D02*
X1118906D01*
G01X1125205D02*
X1122843D01*
G01X1129142D02*
X1126780D01*
G01X1133079D02*
X1130717D01*
G01X1137016D02*
X1134654D01*
G01X1140953D02*
X1138591D01*
G01X1105165Y528902D02*
X1103512D01*
G01X1113039D02*
X1111386D01*
G01X1120913D02*
X1119260D01*
G01X1128787D02*
X1127134D01*
G01X1136661D02*
X1135008D01*
G01X1095855Y528735D02*
X1092269D01*
G01X1101819Y528035D02*
X1098984D01*
G01X1105756D02*
X1102921D01*
G01X1109693D02*
X1106858D01*
G01X1113630D02*
X1110795D01*
G01X1117567D02*
X1114732D01*
G01X1121504D02*
X1118669D01*
G01X1125441D02*
X1122606D01*
G01X1129378D02*
X1126543D01*
G01X1133315D02*
X1130480D01*
G01X1137252D02*
X1134417D01*
G01X1141189D02*
X1138354D01*
G01X1105165Y527130D02*
X1103512D01*
G01X1113039D02*
X1111386D01*
G01X1120913D02*
X1119260D01*
G01X1128787D02*
X1127134D01*
G01X1136661D02*
X1135008D01*
G01Y526638D02*
X1136661D01*
G01X1127134D02*
X1128787D01*
G01X1119260D02*
X1120913D01*
G01X1111386D02*
X1113039D01*
G01X1103512D02*
X1105165D01*
G01X1101819Y526539D02*
X1098984D01*
G01X1105756D02*
X1102921D01*
G01X1109693D02*
X1106858D01*
G01X1113630D02*
X1110795D01*
G01X1117567D02*
X1114732D01*
G01X1121504D02*
X1118669D01*
G01X1125441D02*
X1122606D01*
G01X1129378D02*
X1126543D01*
G01X1133315D02*
X1130480D01*
G01X1137252D02*
X1134417D01*
G01X1141189D02*
X1138354D01*
G01X1140598Y526382D02*
X1141189D01*
G01X1138354D02*
X1138945D01*
G01X1136661D02*
X1137252D01*
G01X1134417D02*
X1135008D01*
G01X1132724D02*
X1133315D01*
G01X1130480D02*
X1131071D01*
G01X1128787D02*
X1129378D01*
G01X1126543D02*
X1127134D01*
G01X1124850D02*
X1125441D01*
G01X1122606D02*
X1123197D01*
G01X1120913D02*
X1121504D01*
G01X1118669D02*
X1119260D01*
G01X1116976D02*
X1117567D01*
G01X1114732D02*
X1115323D01*
G01X1113039D02*
X1113630D01*
G01X1110795D02*
X1111386D01*
G01X1109102D02*
X1109693D01*
G01X1106858D02*
X1107449D01*
G01X1105165D02*
X1105756D01*
G01X1102921D02*
X1103512D01*
G01X1101228D02*
X1101819D01*
G01X1098984D02*
X1099575D01*
G01X1138771Y526147D02*
X1140782D01*
G01X1134829D02*
X1136840D01*
G01X1130897D02*
X1132908D01*
G01X1126955D02*
X1128966D01*
G01X1123023D02*
X1125034D01*
G01X1119081D02*
X1121092D01*
G01X1115149D02*
X1117160D01*
G01X1111207D02*
X1113218D01*
G01X1107275D02*
X1109286D01*
G01X1103333D02*
X1105344D01*
G01X1099401D02*
X1101412D01*
G01X1101156Y525757D02*
X1099657D01*
G01X1105088D02*
X1103589D01*
G01X1109030D02*
X1107531D01*
G01X1112962D02*
X1111463D01*
G01X1116904D02*
X1115405D01*
G01X1120836D02*
X1119337D01*
G01X1124778D02*
X1123279D01*
G01X1128710D02*
X1127211D01*
G01X1132652D02*
X1131153D01*
G01X1136584D02*
X1135085D01*
G01X1140526D02*
X1139027D01*
G01X1139040Y525738D02*
X1140513D01*
G01X1135098D02*
X1136571D01*
G01X1131166D02*
X1132639D01*
G01X1127224D02*
X1128697D01*
G01X1123292D02*
X1124765D01*
G01X1119350D02*
X1120823D01*
G01X1115418D02*
X1116891D01*
G01X1111476D02*
X1112949D01*
G01X1107544D02*
X1109017D01*
G01X1103602D02*
X1105075D01*
G01X1099670D02*
X1101143D01*
G01X1099575Y525713D02*
X1098984D01*
G01X1101819D02*
X1101228D01*
G01X1103512D02*
X1102921D01*
G01X1105756D02*
X1105165D01*
G01X1107449D02*
X1106858D01*
G01X1109693D02*
X1109102D01*
G01X1111386D02*
X1110795D01*
G01X1113630D02*
X1113039D01*
G01X1115323D02*
X1114732D01*
G01X1117567D02*
X1116976D01*
G01X1119260D02*
X1118669D01*
G01X1121504D02*
X1120913D01*
G01X1123197D02*
X1122606D01*
G01X1125441D02*
X1124850D01*
G01X1127134D02*
X1126543D01*
G01X1129378D02*
X1128787D01*
G01X1131071D02*
X1130480D01*
G01X1133315D02*
X1132724D01*
G01X1135008D02*
X1134417D01*
G01X1137252D02*
X1136661D01*
G01X1138945D02*
X1138354D01*
G01X1141189D02*
X1140598D01*
G01X1134417Y525555D02*
X1137252D01*
G01X1126543D02*
X1129378D01*
G01X1122606D02*
X1125441D01*
G01X1118669D02*
X1121504D01*
G01X1114732D02*
X1117567D01*
G01X1110795D02*
X1113630D01*
G01X1106858D02*
X1109693D01*
G01X1102921D02*
X1105756D01*
G01X1101819D02*
X1098984D01*
G01X1133315D02*
X1130480D01*
G01X1141189D02*
X1138354D01*
G01X1101228Y525457D02*
X1099575D01*
G01X1109102D02*
X1107449D01*
G01X1116976D02*
X1115323D01*
G01X1124850D02*
X1123197D01*
G01X1132724D02*
X1131071D01*
G01X1140598D02*
X1138945D01*
G01X1100889Y525368D02*
X1099924D01*
G01X1104821D02*
X1103856D01*
G01X1108763D02*
X1107798D01*
G01X1112695D02*
X1111730D01*
G01X1116637D02*
X1115672D01*
G01X1120569D02*
X1119604D01*
G01X1124511D02*
X1123546D01*
G01X1128443D02*
X1127478D01*
G01X1132385D02*
X1131420D01*
G01X1136317D02*
X1135352D01*
G01X1140259D02*
X1139294D01*
G01X1138354Y525358D02*
X1138669D01*
G01X1130480D02*
X1130795D01*
G01X1122606D02*
X1122921D01*
G01X1114732D02*
X1115047D01*
G01X1106858D02*
X1107173D01*
G01X1098984D02*
X1099299D01*
G01X1101819D02*
X1101504D01*
G01X1103236D02*
X1102921D01*
G01X1105756D02*
X1105441D01*
G01X1109693D02*
X1109378D01*
G01X1111110D02*
X1110795D01*
G01X1113630D02*
X1113315D01*
G01X1117567D02*
X1117252D01*
G01X1118984D02*
X1118669D01*
G01X1121504D02*
X1121189D01*
G01X1125441D02*
X1125126D01*
G01X1126858D02*
X1126543D01*
G01X1129378D02*
X1129063D01*
G01X1133315D02*
X1133000D01*
G01X1134732D02*
X1134417D01*
G01X1137252D02*
X1136937D01*
G01X1141189D02*
X1140874D01*
G01X1101417Y525261D02*
X1099396D01*
G01X1105349D02*
X1103328D01*
G01X1109291D02*
X1107270D01*
G01X1113223D02*
X1111202D01*
G01X1117165D02*
X1115144D01*
G01X1121097D02*
X1119076D01*
G01X1125039D02*
X1123018D01*
G01X1128971D02*
X1126950D01*
G01X1132913D02*
X1130892D01*
G01X1136845D02*
X1134824D01*
G01X1140787D02*
X1138766D01*
G01X1138945Y524965D02*
X1140598D01*
G01X1131071D02*
X1132724D01*
G01X1123197D02*
X1124850D01*
G01X1115323D02*
X1116976D01*
G01X1107449D02*
X1109102D01*
G01X1099575D02*
X1101228D01*
G01X1101156Y524772D02*
X1099657D01*
G01X1105088D02*
X1103589D01*
G01X1109030D02*
X1107531D01*
G01X1112962D02*
X1111463D01*
G01X1116904D02*
X1115405D01*
G01X1120836D02*
X1119337D01*
G01X1124778D02*
X1123279D01*
G01X1128710D02*
X1127211D01*
G01X1132652D02*
X1131153D01*
G01X1136584D02*
X1135085D01*
G01X1140526D02*
X1139027D01*
G01X1143177Y524768D02*
X1148177D01*
G01X1101154Y524763D02*
X1099658D01*
G01X1105087D02*
X1103590D01*
G01X1109028D02*
X1107532D01*
G01X1112961D02*
X1111464D01*
G01X1116902D02*
X1115406D01*
G01X1120835D02*
X1119338D01*
G01X1124777D02*
X1123280D01*
G01X1128709D02*
X1127212D01*
G01X1132651D02*
X1131154D01*
G01X1136583D02*
X1135086D01*
G01X1140525D02*
X1139028D01*
G01X1139248Y524441D02*
X1140305D01*
G01X1135306D02*
X1136363D01*
G01X1131374D02*
X1132431D01*
G01X1127432D02*
X1128489D01*
G01X1123500D02*
X1124557D01*
G01X1119558D02*
X1120615D01*
G01X1115626D02*
X1116683D01*
G01X1111684D02*
X1112741D01*
G01X1107752D02*
X1108809D01*
G01X1103810D02*
X1104867D01*
G01X1099878D02*
X1100935D01*
G01X1138591Y524394D02*
X1140953D01*
G01X1134654D02*
X1137016D01*
G01X1130717D02*
X1133079D01*
G01X1126780D02*
X1129142D01*
G01X1122843D02*
X1125205D01*
G01X1118906D02*
X1121268D01*
G01X1114968D02*
X1117331D01*
G01X1111031D02*
X1113394D01*
G01X1107094D02*
X1109457D01*
G01X1103157D02*
X1105520D01*
G01X1099220D02*
X1101583D01*
G01X1140874Y523862D02*
X1141189D01*
G01X1138354D02*
X1138669D01*
G01X1136937D02*
X1137252D01*
G01X1134417D02*
X1134732D01*
G01X1133000D02*
X1133315D01*
G01X1130480D02*
X1130795D01*
G01X1129063D02*
X1129378D01*
G01X1126543D02*
X1126858D01*
G01X1125126D02*
X1125441D01*
G01X1122606D02*
X1122921D01*
G01X1121189D02*
X1121504D01*
G01X1118669D02*
X1118984D01*
G01X1117252D02*
X1117567D01*
G01X1114732D02*
X1115047D01*
G01X1113315D02*
X1113630D01*
G01X1110795D02*
X1111110D01*
G01X1109378D02*
X1109693D01*
G01X1106858D02*
X1107173D01*
G01X1105441D02*
X1105756D01*
G01X1102921D02*
X1103236D01*
G01X1101504D02*
X1101819D01*
G01X1098984D02*
X1099299D01*
G01X1139005Y523826D02*
X1140548D01*
G01X1135063D02*
X1136606D01*
G01X1131131D02*
X1132674D01*
G01X1127189D02*
X1128732D01*
G01X1123257D02*
X1124800D01*
G01X1119315D02*
X1120858D01*
G01X1115383D02*
X1116926D01*
G01X1111441D02*
X1112984D01*
G01X1107509D02*
X1109052D01*
G01X1103567D02*
X1105110D01*
G01X1099635D02*
X1101178D01*
G01X1139016Y523807D02*
X1140537D01*
G01X1135074D02*
X1136595D01*
G01X1131142D02*
X1132663D01*
G01X1127200D02*
X1128721D01*
G01X1123268D02*
X1124789D01*
G01X1119326D02*
X1120847D01*
G01X1115394D02*
X1116915D01*
G01X1111452D02*
X1112973D01*
G01X1107520D02*
X1109041D01*
G01X1103578D02*
X1105099D01*
G01X1099646D02*
X1101167D01*
G01X1434575Y523685D02*
X1093000D01*
G01X1094240Y523390D02*
X1089516D01*
G01X1138945Y523193D02*
X1140598D01*
G01X1131071D02*
X1132724D01*
G01X1123197D02*
X1124850D01*
G01X1115323D02*
X1116976D01*
G01X1107449D02*
X1109102D01*
G01X1099575D02*
X1101228D01*
G01Y522701D02*
X1099575D01*
G01X1109102D02*
X1107449D01*
G01X1116976D02*
X1115323D01*
G01X1124850D02*
X1123197D01*
G01X1132724D02*
X1131071D01*
G01X1140598D02*
X1138945D01*
G01X1101071Y522602D02*
X1099732D01*
G01X1108945D02*
X1107606D01*
G01X1116819D02*
X1115480D01*
G01X1124693D02*
X1123354D01*
G01X1132567D02*
X1131228D01*
G01X1140441D02*
X1139102D01*
G01Y521618D02*
X1140441D01*
G01X1131228D02*
X1132567D01*
G01X1123354D02*
X1124693D01*
G01X1115480D02*
X1116819D01*
G01X1107606D02*
X1108945D01*
G01X1099732D02*
X1101071D01*
G01X1094496Y521126D02*
X1090559D01*
G01X1101204Y520999D02*
X1099609D01*
G01X1105136D02*
X1103541D01*
G01X1109078D02*
X1107483D01*
G01X1113010D02*
X1111415D01*
G01X1116952D02*
X1115357D01*
G01X1120884D02*
X1119289D01*
G01X1124826D02*
X1123231D01*
G01X1128758D02*
X1127163D01*
G01X1132700D02*
X1131105D01*
G01X1136632D02*
X1135037D01*
G01X1140574D02*
X1138979D01*
G01X1101504Y520890D02*
X1099299D01*
G01X1105441D02*
X1103236D01*
G01X1109378D02*
X1107173D01*
G01X1113315D02*
X1111110D01*
G01X1117252D02*
X1115047D01*
G01X1121189D02*
X1118984D01*
G01X1125126D02*
X1122921D01*
G01X1129063D02*
X1126858D01*
G01X1133000D02*
X1130795D01*
G01X1136937D02*
X1134732D01*
G01X1140874D02*
X1138669D01*
G01X1142932Y520732D02*
X1094957D01*
G01X1101276Y520239D02*
X1099537D01*
G01X1105208D02*
X1103469D01*
G01X1109150D02*
X1107411D01*
G01X1113082D02*
X1111343D01*
G01X1117024D02*
X1115285D01*
G01X1120956D02*
X1119217D01*
G01X1124898D02*
X1123159D01*
G01X1128830D02*
X1127091D01*
G01X1132772D02*
X1131033D01*
G01X1136704D02*
X1134965D01*
G01X1140646D02*
X1138907D01*
G01X1138981Y520037D02*
X1140572D01*
G01X1135039D02*
X1136630D01*
G01X1131107D02*
X1132698D01*
G01X1127165D02*
X1128756D01*
G01X1123233D02*
X1124824D01*
G01X1119291D02*
X1120882D01*
G01X1115359D02*
X1116950D01*
G01X1111417D02*
X1113008D01*
G01X1107485D02*
X1109076D01*
G01X1103543D02*
X1105134D01*
G01X1099611D02*
X1101201D01*
G01X1138928Y520013D02*
X1140624D01*
G01X1134987D02*
X1136683D01*
G01X1131054D02*
X1132750D01*
G01X1127113D02*
X1128809D01*
G01X1123180D02*
X1124876D01*
G01X1119239D02*
X1120935D01*
G01X1115306D02*
X1117002D01*
G01X1111365D02*
X1113061D01*
G01X1107432D02*
X1109128D01*
G01X1103491D02*
X1105187D01*
G01X1099558D02*
X1101254D01*
G01X1101261Y519945D02*
X1099551D01*
G01X1105194D02*
X1103484D01*
G01X1109135D02*
X1107425D01*
G01X1113068D02*
X1111358D01*
G01X1117009D02*
X1115299D01*
G01X1120942D02*
X1119232D01*
G01X1124883D02*
X1123173D01*
G01X1128816D02*
X1127106D01*
G01X1132757D02*
X1131047D01*
G01X1136690D02*
X1134980D01*
G01X1140631D02*
X1138921D01*
G01X1138902Y519353D02*
X1140650D01*
G01X1134960D02*
X1136709D01*
G01X1131028D02*
X1132776D01*
G01X1127086D02*
X1128835D01*
G01X1123154D02*
X1124902D01*
G01X1119212D02*
X1120961D01*
G01X1115280D02*
X1117028D01*
G01X1111338D02*
X1113087D01*
G01X1107406D02*
X1109154D01*
G01X1103464D02*
X1105213D01*
G01X1099532D02*
X1101280D01*
G01X1101252Y519051D02*
X1099560D01*
G01X1105184D02*
X1103493D01*
G01X1109126D02*
X1107435D01*
G01X1113058D02*
X1111367D01*
G01X1117000D02*
X1115309D01*
G01X1120932D02*
X1119241D01*
G01X1124874D02*
X1123183D01*
G01X1128806D02*
X1127115D01*
G01X1132748D02*
X1131057D01*
G01X1136680D02*
X1134989D01*
G01X1140622D02*
X1138931D01*
G01X1101261Y518961D02*
X1099551D01*
G01X1105194D02*
X1103484D01*
G01X1109135D02*
X1107425D01*
G01X1113068D02*
X1111358D01*
G01X1117009D02*
X1115299D01*
G01X1120942D02*
X1119232D01*
G01X1124883D02*
X1123173D01*
G01X1128816D02*
X1127106D01*
G01X1132757D02*
X1131047D01*
G01X1136690D02*
X1134980D01*
G01X1140631D02*
X1138921D01*
G01X1101504Y518635D02*
X1099299D01*
G01X1105441D02*
X1103236D01*
G01X1109378D02*
X1107173D01*
G01X1113315D02*
X1111110D01*
G01X1117252D02*
X1115047D01*
G01X1121189D02*
X1118984D01*
G01X1125126D02*
X1122921D01*
G01X1129063D02*
X1126858D01*
G01X1133000D02*
X1130795D01*
G01X1136937D02*
X1134732D01*
G01X1140874D02*
X1138669D01*
G01Y518468D02*
X1140874D01*
G01X1134732D02*
X1136937D01*
G01X1130795D02*
X1133000D01*
G01X1126858D02*
X1129063D01*
G01X1122921D02*
X1125126D01*
G01X1118984D02*
X1121189D01*
G01X1115047D02*
X1117252D01*
G01X1111110D02*
X1113315D01*
G01X1107173D02*
X1109378D01*
G01X1103236D02*
X1105441D01*
G01X1099299D02*
X1101504D01*
G01Y515910D02*
X1099299D01*
G01X1105441D02*
X1103236D01*
G01X1109378D02*
X1107173D01*
G01X1113315D02*
X1111110D01*
G01X1117252D02*
X1115047D01*
G01X1121189D02*
X1118984D01*
G01X1125126D02*
X1122921D01*
G01X1129063D02*
X1126858D01*
G01X1133000D02*
X1130795D01*
G01X1136937D02*
X1134732D01*
G01X1140874D02*
X1138669D01*
G01Y515743D02*
X1140874D01*
G01X1134732D02*
X1136937D01*
G01X1130795D02*
X1133000D01*
G01X1126858D02*
X1129063D01*
G01X1122921D02*
X1125126D01*
G01X1118984D02*
X1121189D01*
G01X1115047D02*
X1117252D01*
G01X1111110D02*
X1113315D01*
G01X1107173D02*
X1109378D01*
G01X1103236D02*
X1105441D01*
G01X1099299D02*
X1101504D01*
G01X1138912Y515417D02*
X1140622D01*
G01X1134980D02*
X1136690D01*
G01X1131038D02*
X1132748D01*
G01X1127106D02*
X1128816D01*
G01X1123164D02*
X1124874D01*
G01X1119232D02*
X1120942D01*
G01X1115290D02*
X1117000D01*
G01X1111358D02*
X1113068D01*
G01X1107416D02*
X1109126D01*
G01X1103484D02*
X1105194D01*
G01X1099542D02*
X1101252D01*
G01X1138921Y515327D02*
X1140613D01*
G01X1134989D02*
X1136680D01*
G01X1131047D02*
X1132739D01*
G01X1127115D02*
X1128806D01*
G01X1123173D02*
X1124865D01*
G01X1119241D02*
X1120932D01*
G01X1115299D02*
X1116991D01*
G01X1111367D02*
X1113058D01*
G01X1107425D02*
X1109117D01*
G01X1103493D02*
X1105184D01*
G01X1099551D02*
X1101243D01*
G01X1101271Y515025D02*
X1099523D01*
G01X1105213D02*
X1103464D01*
G01X1109145D02*
X1107397D01*
G01X1113087D02*
X1111338D01*
G01X1117019D02*
X1115271D01*
G01X1120961D02*
X1119212D01*
G01X1124893D02*
X1123145D01*
G01X1128835D02*
X1127086D01*
G01X1132767D02*
X1131019D01*
G01X1136709D02*
X1134960D01*
G01X1140641D02*
X1138893D01*
G01X1138912Y514433D02*
X1140622D01*
G01X1134980D02*
X1136690D01*
G01X1131038D02*
X1132748D01*
G01X1127106D02*
X1128816D01*
G01X1123164D02*
X1124874D01*
G01X1119232D02*
X1120942D01*
G01X1115290D02*
X1117000D01*
G01X1111358D02*
X1113068D01*
G01X1107416D02*
X1109126D01*
G01X1103484D02*
X1105194D01*
G01X1099542D02*
X1101252D01*
G01X1101245Y514365D02*
X1099549D01*
G01X1105187D02*
X1103491D01*
G01X1109119D02*
X1107423D01*
G01X1113061D02*
X1111365D01*
G01X1116993D02*
X1115297D01*
G01X1120935D02*
X1119239D01*
G01X1124867D02*
X1123171D01*
G01X1128809D02*
X1127113D01*
G01X1132741D02*
X1131045D01*
G01X1136683D02*
X1134987D01*
G01X1140615D02*
X1138919D01*
G01X1101192Y514341D02*
X1099602D01*
G01X1105134D02*
X1103543D01*
G01X1109066D02*
X1107476D01*
G01X1113008D02*
X1111417D01*
G01X1116940D02*
X1115350D01*
G01X1120882D02*
X1119291D01*
G01X1124814D02*
X1123224D01*
G01X1128756D02*
X1127165D01*
G01X1132688D02*
X1131098D01*
G01X1136630D02*
X1135039D01*
G01X1140562D02*
X1138972D01*
G01X1138898Y514139D02*
X1140636D01*
G01X1134965D02*
X1136704D01*
G01X1131024D02*
X1132762D01*
G01X1127091D02*
X1128830D01*
G01X1123150D02*
X1124888D01*
G01X1119217D02*
X1120956D01*
G01X1115276D02*
X1117014D01*
G01X1111343D02*
X1113082D01*
G01X1107402D02*
X1109140D01*
G01X1103469D02*
X1105208D01*
G01X1099527D02*
X1101266D01*
G01X1094957Y513646D02*
X1142932D01*
G01X1138669Y513488D02*
X1140874D01*
G01X1134732D02*
X1136937D01*
G01X1130795D02*
X1133000D01*
G01X1126858D02*
X1129063D01*
G01X1122921D02*
X1125126D01*
G01X1118984D02*
X1121189D01*
G01X1115047D02*
X1117252D01*
G01X1111110D02*
X1113315D01*
G01X1107173D02*
X1109378D01*
G01X1103236D02*
X1105441D01*
G01X1099299D02*
X1101504D01*
G01X1138969Y513379D02*
X1140565D01*
G01X1135037D02*
X1136632D01*
G01X1131095D02*
X1132691D01*
G01X1127163D02*
X1128758D01*
G01X1123221D02*
X1124817D01*
G01X1119289D02*
X1120884D01*
G01X1115347D02*
X1116943D01*
G01X1111415D02*
X1113010D01*
G01X1107473D02*
X1109068D01*
G01X1103541D02*
X1105136D01*
G01X1099599D02*
X1101194D01*
G01X1090559Y513252D02*
X1094496D01*
G01X1101071Y512760D02*
X1099732D01*
G01X1108945D02*
X1107606D01*
G01X1116819D02*
X1115480D01*
G01X1124693D02*
X1123354D01*
G01X1132567D02*
X1131228D01*
G01X1140441D02*
X1139102D01*
G01X1101071Y511776D02*
X1099732D01*
G01X1108945D02*
X1107606D01*
G01X1116819D02*
X1115480D01*
G01X1124693D02*
X1123354D01*
G01X1132567D02*
X1131228D01*
G01X1140441D02*
X1139102D01*
G01X1138945Y511677D02*
X1140598D01*
G01X1131071D02*
X1132724D01*
G01X1123197D02*
X1124850D01*
G01X1115323D02*
X1116976D01*
G01X1107449D02*
X1109102D01*
G01X1099575D02*
X1101228D01*
G01Y511185D02*
X1099575D01*
G01X1109102D02*
X1107449D01*
G01X1116976D02*
X1115323D01*
G01X1124850D02*
X1123197D01*
G01X1132724D02*
X1131071D01*
G01X1140598D02*
X1138945D01*
G01X1094240Y510988D02*
X1089516D01*
G01X1093000Y510693D02*
X1434575D01*
G01X1101158Y510571D02*
X1099636D01*
G01X1105099D02*
X1103578D01*
G01X1109032D02*
X1107510D01*
G01X1112973D02*
X1111452D01*
G01X1116906D02*
X1115384D01*
G01X1120847D02*
X1119326D01*
G01X1124780D02*
X1123258D01*
G01X1128721D02*
X1127200D01*
G01X1132654D02*
X1131132D01*
G01X1136595D02*
X1135074D01*
G01X1140528D02*
X1139006D01*
G01X1101169Y510552D02*
X1099625D01*
G01X1105110D02*
X1103567D01*
G01X1109043D02*
X1107499D01*
G01X1112984D02*
X1111441D01*
G01X1116917D02*
X1115373D01*
G01X1120858D02*
X1119315D01*
G01X1124791D02*
X1123247D01*
G01X1128732D02*
X1127189D01*
G01X1132665D02*
X1131121D01*
G01X1136606D02*
X1135063D01*
G01X1140539D02*
X1138995D01*
G01X1099299Y510516D02*
X1098984D01*
G01X1101819D02*
X1101504D01*
G01X1103236D02*
X1102921D01*
G01X1105756D02*
X1105441D01*
G01X1107173D02*
X1106858D01*
G01X1109693D02*
X1109378D01*
G01X1111110D02*
X1110795D01*
G01X1113630D02*
X1113315D01*
G01X1115047D02*
X1114732D01*
G01X1117567D02*
X1117252D01*
G01X1118984D02*
X1118669D01*
G01X1122921D02*
X1122606D01*
G01X1121504D02*
X1121189D01*
G01X1125441D02*
X1125126D01*
G01X1126858D02*
X1126543D01*
G01X1129378D02*
X1129063D01*
G01X1130795D02*
X1130480D01*
G01X1133315D02*
X1133000D01*
G01X1134732D02*
X1134417D01*
G01X1137252D02*
X1136937D01*
G01X1138669D02*
X1138354D01*
G01X1141189D02*
X1140874D01*
G01X1101583Y509984D02*
X1099220D01*
G01X1105520D02*
X1103157D01*
G01X1109457D02*
X1107094D01*
G01X1113394D02*
X1111031D01*
G01X1117331D02*
X1114968D01*
G01X1121268D02*
X1118906D01*
G01X1125205D02*
X1122843D01*
G01X1129142D02*
X1126780D01*
G01X1133079D02*
X1130717D01*
G01X1137016D02*
X1134654D01*
G01X1140953D02*
X1138591D01*
G01X1100925Y509937D02*
X1099869D01*
G01X1104867D02*
X1103810D01*
G01X1108799D02*
X1107743D01*
G01X1112741D02*
X1111684D01*
G01X1116673D02*
X1115617D01*
G01X1120615D02*
X1119558D01*
G01X1124547D02*
X1123491D01*
G01X1128489D02*
X1127432D01*
G01X1132421D02*
X1131365D01*
G01X1136363D02*
X1135306D01*
G01X1140295D02*
X1139239D01*
G01X1139019Y509615D02*
X1140515D01*
G01X1135086D02*
X1136583D01*
G01X1131145D02*
X1132641D01*
G01X1127212D02*
X1128709D01*
G01X1123271D02*
X1124767D01*
G01X1119338D02*
X1120835D01*
G01X1115397D02*
X1116893D01*
G01X1111464D02*
X1112961D01*
G01X1107523D02*
X1109019D01*
G01X1103590D02*
X1105087D01*
G01X1099649D02*
X1101145D01*
G01X1148177Y509610D02*
X1143177D01*
G01X1139017Y509606D02*
X1140517D01*
G01X1135085D02*
X1136584D01*
G01X1131143D02*
X1132643D01*
G01X1127211D02*
X1128710D01*
G01X1123269D02*
X1124769D01*
G01X1119337D02*
X1120836D01*
G01X1115395D02*
X1116895D01*
G01X1111463D02*
X1112962D01*
G01X1107521D02*
X1109021D01*
G01X1103589D02*
X1105088D01*
G01X1099647D02*
X1101147D01*
G01X1101228Y509413D02*
X1099575D01*
G01X1109102D02*
X1107449D01*
G01X1116976D02*
X1115323D01*
G01X1124850D02*
X1123197D01*
G01X1132724D02*
X1131071D01*
G01X1140598D02*
X1138945D01*
G01X1138757Y509117D02*
X1140777D01*
G01X1134824D02*
X1136845D01*
G01X1130883D02*
X1132903D01*
G01X1126950D02*
X1128971D01*
G01X1123009D02*
X1125029D01*
G01X1119076D02*
X1121097D01*
G01X1115135D02*
X1117155D01*
G01X1111202D02*
X1113223D01*
G01X1107261D02*
X1109281D01*
G01X1103328D02*
X1105349D01*
G01X1099386D02*
X1101407D01*
G01X1140874Y509020D02*
X1141189D01*
G01X1133000D02*
X1133315D01*
G01X1125126D02*
X1125441D01*
G01X1117252D02*
X1117567D01*
G01X1109378D02*
X1109693D01*
G01X1101504D02*
X1101819D01*
G01X1099299D02*
X1098984D01*
G01X1103236D02*
X1102921D01*
G01X1105756D02*
X1105441D01*
G01X1107173D02*
X1106858D01*
G01X1111110D02*
X1110795D01*
G01X1113630D02*
X1113315D01*
G01X1115047D02*
X1114732D01*
G01X1118984D02*
X1118669D01*
G01X1122921D02*
X1122606D01*
G01X1121504D02*
X1121189D01*
G01X1126858D02*
X1126543D01*
G01X1129378D02*
X1129063D01*
G01X1130795D02*
X1130480D01*
G01X1134732D02*
X1134417D01*
G01X1137252D02*
X1136937D01*
G01X1138669D02*
X1138354D01*
G01X1139284Y509010D02*
X1140250D01*
G01X1135352D02*
X1136317D01*
G01X1131410D02*
X1132376D01*
G01X1127478D02*
X1128443D01*
G01X1123536D02*
X1124502D01*
G01X1119604D02*
X1120569D01*
G01X1115662D02*
X1116628D01*
G01X1111730D02*
X1112695D01*
G01X1107788D02*
X1108754D01*
G01X1103856D02*
X1104821D01*
G01X1099914D02*
X1100880D01*
G01X1138945Y508921D02*
X1140598D01*
G01X1131071D02*
X1132724D01*
G01X1123197D02*
X1124850D01*
G01X1115323D02*
X1116976D01*
G01X1107449D02*
X1109102D01*
G01X1099575D02*
X1101228D01*
G01X1138354Y508823D02*
X1141189D01*
G01X1134417D02*
X1137252D01*
G01X1130480D02*
X1133315D01*
G01X1126543D02*
X1129378D01*
G01X1122606D02*
X1125441D01*
G01X1118669D02*
X1121504D01*
G01X1114732D02*
X1117567D01*
G01X1110795D02*
X1113630D01*
G01X1106858D02*
X1109693D01*
G01X1102921D02*
X1105756D01*
G01X1098984D02*
X1101819D01*
G01X1140598Y508665D02*
X1141189D01*
G01X1138354D02*
X1138945D01*
G01X1136661D02*
X1137252D01*
G01X1134417D02*
X1135008D01*
G01X1132724D02*
X1133315D01*
G01X1130480D02*
X1131071D01*
G01X1128787D02*
X1129378D01*
G01X1126543D02*
X1127134D01*
G01X1124850D02*
X1125441D01*
G01X1122606D02*
X1123197D01*
G01X1120913D02*
X1121504D01*
G01X1118669D02*
X1119260D01*
G01X1116976D02*
X1117567D01*
G01X1114732D02*
X1115323D01*
G01X1113039D02*
X1113630D01*
G01X1110795D02*
X1111386D01*
G01X1109102D02*
X1109693D01*
G01X1106858D02*
X1107449D01*
G01X1105165D02*
X1105756D01*
G01X1102921D02*
X1103512D01*
G01X1101228D02*
X1101819D01*
G01X1098984D02*
X1099575D01*
G01X1101133Y508640D02*
X1099660D01*
G01X1105075D02*
X1103602D01*
G01X1109007D02*
X1107534D01*
G01X1112949D02*
X1111476D01*
G01X1116881D02*
X1115408D01*
G01X1120823D02*
X1119350D01*
G01X1124755D02*
X1123282D01*
G01X1128697D02*
X1127224D01*
G01X1132629D02*
X1131156D01*
G01X1136571D02*
X1135098D01*
G01X1140503D02*
X1139030D01*
G01X1139017Y508621D02*
X1140517D01*
G01X1135085D02*
X1136584D01*
G01X1131143D02*
X1132643D01*
G01X1127211D02*
X1128710D01*
G01X1123269D02*
X1124769D01*
G01X1119337D02*
X1120836D01*
G01X1115395D02*
X1116895D01*
G01X1111463D02*
X1112962D01*
G01X1107521D02*
X1109021D01*
G01X1103589D02*
X1105088D01*
G01X1099647D02*
X1101147D01*
G01X1101403Y508231D02*
X1099391D01*
G01X1105344D02*
X1103333D01*
G01X1109277D02*
X1107265D01*
G01X1113218D02*
X1111207D01*
G01X1117151D02*
X1115139D01*
G01X1121092D02*
X1119081D01*
G01X1125025D02*
X1123013D01*
G01X1128966D02*
X1126955D01*
G01X1132899D02*
X1130887D01*
G01X1136840D02*
X1134829D01*
G01X1140773D02*
X1138761D01*
G01X1099575Y507996D02*
X1098984D01*
G01X1101819D02*
X1101228D01*
G01X1103512D02*
X1102921D01*
G01X1105756D02*
X1105165D01*
G01X1107449D02*
X1106858D01*
G01X1109693D02*
X1109102D01*
G01X1111386D02*
X1110795D01*
G01X1113630D02*
X1113039D01*
G01X1115323D02*
X1114732D01*
G01X1117567D02*
X1116976D01*
G01X1119260D02*
X1118669D01*
G01X1121504D02*
X1120913D01*
G01X1123197D02*
X1122606D01*
G01X1125441D02*
X1124850D01*
G01X1127134D02*
X1126543D01*
G01X1129378D02*
X1128787D01*
G01X1131071D02*
X1130480D01*
G01X1133315D02*
X1132724D01*
G01X1135008D02*
X1134417D01*
G01X1137252D02*
X1136661D01*
G01X1138945D02*
X1138354D01*
G01X1141189D02*
X1140598D01*
G01X1101819Y507839D02*
X1098984D01*
G01X1105756D02*
X1102921D01*
G01X1109693D02*
X1106858D01*
G01X1113630D02*
X1110795D01*
G01X1117567D02*
X1114732D01*
G01X1121504D02*
X1118669D01*
G01X1125441D02*
X1122606D01*
G01X1129378D02*
X1126543D01*
G01X1133315D02*
X1130480D01*
G01X1137252D02*
X1134417D01*
G01X1141189D02*
X1138354D01*
G01X1105165Y507740D02*
X1103512D01*
G01X1113039D02*
X1111386D01*
G01X1120913D02*
X1119260D01*
G01X1128787D02*
X1127134D01*
G01X1136661D02*
X1135008D01*
G01Y507248D02*
X1136661D01*
G01X1127134D02*
X1128787D01*
G01X1119260D02*
X1120913D01*
G01X1111386D02*
X1113039D01*
G01X1103512D02*
X1105165D01*
G01X1138354Y506343D02*
X1141189D01*
G01X1134417D02*
X1137252D01*
G01X1130480D02*
X1133315D01*
G01X1126543D02*
X1129378D01*
G01X1122606D02*
X1125441D01*
G01X1118669D02*
X1121504D01*
G01X1114732D02*
X1117567D01*
G01X1110795D02*
X1113630D01*
G01X1106858D02*
X1109693D01*
G01X1102921D02*
X1105756D01*
G01X1098984D02*
X1101819D01*
G01X1135008Y505476D02*
X1136661D01*
G01X1127134D02*
X1128787D01*
G01X1119260D02*
X1120913D01*
G01X1111386D02*
X1113039D01*
G01X1103512D02*
X1105165D01*
G01X1138591Y505083D02*
X1140953D01*
G01X1134654D02*
X1137016D01*
G01X1130717D02*
X1133079D01*
G01X1126780D02*
X1129142D01*
G01X1122843D02*
X1125205D01*
G01X1118906D02*
X1121268D01*
G01X1114968D02*
X1117331D01*
G01X1111031D02*
X1113394D01*
G01X1107094D02*
X1109457D01*
G01X1103157D02*
X1105520D01*
G01X1099220D02*
X1101583D01*
G01X1094240D02*
X1089516D01*
G01X1105165Y504984D02*
X1103512D01*
G01X1113039D02*
X1111386D01*
G01X1120913D02*
X1119260D01*
G01X1128787D02*
X1127134D01*
G01X1136661D02*
X1135008D01*
G01X1143177Y504886D02*
X1148177D01*
G01X1105008D02*
X1103669D01*
G01X1112882D02*
X1111543D01*
G01X1120756D02*
X1119417D01*
G01X1128630D02*
X1127291D01*
G01X1136504D02*
X1135165D01*
G01X1138591Y503902D02*
X1140953D01*
G01X1134654D02*
X1137016D01*
G01X1130717D02*
X1133079D01*
G01X1126780D02*
X1129142D01*
G01X1122843D02*
X1125205D01*
G01X1118906D02*
X1121268D01*
G01X1114968D02*
X1117331D01*
G01X1111031D02*
X1113394D01*
G01X1107094D02*
X1109457D01*
G01X1103157D02*
X1105520D01*
G01X1099220D02*
X1101583D01*
G01X1438984Y502524D02*
X1088591D01*
G01X1148422Y520732D02*
X1146935Y522976D01*
G01X1142932Y513646D02*
X1144420Y511402D01*
G01X1139294Y525368D02*
X1139040Y525738D01*
G01X1139248Y524441D02*
X1139027Y524763D01*
G01X1135352Y525368D02*
X1135098Y525738D01*
G01X1135087Y524760D02*
X1135306Y524441D01*
G01X1131420Y525368D02*
X1131166Y525738D01*
G01X1131374Y524441D02*
X1131153Y524763D01*
G01X1140295Y509937D02*
X1140517Y509615D01*
G01X1140250Y509010D02*
X1140503Y508640D01*
G01X1127478Y525368D02*
X1127224Y525738D01*
G01X1127213Y524760D02*
X1127432Y524441D01*
G01X1136583Y509618D02*
X1136363Y509937D01*
G01X1136317Y509010D02*
X1136571Y508640D01*
G01X1123546Y525368D02*
X1123292Y525738D01*
G01X1123500Y524441D02*
X1123279Y524763D01*
G01X1132421Y509937D02*
X1132643Y509615D01*
G01X1132376Y509010D02*
X1132629Y508640D01*
G01X1119604Y525368D02*
X1119350Y525738D01*
G01X1119339Y524760D02*
X1119558Y524441D01*
G01X1128709Y509618D02*
X1128489Y509937D01*
G01X1128443Y509010D02*
X1128697Y508640D01*
G01X1115672Y525368D02*
X1115418Y525738D01*
G01X1093000Y523685D02*
X1094957Y520732D01*
G01X1115626Y524441D02*
X1115405Y524763D01*
G01X1124547Y509937D02*
X1124769Y509615D01*
G01X1124502Y509010D02*
X1124755Y508640D01*
G01X1111730Y525368D02*
X1111476Y525738D01*
G01X1111465Y524760D02*
X1111684Y524441D01*
G01X1120835Y509618D02*
X1120615Y509937D01*
G01X1120569Y509010D02*
X1120823Y508640D01*
G01X1107798Y525368D02*
X1107544Y525738D01*
G01X1107752Y524441D02*
X1107531Y524763D01*
G01X1116673Y509937D02*
X1116895Y509615D01*
G01X1116628Y509010D02*
X1116881Y508640D01*
G01X1103856Y525368D02*
X1103602Y525738D01*
G01X1103591Y524760D02*
X1103810Y524441D01*
G01X1112961Y509618D02*
X1112741Y509937D01*
G01X1112695Y509010D02*
X1112949Y508640D01*
G01X1099924Y525368D02*
X1099670Y525738D01*
G01X1099878Y524441D02*
X1099657Y524763D01*
G01X1108799Y509937D02*
X1109021Y509615D01*
G01X1108754Y509010D02*
X1109007Y508640D01*
G01X1105087Y509618D02*
X1104867Y509937D01*
G01X1104821Y509010D02*
X1105075Y508640D01*
G01X1100925Y509937D02*
X1101147Y509615D01*
G01X1100880Y509010D02*
X1101133Y508640D01*
G01X1139248Y524441D02*
X1139258Y524394D01*
G01X1140295Y509937D02*
X1140286Y509984D01*
G01X1135316Y524394D02*
X1135306Y524441D01*
G01X1136353Y509984D02*
X1136363Y509937D01*
G01X1131374Y524441D02*
X1131384Y524394D01*
G01X1132421Y509937D02*
X1132412Y509984D01*
G01X1127442Y524394D02*
X1127432Y524441D01*
G01X1128479Y509984D02*
X1128489Y509937D01*
G01X1123500Y524441D02*
X1123510Y524394D01*
G01X1124547Y509937D02*
X1124538Y509984D01*
G01X1139030Y508640D02*
X1139284Y509010D01*
G01X1139017Y509615D02*
X1139239Y509937D01*
G01X1146935Y511402D02*
X1148422Y513646D01*
G01X1140565Y513379D02*
X1140615Y514365D01*
G01X1140613Y515327D02*
X1140562Y514341D01*
G01X1140650Y519353D02*
X1140787Y525261D01*
G01X1140782Y526147D02*
X1140646Y520239D01*
G01X1138761Y508231D02*
X1138898Y514139D01*
G01X1138893Y515025D02*
X1138757Y509117D01*
G01X1140263Y509984D02*
X1140250Y509010D01*
G01X1139281Y524394D02*
X1139294Y525368D01*
G01X1146935Y511402D02*
Y522976D01*
G01X1144420D02*
Y511402D01*
G01X1143177Y509610D02*
Y504886D01*
G01Y529492D02*
Y524768D01*
G01X1142628Y513646D02*
Y520732D01*
G01X1142272D02*
Y513646D01*
G01X1141189Y523862D02*
Y528035D01*
G01Y506343D02*
Y510516D01*
G01X1141154Y526539D02*
Y525555D01*
G01X1141150Y508823D02*
Y507839D01*
G01X1141145Y508823D02*
Y507839D01*
G01X1140953Y509984D02*
Y503902D01*
G01Y530476D02*
Y524394D01*
G01X1140874Y507839D02*
Y526539D01*
G01X1140800Y526538D02*
Y525553D01*
G01X1140791Y508825D02*
Y507840D01*
G01X1140598Y521698D02*
Y526539D01*
G01Y507839D02*
Y512680D01*
G01X1140524Y524760D02*
Y525751D01*
G01X1140515Y508627D02*
Y509618D01*
G01X1140441Y512760D02*
Y511696D01*
G01Y522681D02*
Y521618D01*
G01X1140165D02*
Y522602D01*
G01Y512760D02*
Y511776D01*
G01X1139378Y512760D02*
Y511776D01*
G01Y522602D02*
Y521618D01*
G01X1139102Y512760D02*
Y511696D01*
G01Y522682D02*
Y521618D01*
G01X1139028Y525751D02*
Y524760D01*
G01X1139019Y509618D02*
Y508627D01*
G01X1138945Y521698D02*
Y526539D01*
G01Y507839D02*
Y512680D01*
G01X1138753Y525553D02*
Y526538D01*
G01X1138743Y507840D02*
Y508825D01*
G01X1138669Y526539D02*
Y507839D01*
G01X1138591Y509984D02*
Y503902D01*
G01Y530476D02*
Y524394D01*
G01X1138398Y526539D02*
Y525555D01*
G01X1138394Y526539D02*
Y525555D01*
G01X1138389Y508823D02*
Y507839D01*
G01X1138354Y510516D02*
Y506343D01*
G01Y528035D02*
Y523862D01*
G01X1140259Y525368D02*
X1140272Y524394D01*
G01X1139284Y509010D02*
X1139271Y509984D01*
G01X1140777Y509117D02*
X1140641Y515025D01*
G01X1140636Y514139D02*
X1140773Y508231D01*
G01X1138907Y520239D02*
X1138771Y526147D01*
G01X1138766Y525261D02*
X1138902Y519353D01*
G01X1136845Y509117D02*
X1136709Y515025D01*
G01X1136704Y514139D02*
X1136840Y508231D01*
G01X1140624Y520013D02*
X1140574Y520999D01*
G01X1140572Y520037D02*
X1140622Y519051D01*
G01X1138972Y514341D02*
X1138921Y515327D01*
G01X1138919Y514365D02*
X1138969Y513379D01*
G01X1136683Y520013D02*
X1136632Y520999D01*
G01X1136630Y520037D02*
X1136680Y519051D01*
G01X1135039Y514341D02*
X1134989Y515327D01*
G01X1134987Y514365D02*
X1135037Y513379D01*
G01X1119568Y524394D02*
X1119558Y524441D01*
G01X1120605Y509984D02*
X1120615Y509937D01*
G01X1115626Y524441D02*
X1115636Y524394D01*
G01X1116673Y509937D02*
X1116664Y509984D01*
G01X1111694Y524394D02*
X1111684Y524441D01*
G01X1112731Y509984D02*
X1112741Y509937D01*
G01X1107752Y524441D02*
X1107762Y524394D01*
G01X1108799Y509937D02*
X1108790Y509984D01*
G01X1103820Y524394D02*
X1103810Y524441D01*
G01X1104857Y509984D02*
X1104867Y509937D01*
G01X1099878Y524441D02*
X1099888Y524394D01*
G01X1100925Y509937D02*
X1100916Y509984D01*
G01X1090231Y536854D02*
X1090969Y534592D01*
G01X1091379Y533252D02*
X1091051Y534257D01*
G01X1090559Y537189D02*
X1091871Y533252D01*
G01X1135098Y508640D02*
X1135352Y509010D01*
G01X1135306Y509937D02*
X1135087Y509618D01*
G01X1131156Y508640D02*
X1131410Y509010D01*
G01X1131143Y509615D02*
X1131365Y509937D01*
G01X1140526Y524763D02*
X1140305Y524441D01*
G01X1140513Y525738D02*
X1140259Y525368D01*
G01X1127224Y508640D02*
X1127478Y509010D01*
G01X1127432Y509937D02*
X1127213Y509618D01*
G01X1136363Y524441D02*
X1136583Y524760D01*
G01X1136571Y525738D02*
X1136317Y525368D01*
G01X1123282Y508640D02*
X1123536Y509010D01*
G01X1123269Y509615D02*
X1123491Y509937D01*
G01X1132652Y524763D02*
X1132431Y524441D01*
G01X1132639Y525738D02*
X1132385Y525368D01*
G01X1119350Y508640D02*
X1119604Y509010D01*
G01X1119558Y509937D02*
X1119339Y509618D01*
G01X1128489Y524441D02*
X1128709Y524760D01*
G01X1128697Y525738D02*
X1128443Y525368D01*
G01X1115408Y508640D02*
X1115662Y509010D01*
G01X1115395Y509615D02*
X1115617Y509937D01*
G01X1124778Y524763D02*
X1124557Y524441D01*
G01X1124765Y525738D02*
X1124511Y525368D01*
G01X1111476Y508640D02*
X1111730Y509010D01*
G01X1111684Y509937D02*
X1111465Y509618D01*
G01X1120615Y524441D02*
X1120835Y524760D01*
G01X1120823Y525738D02*
X1120569Y525368D01*
G01X1107534Y508640D02*
X1107788Y509010D01*
G01X1107521Y509615D02*
X1107743Y509937D01*
G01X1144420Y522976D02*
X1142932Y520732D01*
G01X1139248Y509984D02*
X1139239Y509937D01*
G01X1140295Y524394D02*
X1140305Y524441D01*
G01X1135306Y509937D02*
X1135316Y509984D01*
G01X1136363Y524441D02*
X1136353Y524394D01*
G01X1131374Y509984D02*
X1131365Y509937D01*
G01X1132421Y524394D02*
X1132431Y524441D01*
G01X1127432Y509937D02*
X1127442Y509984D01*
G01X1128489Y524441D02*
X1128479Y524394D01*
G01X1123500Y509984D02*
X1123491Y509937D01*
G01X1124547Y524394D02*
X1124557Y524441D01*
G01X1119558Y509937D02*
X1119568Y509984D01*
G01X1138931Y519051D02*
X1138981Y520037D01*
G01X1138979Y520999D02*
X1138928Y520013D01*
G01X1136632Y513379D02*
X1136683Y514365D01*
G01X1136680Y515327D02*
X1136630Y514341D01*
G01X1134989Y519051D02*
X1135039Y520037D01*
G01X1135037Y520999D02*
X1134987Y520013D01*
G01X1132691Y513379D02*
X1132741Y514365D01*
G01X1132739Y515327D02*
X1132688Y514341D01*
G01X1131057Y519051D02*
X1131107Y520037D01*
G01X1131105Y520999D02*
X1131054Y520013D01*
G01X1128758Y513379D02*
X1128809Y514365D01*
G01X1128806Y515327D02*
X1128756Y514341D01*
G01X1127115Y519051D02*
X1127165Y520037D01*
G01X1127163Y520999D02*
X1127113Y520013D01*
G01X1124817Y513379D02*
X1124867Y514365D01*
G01X1124865Y515327D02*
X1124814Y514341D01*
G01X1123183Y519051D02*
X1123233Y520037D01*
G01X1123231Y520999D02*
X1123180Y520013D01*
G01X1120884Y513379D02*
X1120935Y514365D01*
G01X1120932Y515327D02*
X1120882Y514341D01*
G01X1119241Y519051D02*
X1119291Y520037D01*
G01X1119289Y520999D02*
X1119239Y520013D01*
G01X1116943Y513379D02*
X1116993Y514365D01*
G01X1116991Y515327D02*
X1116940Y514341D01*
G01X1136709Y519353D02*
X1136845Y525261D01*
G01X1136840Y526147D02*
X1136704Y520239D01*
G01X1134829Y508231D02*
X1134965Y514139D01*
G01X1134960Y515025D02*
X1134824Y509117D01*
G01X1132776Y519353D02*
X1132913Y525261D01*
G01X1132908Y526147D02*
X1132772Y520239D01*
G01X1130887Y508231D02*
X1131024Y514139D01*
G01X1131019Y515025D02*
X1130883Y509117D01*
G01X1128835Y519353D02*
X1128971Y525261D01*
G01X1128966Y526147D02*
X1128830Y520239D01*
G01X1126955Y508231D02*
X1127091Y514139D01*
G01X1127086Y515025D02*
X1126950Y509117D01*
G01X1124902Y519353D02*
X1125039Y525261D01*
G01X1125034Y526147D02*
X1124898Y520239D01*
G01X1123013Y508231D02*
X1123150Y514139D01*
G01X1123145Y515025D02*
X1123009Y509117D01*
G01X1120961Y519353D02*
X1121097Y525261D01*
G01X1121092Y526147D02*
X1120956Y520239D01*
G01X1119081Y508231D02*
X1119217Y514139D01*
G01X1119212Y515025D02*
X1119076Y509117D01*
G01X1117028Y519353D02*
X1117165Y525261D01*
G01X1117160Y526147D02*
X1117024Y520239D01*
G01X1115139Y508231D02*
X1115276Y514139D01*
G01X1115271Y515025D02*
X1115135Y509117D01*
G01X1136330Y509984D02*
X1136317Y509010D01*
G01X1135339Y524394D02*
X1135352Y525368D01*
G01X1132389Y509984D02*
X1132376Y509010D01*
G01X1131406Y524394D02*
X1131420Y525368D01*
G01X1128456Y509984D02*
X1128443Y509010D01*
G01X1127465Y524394D02*
X1127478Y525368D01*
G01X1124515Y509984D02*
X1124502Y509010D01*
G01X1123532Y524394D02*
X1123546Y525368D01*
G01X1120582Y509984D02*
X1120569Y509010D01*
G01X1119591Y524394D02*
X1119604Y525368D01*
G01X1116641Y509984D02*
X1116628Y509010D01*
G01X1115658Y524394D02*
X1115672Y525368D01*
G01X1137252Y523862D02*
Y528035D01*
G01Y506343D02*
Y510516D01*
G01X1137217Y508823D02*
Y507839D01*
G01X1137213Y508823D02*
Y507839D01*
G01Y526539D02*
Y525555D01*
G01X1137016Y509984D02*
Y503902D01*
G01Y530476D02*
Y524394D01*
G01X1136937Y507839D02*
Y526539D01*
G01X1136858Y508825D02*
Y507840D01*
G01Y526538D02*
Y525553D01*
G01X1136661Y525555D02*
Y530396D01*
G01Y503982D02*
Y508823D01*
G01X1136583Y524760D02*
Y525751D01*
G01Y508627D02*
Y509618D01*
G01X1136504Y504965D02*
Y503902D01*
G01Y530476D02*
Y529413D01*
G01X1136228Y503902D02*
Y504886D01*
G01Y530476D02*
Y529492D01*
G01X1135441Y504886D02*
Y503902D01*
G01Y530476D02*
Y529492D01*
G01X1135165Y504965D02*
Y503902D01*
G01Y530476D02*
Y529413D01*
G01X1135087Y509618D02*
Y508627D01*
G01Y525751D02*
Y524760D01*
G01X1135008Y525555D02*
Y530396D01*
G01Y503982D02*
Y508823D01*
G01X1134811Y525553D02*
Y526538D01*
G01Y507840D02*
Y508825D01*
G01X1134732Y526539D02*
Y507839D01*
G01X1134654Y509984D02*
Y503902D01*
G01Y530476D02*
Y524394D01*
G01X1134457Y508823D02*
Y507839D01*
G01Y526539D02*
Y525555D01*
G01X1134452Y526539D02*
Y525555D01*
G01X1134417Y510516D02*
Y506343D01*
G01Y528035D02*
Y523862D01*
G01X1133315D02*
Y528035D01*
G01Y506343D02*
Y510516D01*
G01X1133280Y526539D02*
Y525555D01*
G01X1133276Y508823D02*
Y507839D01*
G01X1133271Y508823D02*
Y507839D01*
G01X1133079Y509984D02*
Y503902D01*
G01Y530476D02*
Y524394D01*
G01X1133000Y507839D02*
Y526539D01*
G01X1132926Y526538D02*
Y525553D01*
G01X1132917Y508825D02*
Y507840D01*
G01X1132724Y521698D02*
Y526539D01*
G01Y507839D02*
Y512680D01*
G01X1132650Y524760D02*
Y525751D01*
G01X1132641Y508627D02*
Y509618D01*
G01X1132567Y512760D02*
Y511696D01*
G01Y522681D02*
Y521618D01*
G01X1132291D02*
Y522602D01*
G01Y512760D02*
Y511776D01*
G01X1131504Y512760D02*
Y511776D01*
G01Y522602D02*
Y521618D01*
G01X1131228Y512760D02*
Y511696D01*
G01Y522682D02*
Y521618D01*
G01X1131154Y525751D02*
Y524760D01*
G01X1131145Y509618D02*
Y508627D01*
G01X1131071Y521698D02*
Y526539D01*
G01Y507839D02*
Y512680D01*
G01X1130879Y525553D02*
Y526538D01*
G01X1130869Y507840D02*
Y508825D01*
G01X1130795Y526539D02*
Y507839D01*
G01X1130717Y509984D02*
Y503902D01*
G01Y530476D02*
Y524394D01*
G01X1130524Y526539D02*
Y525555D01*
G01X1130520Y526539D02*
Y525555D01*
G01X1130515Y508823D02*
Y507839D01*
G01X1130480Y510516D02*
Y506343D01*
G01Y528035D02*
Y523862D01*
G01X1129378D02*
Y528035D01*
G01Y506343D02*
Y510516D01*
G01X1129343Y508823D02*
Y507839D01*
G01X1129339Y508823D02*
Y507839D01*
G01Y526539D02*
Y525555D01*
G01X1129142Y509984D02*
Y503902D01*
G01Y530476D02*
Y524394D01*
G01X1129063Y507839D02*
Y526539D01*
G01X1128984Y508825D02*
Y507840D01*
G01Y526538D02*
Y525553D01*
G01X1128787Y525555D02*
Y530396D01*
G01Y503982D02*
Y508823D01*
G01X1128709Y524760D02*
Y525751D01*
G01Y508627D02*
Y509618D01*
G01X1128630Y504965D02*
Y503902D01*
G01Y530476D02*
Y529413D01*
G01X1128354Y503902D02*
Y504886D01*
G01Y530476D02*
Y529492D01*
G01X1127567Y504886D02*
Y503902D01*
G01Y530476D02*
Y529492D01*
G01X1127291Y504965D02*
Y503902D01*
G01Y530476D02*
Y529413D01*
G01X1127213Y509618D02*
Y508627D01*
G01Y525751D02*
Y524760D01*
G01X1127134Y525555D02*
Y530396D01*
G01Y503982D02*
Y508823D01*
G01X1126937Y525553D02*
Y526538D01*
G01Y507840D02*
Y508825D01*
G01X1126858Y526539D02*
Y507839D01*
G01X1126780Y509984D02*
Y503902D01*
G01Y530476D02*
Y524394D01*
G01X1126583Y508823D02*
Y507839D01*
G01Y526539D02*
Y525555D01*
G01X1126578Y526539D02*
Y525555D01*
G01X1126543Y510516D02*
Y506343D01*
G01Y528035D02*
Y523862D01*
G01X1125441D02*
Y528035D01*
G01Y506343D02*
Y510516D01*
G01X1125406Y526539D02*
Y525555D01*
G01X1125402Y508823D02*
Y507839D01*
G01X1125397Y508823D02*
Y507839D01*
G01X1125205Y509984D02*
Y503902D01*
G01Y530476D02*
Y524394D01*
G01X1125126Y507839D02*
Y526539D01*
G01X1125052Y526538D02*
Y525553D01*
G01X1125043Y508825D02*
Y507840D01*
G01X1124850Y521698D02*
Y526539D01*
G01Y507839D02*
Y512680D01*
G01X1124776Y524760D02*
Y525751D01*
G01X1124767Y508627D02*
Y509618D01*
G01X1124693Y512760D02*
Y511696D01*
G01Y522681D02*
Y521618D01*
G01X1124417D02*
Y522602D01*
G01Y512760D02*
Y511776D01*
G01X1123630Y512760D02*
Y511776D01*
G01Y522602D02*
Y521618D01*
G01X1123354Y512760D02*
Y511696D01*
G01Y522682D02*
Y521618D01*
G01X1123280Y525751D02*
Y524760D01*
G01X1123271Y509618D02*
Y508627D01*
G01X1123197Y521698D02*
Y526539D01*
G01Y507839D02*
Y512680D01*
G01X1123005Y525553D02*
Y526538D01*
G01X1122995Y507840D02*
Y508825D01*
G01X1122921Y526539D02*
Y507839D01*
G01X1122843Y509984D02*
Y503902D01*
G01Y530476D02*
Y524394D01*
G01X1122650Y526539D02*
Y525555D01*
G01X1122646Y526539D02*
Y525555D01*
G01X1122641Y508823D02*
Y507839D01*
G01X1122606Y510516D02*
Y506343D01*
G01Y528035D02*
Y523862D01*
G01X1121504D02*
Y528035D01*
G01Y506343D02*
Y510516D01*
G01X1121469Y508823D02*
Y507839D01*
G01X1121465Y508823D02*
Y507839D01*
G01Y526539D02*
Y525555D01*
G01X1121268Y509984D02*
Y503902D01*
G01Y530476D02*
Y524394D01*
G01X1121189Y507839D02*
Y526539D01*
G01X1121110Y508825D02*
Y507840D01*
G01Y526538D02*
Y525553D01*
G01X1120913Y525555D02*
Y530396D01*
G01Y503982D02*
Y508823D01*
G01X1120835Y524760D02*
Y525751D01*
G01Y508627D02*
Y509618D01*
G01X1120756Y504965D02*
Y503902D01*
G01Y530476D02*
Y529413D01*
G01X1120480Y503902D02*
Y504886D01*
G01Y530476D02*
Y529492D01*
G01X1119693Y504886D02*
Y503902D01*
G01Y530476D02*
Y529492D01*
G01X1119417Y504965D02*
Y503902D01*
G01Y530476D02*
Y529413D01*
G01X1119339Y509618D02*
Y508627D01*
G01Y525751D02*
Y524760D01*
G01X1119260Y525555D02*
Y530396D01*
G01Y503982D02*
Y508823D01*
G01X1119063Y507840D02*
Y508825D01*
G01Y525553D02*
Y526538D01*
G01X1118984Y526539D02*
Y507839D01*
G01X1118906Y509984D02*
Y503902D01*
G01Y530476D02*
Y524394D01*
G01X1118709Y508823D02*
Y507839D01*
G01Y526539D02*
Y525555D01*
G01X1118704Y526539D02*
Y525555D01*
G01X1118669Y510516D02*
Y506343D01*
G01Y528035D02*
Y523862D01*
G01X1117567D02*
Y528035D01*
G01Y506343D02*
Y510516D01*
G01X1117532Y526539D02*
Y525555D01*
G01X1117528Y508823D02*
Y507839D01*
G01X1117523Y508823D02*
Y507839D01*
G01X1117331Y509984D02*
Y503902D01*
G01Y530476D02*
Y524394D01*
G01X1117252Y507839D02*
Y526539D01*
G01X1117178Y526538D02*
Y525553D01*
G01X1117169Y508825D02*
Y507840D01*
G01X1116976Y521698D02*
Y526539D01*
G01Y507839D02*
Y512680D01*
G01X1116902Y524760D02*
Y525751D01*
G01X1116893Y508627D02*
Y509618D01*
G01X1116819Y512760D02*
Y511696D01*
G01Y522681D02*
Y521618D01*
G01X1116543D02*
Y522602D01*
G01Y512760D02*
Y511776D01*
G01X1115756Y521618D02*
Y522602D01*
G01Y512760D02*
Y511776D01*
G01X1115480Y512760D02*
Y511696D01*
G01Y522682D02*
Y521618D01*
G01X1115406Y525751D02*
Y524760D01*
G01X1115397Y509618D02*
Y508627D01*
G01X1115323Y521698D02*
Y526539D01*
G01Y507839D02*
Y512680D01*
G01X1115131Y525553D02*
Y526538D01*
G01X1115121Y507840D02*
Y508825D01*
G01X1115047Y526539D02*
Y507839D01*
G01X1114968Y509984D02*
Y503902D01*
G01Y530476D02*
Y524394D01*
G01X1114776Y526539D02*
Y525555D01*
G01X1114772Y526539D02*
Y525555D01*
G01X1114767Y508823D02*
Y507839D01*
G01X1114732Y510516D02*
Y506343D01*
G01Y528035D02*
Y523862D01*
G01X1113630D02*
Y528035D01*
G01Y506343D02*
Y510516D01*
G01X1113595Y508823D02*
Y507839D01*
G01X1113591Y508823D02*
Y507839D01*
G01Y526539D02*
Y525555D01*
G01X1113394Y509984D02*
Y503902D01*
G01Y530476D02*
Y524394D01*
G01X1113315Y507839D02*
Y526539D01*
G01X1113236Y508825D02*
Y507840D01*
G01Y526538D02*
Y525553D01*
G01X1113039Y525555D02*
Y530396D01*
G01Y503982D02*
Y508823D01*
G01X1112961Y524760D02*
Y525751D01*
G01Y508627D02*
Y509618D01*
G01X1112882Y504965D02*
Y503902D01*
G01Y530476D02*
Y529413D01*
G01X1136317Y525368D02*
X1136330Y524394D01*
G01X1135352Y509010D02*
X1135339Y509984D01*
G01X1132385Y525368D02*
X1132398Y524394D01*
G01X1131410Y509010D02*
X1131397Y509984D01*
G01X1128443Y525368D02*
X1128456Y524394D01*
G01X1127478Y509010D02*
X1127465Y509984D01*
G01X1124511Y525368D02*
X1124524Y524394D01*
G01X1123536Y509010D02*
X1123523Y509984D01*
G01X1120569Y525368D02*
X1120582Y524394D01*
G01X1119604Y509010D02*
X1119591Y509984D01*
G01X1116637Y525368D02*
X1116650Y524394D01*
G01X1115662Y509010D02*
X1115649Y509984D01*
G01X1112695Y525368D02*
X1112708Y524394D01*
G01X1134965Y520239D02*
X1134829Y526147D01*
G01X1134824Y525261D02*
X1134960Y519353D01*
G01X1132903Y509117D02*
X1132767Y515025D01*
G01X1132762Y514139D02*
X1132899Y508231D01*
G01X1131033Y520239D02*
X1130897Y526147D01*
G01X1130892Y525261D02*
X1131028Y519353D01*
G01X1128971Y509117D02*
X1128835Y515025D01*
G01X1128830Y514139D02*
X1128966Y508231D01*
G01X1127091Y520239D02*
X1126955Y526147D01*
G01X1126950Y525261D02*
X1127086Y519353D01*
G01X1125029Y509117D02*
X1124893Y515025D01*
G01X1124888Y514139D02*
X1125025Y508231D01*
G01X1123159Y520239D02*
X1123023Y526147D01*
G01X1123018Y525261D02*
X1123154Y519353D01*
G01X1121097Y509117D02*
X1120961Y515025D01*
G01X1120956Y514139D02*
X1121092Y508231D01*
G01X1119217Y520239D02*
X1119081Y526147D01*
G01X1119076Y525261D02*
X1119212Y519353D01*
G01X1117155Y509117D02*
X1117019Y515025D01*
G01X1117014Y514139D02*
X1117151Y508231D01*
G01X1115285Y520239D02*
X1115149Y526147D01*
G01X1115144Y525261D02*
X1115280Y519353D01*
G01X1113223Y509117D02*
X1113087Y515025D01*
G01X1113082Y514139D02*
X1113218Y508231D01*
G01X1132750Y520013D02*
X1132700Y520999D01*
G01X1132698Y520037D02*
X1132748Y519051D01*
G01X1131098Y514341D02*
X1131047Y515327D01*
G01X1131045Y514365D02*
X1131095Y513379D01*
G01X1128809Y520013D02*
X1128758Y520999D01*
G01X1128756Y520037D02*
X1128806Y519051D01*
G01X1127165Y514341D02*
X1127115Y515327D01*
G01X1127113Y514365D02*
X1127163Y513379D01*
G01X1124876Y520013D02*
X1124826Y520999D01*
G01X1124824Y520037D02*
X1124874Y519051D01*
G01X1123224Y514341D02*
X1123173Y515327D01*
G01X1123171Y514365D02*
X1123221Y513379D01*
G01X1120935Y520013D02*
X1120884Y520999D01*
G01X1120882Y520037D02*
X1120932Y519051D01*
G01X1119291Y514341D02*
X1119241Y515327D01*
G01X1119239Y514365D02*
X1119289Y513379D01*
G01X1117002Y520013D02*
X1116952Y520999D01*
G01X1116950Y520037D02*
X1117000Y519051D01*
G01X1115350Y514341D02*
X1115299Y515327D01*
G01X1115297Y514365D02*
X1115347Y513379D01*
G01X1113061Y520013D02*
X1113010Y520999D01*
G01X1113008Y520037D02*
X1113058Y519051D01*
G01X1111417Y514341D02*
X1111367Y515327D01*
G01X1111365Y514365D02*
X1111415Y513379D01*
G01X1093020Y536519D02*
X1092528Y535932D01*
G01Y536603D02*
X1093020Y537189D01*
G01X1116904Y524763D02*
X1116683Y524441D01*
G01X1116891Y525738D02*
X1116637Y525368D01*
G01X1103602Y508640D02*
X1103856Y509010D01*
G01X1103810Y509937D02*
X1103591Y509618D01*
G01X1112741Y524441D02*
X1112961Y524760D01*
G01X1112949Y525738D02*
X1112695Y525368D01*
G01X1099660Y508640D02*
X1099914Y509010D01*
G01X1099647Y509615D02*
X1099869Y509937D01*
G01X1109030Y524763D02*
X1108809Y524441D01*
G01X1109017Y525738D02*
X1108763Y525368D01*
G01X1104867Y524441D02*
X1105087Y524760D01*
G01X1105075Y525738D02*
X1104821Y525368D01*
G01X1101156Y524763D02*
X1100935Y524441D01*
G01X1101143Y525738D02*
X1100889Y525368D01*
G01X1094957Y513646D02*
X1093000Y510693D01*
G01X1120615Y524441D02*
X1120605Y524394D01*
G01X1115626Y509984D02*
X1115617Y509937D01*
G01X1116673Y524394D02*
X1116683Y524441D01*
G01X1111684Y509937D02*
X1111694Y509984D01*
G01X1112741Y524441D02*
X1112731Y524394D01*
G01X1107752Y509984D02*
X1107743Y509937D01*
G01X1108799Y524394D02*
X1108809Y524441D01*
G01X1103810Y509937D02*
X1103820Y509984D01*
G01X1104867Y524441D02*
X1104857Y524394D01*
G01X1099878Y509984D02*
X1099869Y509937D01*
G01X1100925Y524394D02*
X1100935Y524441D01*
G01X1115309Y519051D02*
X1115359Y520037D01*
G01X1115357Y520999D02*
X1115306Y520013D01*
G01X1113010Y513379D02*
X1113061Y514365D01*
G01X1113058Y515327D02*
X1113008Y514341D01*
G01X1111367Y519051D02*
X1111417Y520037D01*
G01X1111415Y520999D02*
X1111365Y520013D01*
G01X1109068Y513379D02*
X1109119Y514365D01*
G01X1109117Y515327D02*
X1109066Y514341D01*
G01X1107435Y519051D02*
X1107485Y520037D01*
G01X1107483Y520999D02*
X1107432Y520013D01*
G01X1105136Y513379D02*
X1105187Y514365D01*
G01X1105184Y515327D02*
X1105134Y514341D01*
G01X1103493Y519051D02*
X1103543Y520037D01*
G01X1103541Y520999D02*
X1103491Y520013D01*
G01X1101194Y513379D02*
X1101245Y514365D01*
G01X1101243Y515327D02*
X1101192Y514341D01*
G01X1099560Y519051D02*
X1099611Y520037D01*
G01X1099609Y520999D02*
X1099558Y520013D01*
G01X1113087Y519353D02*
X1113223Y525261D01*
G01X1113218Y526147D02*
X1113082Y520239D01*
G01X1111207Y508231D02*
X1111343Y514139D01*
G01X1111338Y515025D02*
X1111202Y509117D01*
G01X1109154Y519353D02*
X1109291Y525261D01*
G01X1109286Y526147D02*
X1109150Y520239D01*
G01X1107265Y508231D02*
X1107402Y514139D01*
G01X1107397Y515025D02*
X1107261Y509117D01*
G01X1105213Y519353D02*
X1105349Y525261D01*
G01X1105344Y526147D02*
X1105208Y520239D01*
G01X1103333Y508231D02*
X1103469Y514139D01*
G01X1103464Y515025D02*
X1103328Y509117D01*
G01X1101280Y519353D02*
X1101417Y525261D01*
G01X1101412Y526147D02*
X1101276Y520239D01*
G01X1099391Y508231D02*
X1099527Y514139D01*
G01X1099523Y515025D02*
X1099386Y509117D01*
G01X1112708Y509984D02*
X1112695Y509010D01*
G01X1111717Y524394D02*
X1111730Y525368D01*
G01X1108767Y509984D02*
X1108754Y509010D01*
G01X1107784Y524394D02*
X1107798Y525368D01*
G01X1104834Y509984D02*
X1104821Y509010D01*
G01X1103843Y524394D02*
X1103856Y525368D01*
G01X1100893Y509984D02*
X1100880Y509010D01*
G01X1099910Y524394D02*
X1099924Y525368D01*
G01X1112606Y503902D02*
Y504886D01*
G01Y530476D02*
Y529492D01*
G01X1111819Y504886D02*
Y503902D01*
G01Y530476D02*
Y529492D01*
G01X1111543Y504965D02*
Y503902D01*
G01Y530476D02*
Y529413D01*
G01X1111465Y509618D02*
Y508627D01*
G01Y525751D02*
Y524760D01*
G01X1111386Y525555D02*
Y530396D01*
G01Y503982D02*
Y508823D01*
G01X1111189Y525553D02*
Y526538D01*
G01Y507840D02*
Y508825D01*
G01X1111110Y526539D02*
Y507839D01*
G01X1111031Y509984D02*
Y503902D01*
G01Y530476D02*
Y524394D01*
G01X1110835Y508823D02*
Y507839D01*
G01Y526539D02*
Y525555D01*
G01X1110830Y526539D02*
Y525555D01*
G01X1110795Y510516D02*
Y506343D01*
G01Y528035D02*
Y523862D01*
G01X1109693D02*
Y528035D01*
G01Y506343D02*
Y510516D01*
G01X1109658Y526539D02*
Y525555D01*
G01X1109654Y508823D02*
Y507839D01*
G01X1109649Y508823D02*
Y507839D01*
G01X1109457Y509984D02*
Y503902D01*
G01Y530476D02*
Y524394D01*
G01X1109378Y507839D02*
Y526539D01*
G01X1109304Y526538D02*
Y525553D01*
G01X1109295Y508825D02*
Y507840D01*
G01X1109102Y521698D02*
Y526539D01*
G01Y507839D02*
Y512680D01*
G01X1109028Y524760D02*
Y525751D01*
G01X1109019Y508627D02*
Y509618D01*
G01X1108945Y512760D02*
Y511696D01*
G01Y522681D02*
Y521618D01*
G01X1108669D02*
Y522602D01*
G01Y512760D02*
Y511776D01*
G01X1107882Y521618D02*
Y522602D01*
G01Y512760D02*
Y511776D01*
G01X1107606Y512760D02*
Y511696D01*
G01Y522682D02*
Y521618D01*
G01X1107532Y525751D02*
Y524760D01*
G01X1107523Y509618D02*
Y508627D01*
G01X1107449Y521698D02*
Y526539D01*
G01Y507839D02*
Y512680D01*
G01X1107257Y525553D02*
Y526538D01*
G01X1107247Y507840D02*
Y508825D01*
G01X1107173Y526539D02*
Y507839D01*
G01X1107094Y509984D02*
Y503902D01*
G01Y530476D02*
Y524394D01*
G01X1106902Y526539D02*
Y525555D01*
G01X1106898Y526539D02*
Y525555D01*
G01X1106893Y508823D02*
Y507839D01*
G01X1106858Y510516D02*
Y506343D01*
G01Y528035D02*
Y523862D01*
G01X1105756D02*
Y528035D01*
G01Y506343D02*
Y510516D01*
G01X1105721Y508823D02*
Y507839D01*
G01X1105717Y508823D02*
Y507839D01*
G01Y526539D02*
Y525555D01*
G01X1105520Y509984D02*
Y503902D01*
G01Y530476D02*
Y524394D01*
G01X1105441Y507839D02*
Y526539D01*
G01X1105362Y508825D02*
Y507840D01*
G01Y526538D02*
Y525553D01*
G01X1105165Y525555D02*
Y530396D01*
G01Y503982D02*
Y508823D01*
G01X1105087Y524760D02*
Y525751D01*
G01Y508627D02*
Y509618D01*
G01X1105008Y504965D02*
Y503902D01*
G01Y530476D02*
Y529413D01*
G01X1104732Y503902D02*
Y504886D01*
G01Y530476D02*
Y529492D01*
G01X1103945Y504886D02*
Y503902D01*
G01Y530476D02*
Y529492D01*
G01X1103669Y504965D02*
Y503902D01*
G01Y530476D02*
Y529413D01*
G01X1103591Y509618D02*
Y508627D01*
G01Y525751D02*
Y524760D01*
G01X1103512Y525555D02*
Y530396D01*
G01Y503982D02*
Y508823D01*
G01X1103315Y525553D02*
Y526538D01*
G01Y507840D02*
Y508825D01*
G01X1103236Y526539D02*
Y507839D01*
G01X1103157Y509984D02*
Y503902D01*
G01Y530476D02*
Y524394D01*
G01X1102961Y508823D02*
Y507839D01*
G01Y526539D02*
Y525555D01*
G01X1102956Y526539D02*
Y525555D01*
G01X1102921Y510516D02*
Y506343D01*
G01Y528035D02*
Y523862D01*
G01X1101819D02*
Y528035D01*
G01Y506343D02*
Y510516D01*
G01X1101784Y526539D02*
Y525555D01*
G01X1101780Y508823D02*
Y507839D01*
G01X1101775Y508823D02*
Y507839D01*
G01X1101583Y509984D02*
Y503902D01*
G01Y530476D02*
Y524394D01*
G01X1101504Y507839D02*
Y526539D01*
G01X1101430Y526538D02*
Y525553D01*
G01X1101421Y508825D02*
Y507840D01*
G01X1101228Y521698D02*
Y526539D01*
G01Y507839D02*
Y512680D01*
G01X1101154Y524760D02*
Y525751D01*
G01X1101145Y508627D02*
Y509618D01*
G01X1101071Y512760D02*
Y511696D01*
G01Y522681D02*
Y521618D01*
G01X1100795D02*
Y522602D01*
G01Y512760D02*
Y511776D01*
G01X1100008Y512760D02*
Y511776D01*
G01Y522602D02*
Y521618D01*
G01X1099732Y512760D02*
Y511696D01*
G01Y522682D02*
Y521618D01*
G01X1099658Y525751D02*
Y524760D01*
G01X1099649Y509618D02*
Y508627D01*
G01X1099575Y521698D02*
Y526539D01*
G01Y507839D02*
Y512680D01*
G01X1099383Y525553D02*
Y526538D01*
G01X1099373Y507840D02*
Y508825D01*
G01X1099299Y526539D02*
Y507839D01*
G01X1099220Y509984D02*
Y503902D01*
G01Y530476D02*
Y524394D01*
G01X1099028Y526539D02*
Y525555D01*
G01X1099024Y526539D02*
Y525555D01*
G01X1099019Y508823D02*
Y507839D01*
G01X1098984Y510516D02*
Y506343D01*
G01Y528035D02*
Y523862D01*
G01X1096406Y520732D02*
Y513646D01*
G01X1095855Y531854D02*
Y528735D01*
G01X1094496Y513252D02*
Y521126D01*
G01X1094240Y510988D02*
Y505083D01*
G01Y529295D02*
Y523390D01*
G01X1093512Y537189D02*
Y533252D01*
G01X1093020D02*
Y536519D01*
G01X1093000Y523685D02*
Y510693D01*
G01X1092528Y535932D02*
Y536603D01*
G01X1092269Y531854D02*
Y528735D01*
G01X1090559Y521126D02*
Y513252D01*
G01X1089516Y510988D02*
Y505083D01*
G01Y529295D02*
Y523390D01*
G01X1111730Y509010D02*
X1111717Y509984D01*
G01X1108763Y525368D02*
X1108776Y524394D01*
G01X1107788Y509010D02*
X1107775Y509984D01*
G01X1104821Y525368D02*
X1104834Y524394D01*
G01X1103856Y509010D02*
X1103843Y509984D01*
G01X1100889Y525368D02*
X1100902Y524394D01*
G01X1099914Y509010D02*
X1099901Y509984D01*
G01X1111343Y520239D02*
X1111207Y526147D01*
G01X1111202Y525261D02*
X1111338Y519353D01*
G01X1109281Y509117D02*
X1109145Y515025D01*
G01X1109140Y514139D02*
X1109277Y508231D01*
G01X1107411Y520239D02*
X1107275Y526147D01*
G01X1107270Y525261D02*
X1107406Y519353D01*
G01X1105349Y509117D02*
X1105213Y515025D01*
G01X1105208Y514139D02*
X1105344Y508231D01*
G01X1103469Y520239D02*
X1103333Y526147D01*
G01X1103328Y525261D02*
X1103464Y519353D01*
G01X1101407Y509117D02*
X1101271Y515025D01*
G01X1101266Y514139D02*
X1101403Y508231D01*
G01X1099537Y520239D02*
X1099401Y526147D01*
G01X1099396Y525261D02*
X1099532Y519353D01*
G01X1109128Y520013D02*
X1109078Y520999D01*
G01X1109076Y520037D02*
X1109126Y519051D01*
G01X1107476Y514341D02*
X1107425Y515327D01*
G01X1107423Y514365D02*
X1107473Y513379D01*
G01X1105187Y520013D02*
X1105136Y520999D01*
G01X1105134Y520037D02*
X1105184Y519051D01*
G01X1103543Y514341D02*
X1103493Y515327D01*
G01X1103491Y514365D02*
X1103541Y513379D01*
G01X1101254Y520013D02*
X1101204Y520999D01*
G01X1101201Y520037D02*
X1101252Y519051D01*
G01X1099602Y514341D02*
X1099551Y515327D01*
G01X1099549Y514365D02*
X1099599Y513379D01*
G01X1088591Y533252D02*
X1089903Y537189D01*
G01X1089411Y534257D02*
X1089083Y533252D01*
G01X1089493Y534592D02*
X1090231Y536854D01*
G01X1093492Y577243D02*
X1093082Y577159D01*
G01X1088735Y576237D02*
X1088325Y576154D01*
G01X1089227Y573724D02*
X1089637Y573808D01*
G01X1093902Y574143D02*
X1094312Y574227D01*
G01X1088407Y575735D02*
X1088735Y575819D01*
G01X1089555Y574227D02*
X1089227Y574143D01*
G01X1094312Y573808D02*
X1093984Y573724D01*
G01X1093000Y577578D02*
X1093574Y577661D01*
G01D02*
X1093738D01*
G01X1083978D02*
X1084470D01*
G01X1081189D02*
X1081681D01*
G01X1090293D02*
X1087505D01*
G01X1087915Y577243D02*
X1090293D01*
G01X1093820D02*
X1093492D01*
G01X1135835Y577012D02*
X1155520D01*
G01X1112213D02*
X1131898D01*
G01X1108276D02*
X1088591D01*
G01X1092672Y576740D02*
X1092262D01*
G01X1101612Y576405D02*
X1101940D01*
G01X1100300D02*
X1100628D01*
G01X1099480D02*
X1099890D01*
G01X1097921D02*
X1098249D01*
G01X1096609D02*
X1096937D01*
G01X1095789D02*
X1096199D01*
G01X1089227Y576237D02*
X1088735D01*
G01X1081681Y576070D02*
X1083978D01*
G01X1096773D02*
X1096609D01*
G01X1098085D02*
X1097839D01*
G01X1100464D02*
X1100300D01*
G01X1101776D02*
X1101530D01*
G01X1093492Y575902D02*
X1093820D01*
G01X1088735Y575819D02*
X1089227D01*
G01X1083978Y575567D02*
X1081681D01*
G01X1093820D02*
X1093492D01*
G01X1087505Y575484D02*
X1088079D01*
G01X1087997Y574730D02*
X1087505D01*
G01X1092180Y574646D02*
X1092590D01*
G01X1093410Y574143D02*
X1093902D01*
G01X1091114D02*
X1091524D01*
G01X1089227D02*
X1088735D01*
G01Y573724D02*
X1089227D01*
G01X1081681D02*
X1081189D01*
G01X1084470D02*
X1083978D01*
G01X1091524D02*
X1091114D01*
G01X1093984D02*
X1093328D01*
G01X1096199D02*
X1095789D01*
G01X1097511D02*
X1097101D01*
G01X1099890D02*
X1099480D01*
G01X1098823D02*
X1098413D01*
G01X1101202D02*
X1100792D01*
G01X1102514D02*
X1102104D01*
G01X1446858Y573055D02*
X1080717D01*
G01X1094312Y575484D02*
X1093820Y575567D01*
G01X1093738Y577661D02*
X1094312Y577578D01*
G01X1089227Y575819D02*
X1089555Y575735D01*
G01X1093328Y573724D02*
X1093000Y573808D01*
G01X1088735Y574143D02*
X1088407Y574227D01*
G01X1094230Y577159D02*
X1093820Y577243D01*
G01X1089637Y576154D02*
X1089227Y576237D01*
G01X1093000Y574227D02*
X1093410Y574143D01*
G01X1088325Y573808D02*
X1088735Y573724D01*
G01X1094476Y575735D02*
X1094886Y575567D01*
G01X1101940Y576405D02*
X1102186Y576321D01*
G01X1100628Y576405D02*
X1100874Y576321D01*
G01X1098249Y576405D02*
X1098495Y576321D01*
G01X1096937Y576405D02*
X1097183Y576321D01*
G01X1101940Y575986D02*
X1101776Y576070D01*
G01X1100628Y575986D02*
X1100464Y576070D01*
G01X1098249Y575986D02*
X1098085Y576070D01*
G01X1094312Y577578D02*
X1094640Y577410D01*
G01X1096937Y575986D02*
X1096773Y576070D01*
G01X1092836Y574311D02*
X1093000Y574227D01*
G01Y573808D02*
X1092672Y573976D01*
G01X1085700Y575735D02*
X1086848Y575148D01*
G01X1094476Y576991D02*
X1094230Y577159D01*
G01X1090047Y575902D02*
X1089637Y576154D01*
G01X1087915Y574059D02*
X1088325Y573808D01*
G01X1086684Y574897D02*
X1085126Y575735D01*
G01X1094558Y575316D02*
X1094312Y575484D01*
G01X1092672Y573976D02*
X1092426Y574143D01*
G01X1089555Y575735D02*
X1089801Y575567D01*
G01X1088407Y574227D02*
X1088161Y574395D01*
G01X1102186Y576321D02*
X1102350Y576154D01*
G01X1102022Y575902D02*
X1101940Y575986D01*
G01X1100874Y576321D02*
X1101120Y576070D01*
G01X1100710Y575902D02*
X1100628Y575986D01*
G01X1098495Y576321D02*
X1098659Y576154D01*
G01X1098331Y575902D02*
X1098249Y575986D01*
G01X1097183Y576321D02*
X1097429Y576070D01*
G01X1097019Y575902D02*
X1096937Y575986D01*
G01X1094640Y577410D02*
X1094968Y577075D01*
G01X1092672Y574478D02*
X1092836Y574311D01*
G01X1094640Y576740D02*
X1094476Y576991D01*
G01X1094886Y575567D02*
X1095051Y575316D01*
G01X1092426Y574143D02*
X1092262Y574395D01*
G01X1089801Y575567D02*
X1089965Y575316D01*
G01X1086684Y576572D02*
X1086848Y576321D01*
G01X1090293Y575567D02*
X1090047Y575902D01*
G01X1087669Y574395D02*
X1087915Y574059D01*
G01X1102104Y575735D02*
X1102022Y575902D01*
G01X1100792Y575735D02*
X1100710Y575902D01*
G01X1098413Y575735D02*
X1098331Y575902D01*
G01X1097101Y575735D02*
X1097019Y575902D01*
G01X1094722Y574981D02*
X1094558Y575316D01*
G01X1092590Y574646D02*
X1092672Y574478D01*
G01X1092262Y574395D02*
X1092180Y574646D01*
G01X1102350Y576154D02*
X1102514Y575735D01*
G01X1098659Y576154D02*
X1098823Y575735D01*
G01X1090457Y575148D02*
X1090293Y575567D01*
G01X1088161Y574395D02*
X1087997Y574730D01*
G01X1087505D02*
X1087669Y574395D01*
G01X1138984Y582524D02*
Y577012D01*
G01X1094968Y577075D02*
X1095051Y576740D01*
G01Y575316D02*
X1095133Y574981D01*
G01X1089965Y575316D02*
X1090047Y575065D01*
G01X1101366Y576321D02*
X1101612Y576405D01*
G01X1100300Y576070D02*
X1100054Y575986D01*
G01Y576321D02*
X1100300Y576405D01*
G01X1097675Y576321D02*
X1097921Y576405D01*
G01X1096609Y576070D02*
X1096363Y575986D01*
G01Y576321D02*
X1096609Y576405D01*
G01X1093820Y575902D02*
X1094312Y576070D01*
G01X1135835Y582524D02*
Y577012D01*
G01X1131898Y582524D02*
Y577012D01*
G01X1128748Y582524D02*
Y577012D01*
G01X1115362Y582524D02*
Y577012D01*
G01X1101530Y576070D02*
X1101366Y575986D01*
G01X1094640Y573976D02*
X1094312Y573808D01*
G01Y574227D02*
X1094476Y574311D01*
G01X1097839Y576070D02*
X1097675Y575986D01*
G01X1092672Y577410D02*
X1093000Y577578D01*
G01X1086848Y576321D02*
X1085700Y575735D01*
G01X1085126D02*
X1086684Y576572D01*
G01X1089637Y573808D02*
X1090047Y574059D01*
G01X1088325Y576154D02*
X1087915Y575902D01*
G01X1094886Y574143D02*
X1094640Y573976D01*
G01X1089801Y574395D02*
X1089555Y574227D01*
G01X1112213Y582524D02*
Y577012D01*
G01X1108276Y582524D02*
Y577012D01*
G01X1105126Y582524D02*
Y577012D01*
G01X1102514Y575735D02*
Y573724D01*
G01X1102104D02*
Y575735D01*
G01X1101202D02*
Y573724D01*
G01X1100792D02*
Y575735D01*
G01X1099890Y575819D02*
Y573724D01*
G01Y576405D02*
Y576154D01*
G01X1099480Y573724D02*
Y576405D01*
G01X1098823Y575735D02*
Y573724D01*
G01X1098413D02*
Y575735D01*
G01X1097511D02*
Y573724D01*
G01X1097101D02*
Y575735D01*
G01X1096199Y575819D02*
Y573724D01*
G01Y576405D02*
Y576154D01*
G01X1095789Y573724D02*
Y576405D01*
G01X1095133Y574981D02*
Y574646D01*
G01X1095051Y576740D02*
Y576572D01*
G01X1094722Y574646D02*
Y574981D01*
G01X1094640Y576572D02*
Y576740D01*
G01X1093492Y575567D02*
Y575902D01*
G01X1091740Y582524D02*
Y577012D01*
G01X1091524Y574143D02*
Y573724D01*
G01X1091114D02*
Y574143D01*
G01X1090457Y574813D02*
Y575148D01*
G01X1090293Y577243D02*
Y577661D01*
G01X1090047Y575065D02*
Y574897D01*
G01X1088591Y577012D02*
Y611854D01*
G01X1093082Y577159D02*
X1092836Y576991D01*
G01X1094804Y575986D02*
X1094476Y575735D01*
G01X1088079Y575484D02*
X1088407Y575735D01*
G01X1101366Y575986D02*
X1101284Y575902D01*
G01X1101120Y576070D02*
X1101366Y576321D01*
G01X1100054Y575986D02*
X1099890Y575819D01*
G01Y576154D02*
X1100054Y576321D01*
G01X1097675Y575986D02*
X1097593Y575902D01*
G01X1097429Y576070D02*
X1097675Y576321D01*
G01X1096363Y575986D02*
X1096199Y575819D01*
G01X1094476Y574311D02*
X1094640Y574478D01*
G01X1096199Y576154D02*
X1096363Y576321D01*
G01X1094312Y576070D02*
X1094476Y576237D01*
G01X1092344Y577075D02*
X1092672Y577410D01*
G01X1095051Y574395D02*
X1094886Y574143D01*
G01X1094968Y576237D02*
X1094804Y575986D01*
G01X1101284Y575902D02*
X1101202Y575735D01*
G01X1097593Y575902D02*
X1097511Y575735D01*
G01X1094640Y574478D02*
X1094722Y574646D01*
G01X1094476Y576237D02*
X1094640Y576572D01*
G01X1095133Y574646D02*
X1095051Y574395D01*
G01X1090047Y574897D02*
X1089965Y574646D01*
G01X1095051Y576572D02*
X1094968Y576237D01*
G01X1092262Y576740D02*
X1092344Y577075D01*
G01X1087915Y575902D02*
Y577243D01*
G01X1087505Y577661D02*
Y575484D01*
G01X1084470Y577661D02*
Y573724D01*
G01X1083978Y576070D02*
Y577661D01*
G01Y573724D02*
Y575567D01*
G01X1081681D02*
Y573724D01*
G01Y577661D02*
Y576070D01*
G01X1081189Y573724D02*
Y577661D01*
G01X1080717Y573055D02*
Y616008D01*
G01X1090047Y574059D02*
X1090293Y574395D01*
G01X1092836Y576991D02*
X1092672Y576740D01*
G01X1089965Y574646D02*
X1089801Y574395D01*
G01X1086848Y575148D02*
X1086684Y574897D01*
G01X1090293Y574395D02*
X1090457Y574813D01*
G01X1073148Y597055D02*
X1073476D01*
G01X1071835D02*
X1072163D01*
G01X1071015D02*
X1071425D01*
G01X1069457D02*
X1069785D01*
G01X1068144D02*
X1068472D01*
G01X1068308Y596719D02*
X1068144D01*
G01X1069621D02*
X1069375D01*
G01X1071999D02*
X1071835D01*
G01X1073312D02*
X1073066D01*
G01X1069047Y594374D02*
X1068636D01*
G01X1071425D02*
X1071015D01*
G01X1070359D02*
X1069949D01*
G01X1072738D02*
X1072327D01*
G01X1074050D02*
X1073640D01*
G01X1073476Y597055D02*
X1073722Y596971D01*
G01X1072163Y597055D02*
X1072409Y596971D01*
G01X1069785Y597055D02*
X1070031Y596971D01*
G01X1068472Y597055D02*
X1068718Y596971D01*
G01X1073476Y596636D02*
X1073312Y596719D01*
G01X1072163Y596636D02*
X1071999Y596719D01*
G01X1069785Y596636D02*
X1069621Y596719D01*
G01X1068472Y596636D02*
X1068308Y596719D01*
G01X1073722Y596971D02*
X1073886Y596803D01*
G01X1073558Y596552D02*
X1073476Y596636D01*
G01X1072409Y596971D02*
X1072656Y596719D01*
G01X1072245Y596552D02*
X1072163Y596636D01*
G01X1070031Y596971D02*
X1070195Y596803D01*
G01X1069867Y596552D02*
X1069785Y596636D01*
G01X1068718Y596971D02*
X1068965Y596719D01*
G01X1068554Y596552D02*
X1068472Y596636D01*
G01X1073886Y596803D02*
X1074050Y596384D01*
G01X1073640D02*
X1073558Y596552D01*
G01X1072327Y596384D02*
X1072245Y596552D01*
G01X1069949Y596384D02*
X1069867Y596552D01*
G01X1068636Y596384D02*
X1068554Y596552D01*
G01X1070195Y596803D02*
X1070359Y596384D01*
G01X1072902Y596971D02*
X1073148Y597055D01*
G01X1071835Y596719D02*
X1071589Y596636D01*
G01Y596971D02*
X1071835Y597055D01*
G01X1069211Y596971D02*
X1069457Y597055D01*
G01X1068144Y596719D02*
X1067898Y596636D01*
G01Y596971D02*
X1068144Y597055D01*
G01X1073066Y596719D02*
X1072902Y596636D01*
G01X1069375Y596719D02*
X1069211Y596636D01*
G01X1074050Y596384D02*
Y594374D01*
G01X1073640D02*
Y596384D01*
G01X1072738D02*
Y594374D01*
G01X1072327D02*
Y596384D01*
G01X1071425Y596468D02*
Y594374D01*
G01Y597055D02*
Y596803D01*
G01X1071015Y594374D02*
Y597055D01*
G01X1070359Y596384D02*
Y594374D01*
G01X1069949D02*
Y596384D01*
G01X1069047D02*
Y594374D01*
G01X1068636D02*
Y596384D01*
G01X1067734Y596468D02*
Y594374D01*
G01Y597055D02*
Y596803D01*
G01X1072902Y596636D02*
X1072820Y596552D01*
G01X1072656Y596719D02*
X1072902Y596971D01*
G01X1071589Y596636D02*
X1071425Y596468D01*
G01Y596803D02*
X1071589Y596971D01*
G01X1069211Y596636D02*
X1069129Y596552D01*
G01X1068965Y596719D02*
X1069211Y596971D01*
G01X1067898Y596636D02*
X1067734Y596468D01*
G01Y596803D02*
X1067898Y596971D01*
G01X1072820Y596552D02*
X1072738Y596384D01*
G01X1069129Y596552D02*
X1069047Y596384D01*
G01X1105087Y605754D02*
Y605751D01*
G01X1105088Y605756D02*
X1105087Y605754D01*
G01X1105088Y605757D02*
Y605756D01*
G01X1112961Y605754D02*
Y605751D01*
G01X1112962Y605756D02*
X1112961Y605754D01*
G01X1112962Y605757D02*
Y605756D01*
G01X1099382Y588965D02*
X1099386Y589117D01*
G01X1099378Y588867D02*
X1099382Y588965D01*
G01X1099373Y588825D02*
X1099378Y588867D01*
G01X1101421Y605413D02*
X1101417Y605261D01*
G01X1101425Y605511D02*
X1101421Y605413D01*
G01X1101430Y605553D02*
X1101425Y605511D01*
G01X1101418Y606353D02*
X1101412Y606147D01*
G01X1101424Y606485D02*
X1101418Y606353D01*
G01X1101430Y606538D02*
X1101424Y606485D01*
G01X1099386Y588025D02*
X1099391Y588231D01*
G01X1099379Y587893D02*
X1099386Y588025D01*
G01X1099373Y587840D02*
X1099379Y587893D01*
G01X1099647Y604209D02*
X1099646Y603807D01*
G01X1099649Y604537D02*
X1099647Y604209D01*
G01X1099653Y604733D02*
X1099649Y604537D01*
G01X1099658Y604763D02*
X1099653Y604733D01*
G01X1101157Y590169D02*
X1101158Y590571D01*
G01X1101154Y589841D02*
X1101157Y590169D01*
G01X1101150Y589645D02*
X1101154Y589841D01*
G01X1101145Y589615D02*
X1101150Y589645D01*
G01X1107521Y604209D02*
X1107520Y603807D01*
G01X1107523Y604537D02*
X1107521Y604209D01*
G01X1107527Y604733D02*
X1107523Y604537D01*
G01X1107532Y604763D02*
X1107527Y604733D01*
G01X1103590Y588624D02*
X1103591Y588627D01*
G01X1103589Y588622D02*
X1103590Y588624D01*
G01X1103589Y588621D02*
Y588622D01*
G01X1120835Y605754D02*
Y605751D01*
G01X1120836Y605756D02*
X1120835Y605754D01*
G01X1120836Y605757D02*
Y605756D01*
G01X1111464Y588624D02*
X1111465Y588627D01*
G01X1111463Y588622D02*
X1111464Y588624D01*
G01X1111463Y588621D02*
Y588622D01*
G01X1128709Y605754D02*
Y605751D01*
G01X1128710Y605756D02*
X1128709Y605754D01*
G01X1128710Y605757D02*
Y605756D01*
G01X1119338Y588624D02*
X1119339Y588627D01*
G01X1119337Y588622D02*
X1119338Y588624D01*
G01X1119337Y588621D02*
Y588622D01*
G01X1136583Y605754D02*
Y605751D01*
G01X1136584Y605756D02*
X1136583Y605754D01*
G01X1136584Y605757D02*
Y605756D01*
G01X1127212Y588624D02*
X1127213Y588627D01*
G01X1127211Y588622D02*
X1127212Y588624D01*
G01X1127211Y588621D02*
Y588622D01*
G01X1103579Y590197D02*
X1103578Y590571D01*
G01X1103581Y589887D02*
X1103579Y590197D01*
G01X1103585Y589680D02*
X1103581Y589887D01*
G01X1103589Y589606D02*
X1103585Y589680D01*
G01X1099389Y606485D02*
X1099383Y606538D01*
G01X1099395Y606353D02*
X1099389Y606485D01*
G01X1099401Y606147D02*
X1099395Y606353D01*
G01X1101414Y587893D02*
X1101421Y587840D01*
G01X1101408Y588025D02*
X1101414Y587893D01*
G01X1101403Y588231D02*
X1101408Y588025D01*
G01X1103321Y606485D02*
X1103315Y606538D01*
G01X1103327Y606353D02*
X1103321Y606485D01*
G01X1103333Y606147D02*
X1103327Y606353D01*
G01X1105356Y587893D02*
X1105362Y587840D01*
G01X1105350Y588025D02*
X1105356Y587893D01*
G01X1105344Y588231D02*
X1105350Y588025D01*
G01X1107263Y606485D02*
X1107257Y606538D01*
G01X1107269Y606353D02*
X1107263Y606485D01*
G01X1107275Y606147D02*
X1107269Y606353D01*
G01X1099387Y605511D02*
X1099383Y605553D01*
G01X1099392Y605413D02*
X1099387Y605511D01*
G01X1099396Y605261D02*
X1099392Y605413D01*
G01X1101416Y588867D02*
X1101421Y588825D01*
G01X1101412Y588965D02*
X1101416Y588867D01*
G01X1101407Y589117D02*
X1101412Y588965D01*
G01X1103320Y605511D02*
X1103315Y605553D01*
G01X1103324Y605413D02*
X1103320Y605511D01*
G01X1103328Y605261D02*
X1103324Y605413D01*
G01X1105358Y588867D02*
X1105362Y588825D01*
G01X1105353Y588965D02*
X1105358Y588867D01*
G01X1105349Y589117D02*
X1105353Y588965D01*
G01X1107261Y605511D02*
X1107257Y605553D01*
G01X1107266Y605413D02*
X1107261Y605511D01*
G01X1107270Y605261D02*
X1107266Y605413D01*
G01X1099644Y589645D02*
X1099649Y589615D01*
G01X1099640Y589841D02*
X1099644Y589645D01*
G01X1099637Y590169D02*
X1099640Y589841D01*
G01X1099636Y590571D02*
X1099637Y590169D01*
G01X1101159Y604733D02*
X1101154Y604763D01*
G01X1101163Y604537D02*
X1101159Y604733D01*
G01X1101166Y604209D02*
X1101163Y604537D01*
G01X1101167Y603807D02*
X1101166Y604209D01*
G01X1107518Y589645D02*
X1107523Y589615D01*
G01X1107514Y589841D02*
X1107518Y589645D01*
G01X1107511Y590169D02*
X1107514Y589841D01*
G01X1107510Y590571D02*
X1107511Y590169D01*
G01X1109033Y604733D02*
X1109028Y604763D01*
G01X1109037Y604537D02*
X1109033Y604733D01*
G01X1109040Y604209D02*
X1109037Y604537D01*
G01X1109041Y603807D02*
X1109040Y604209D01*
G01X1103580Y588770D02*
X1103589Y588621D01*
G01X1103573Y589184D02*
X1103580Y588770D01*
G01X1103569Y589804D02*
X1103573Y589184D01*
G01X1103567Y590552D02*
X1103569Y589804D01*
G01X1105097Y605608D02*
X1105088Y605757D01*
G01X1105104Y605193D02*
X1105097Y605608D01*
G01X1105108Y604573D02*
X1105104Y605193D01*
G01X1105110Y603826D02*
X1105108Y604573D01*
G01X1111454Y588770D02*
X1111463Y588621D01*
G01X1111447Y589184D02*
X1111454Y588770D01*
G01X1111443Y589804D02*
X1111447Y589184D01*
G01X1111441Y590552D02*
X1111443Y589804D01*
G01X1103585Y604698D02*
X1103589Y604772D01*
G01X1103581Y604491D02*
X1103585Y604698D01*
G01X1103579Y604181D02*
X1103581Y604491D01*
G01X1103578Y603807D02*
X1103579Y604181D01*
G01X1105092Y589680D02*
X1105088Y589606D01*
G01X1105096Y589887D02*
X1105092Y589680D01*
G01X1105098Y590197D02*
X1105096Y589887D01*
G01X1105099Y590571D02*
X1105098Y590197D01*
G01X1111459Y604698D02*
X1111463Y604772D01*
G01X1111455Y604491D02*
X1111459Y604698D01*
G01X1111453Y604181D02*
X1111455Y604491D01*
G01X1111452Y603807D02*
X1111453Y604181D01*
G01X1112967Y589680D02*
X1112962Y589606D01*
G01X1112970Y589887D02*
X1112967Y589680D01*
G01X1112972Y590197D02*
X1112970Y589887D01*
G01X1112973Y590571D02*
X1112972Y590197D01*
G01X1103569Y604573D02*
X1103567Y603826D01*
G01X1103573Y605193D02*
X1103569Y604573D01*
G01X1103580Y605608D02*
X1103573Y605193D01*
G01X1103589Y605757D02*
X1103580Y605608D01*
G01X1105108Y589804D02*
X1105110Y590552D01*
G01X1105104Y589184D02*
X1105108Y589804D01*
G01X1105097Y588770D02*
X1105104Y589184D01*
G01X1105088Y588621D02*
X1105097Y588770D01*
G01X1111443Y604573D02*
X1111441Y603826D01*
G01X1111447Y605193D02*
X1111443Y604573D01*
G01X1111454Y605608D02*
X1111447Y605193D01*
G01X1111463Y605757D02*
X1111454Y605608D01*
G01X1112982Y589804D02*
X1112984Y590552D01*
G01X1112978Y589184D02*
X1112982Y589804D01*
G01X1112971Y588770D02*
X1112978Y589184D01*
G01X1112962Y588621D02*
X1112971Y588770D01*
G01X1119317Y604573D02*
X1119315Y603826D01*
G01X1119322Y605193D02*
X1119317Y604573D01*
G01X1119329Y605608D02*
X1119322Y605193D01*
G01X1119337Y605757D02*
X1119329Y605608D01*
G01X1103589Y589607D02*
Y589606D01*
G01X1103590Y589610D02*
X1103589Y589607D01*
G01X1103591Y589617D02*
X1103590Y589610D01*
G01X1105088Y604771D02*
Y604772D01*
G01X1105087Y604768D02*
X1105088Y604771D01*
G01X1105087Y604761D02*
Y604768D01*
G01X1111463Y589607D02*
Y589606D01*
G01X1111464Y589610D02*
X1111463Y589607D01*
G01X1111465Y589617D02*
X1111464Y589610D01*
G01X1112962Y604771D02*
Y604772D01*
G01X1112961Y604768D02*
X1112962Y604771D01*
G01X1112961Y604761D02*
Y604768D01*
G01X1119337Y589607D02*
Y589606D01*
G01X1119338Y589610D02*
X1119337Y589607D01*
G01X1119339Y589617D02*
X1119338Y589610D01*
G01X1120836Y604771D02*
Y604772D01*
G01X1120835Y604768D02*
X1120836Y604771D01*
G01X1120835Y604761D02*
Y604768D01*
G01X1103324Y588965D02*
X1103328Y589117D01*
G01X1103320Y588867D02*
X1103324Y588965D01*
G01X1103315Y588825D02*
X1103320Y588867D01*
G01X1105353Y605413D02*
X1105349Y605261D01*
G01X1105358Y605511D02*
X1105353Y605413D01*
G01X1105362Y605553D02*
X1105358Y605511D01*
G01X1107256Y588965D02*
X1107261Y589117D01*
G01X1107252Y588867D02*
X1107256Y588965D01*
G01X1107247Y588825D02*
X1107252Y588867D01*
G01X1109295Y605413D02*
X1109291Y605261D01*
G01X1109299Y605511D02*
X1109295Y605413D01*
G01X1109304Y605553D02*
X1109299Y605511D01*
G01X1111198Y588965D02*
X1111202Y589117D01*
G01X1111194Y588867D02*
X1111198Y588965D01*
G01X1111189Y588825D02*
X1111194Y588867D01*
G01X1113227Y605413D02*
X1113223Y605261D01*
G01X1113232Y605511D02*
X1113227Y605413D01*
G01X1113236Y605553D02*
X1113232Y605511D01*
G01X1115130Y588965D02*
X1115135Y589117D01*
G01X1115126Y588867D02*
X1115130Y588965D01*
G01X1115121Y588825D02*
X1115126Y588867D01*
G01X1117169Y605413D02*
X1117165Y605261D01*
G01X1117173Y605511D02*
X1117169Y605413D01*
G01X1117178Y605553D02*
X1117173Y605511D01*
G01X1119072Y588965D02*
X1119076Y589117D01*
G01X1119068Y588867D02*
X1119072Y588965D01*
G01X1119063Y588825D02*
X1119068Y588867D01*
G01X1121101Y605413D02*
X1121097Y605261D01*
G01X1121106Y605511D02*
X1121101Y605413D01*
G01X1121110Y605553D02*
X1121106Y605511D01*
G01X1123004Y588965D02*
X1123009Y589117D01*
G01X1123000Y588867D02*
X1123004Y588965D01*
G01X1122995Y588825D02*
X1123000Y588867D01*
G01X1125043Y605413D02*
X1125039Y605261D01*
G01X1125047Y605511D02*
X1125043Y605413D01*
G01X1125052Y605553D02*
X1125047Y605511D01*
G01X1105350Y606353D02*
X1105344Y606147D01*
G01X1105356Y606485D02*
X1105350Y606353D01*
G01X1105362Y606538D02*
X1105356Y606485D01*
G01X1103327Y588025D02*
X1103333Y588231D01*
G01X1103321Y587893D02*
X1103327Y588025D01*
G01X1103315Y587840D02*
X1103321Y587893D01*
G01X1109292Y606353D02*
X1109286Y606147D01*
G01X1109298Y606485D02*
X1109292Y606353D01*
G01X1109304Y606538D02*
X1109298Y606485D01*
G01X1107260Y588025D02*
X1107265Y588231D01*
G01X1107253Y587893D02*
X1107260Y588025D01*
G01X1107247Y587840D02*
X1107253Y587893D01*
G01X1113224Y606353D02*
X1113218Y606147D01*
G01X1113230Y606485D02*
X1113224Y606353D01*
G01X1113236Y606538D02*
X1113230Y606485D01*
G01X1111201Y588025D02*
X1111207Y588231D01*
G01X1111195Y587893D02*
X1111201Y588025D01*
G01X1111189Y587840D02*
X1111195Y587893D01*
G01X1117166Y606353D02*
X1117160Y606147D01*
G01X1117172Y606485D02*
X1117166Y606353D01*
G01X1117178Y606538D02*
X1117172Y606485D01*
G01X1115134Y588025D02*
X1115139Y588231D01*
G01X1115127Y587893D02*
X1115134Y588025D01*
G01X1115121Y587840D02*
X1115127Y587893D01*
G01X1121098Y606353D02*
X1121092Y606147D01*
G01X1121104Y606485D02*
X1121098Y606353D01*
G01X1121110Y606538D02*
X1121104Y606485D01*
G01X1119075Y588025D02*
X1119081Y588231D01*
G01X1119069Y587893D02*
X1119075Y588025D01*
G01X1119063Y587840D02*
X1119069Y587893D01*
G01X1125040Y606353D02*
X1125034Y606147D01*
G01X1125046Y606485D02*
X1125040Y606353D01*
G01X1125052Y606538D02*
X1125046Y606485D01*
G01X1123008Y588025D02*
X1123013Y588231D01*
G01X1123002Y587893D02*
X1123008Y588025D01*
G01X1122995Y587840D02*
X1123002Y587893D01*
G01X1109031Y590169D02*
X1109032Y590571D01*
G01X1109028Y589841D02*
X1109031Y590169D01*
G01X1109024Y589645D02*
X1109028Y589841D01*
G01X1109019Y589615D02*
X1109024Y589645D01*
G01X1115395Y604209D02*
X1115394Y603807D01*
G01X1115397Y604537D02*
X1115395Y604209D01*
G01X1115401Y604733D02*
X1115397Y604537D01*
G01X1115406Y604763D02*
X1115401Y604733D01*
G01X1116905Y590169D02*
X1116906Y590571D01*
G01X1116902Y589841D02*
X1116905Y590169D01*
G01X1116898Y589645D02*
X1116902Y589841D01*
G01X1116893Y589615D02*
X1116898Y589645D01*
G01X1123269Y604209D02*
X1123268Y603807D01*
G01X1123271Y604537D02*
X1123269Y604209D01*
G01X1123275Y604733D02*
X1123271Y604537D01*
G01X1123280Y604763D02*
X1123275Y604733D01*
G01X1124779Y590169D02*
X1124780Y590571D01*
G01X1124776Y589841D02*
X1124779Y590169D01*
G01X1124772Y589645D02*
X1124776Y589841D01*
G01X1124767Y589615D02*
X1124772Y589645D01*
G01X1131143Y604209D02*
X1131142Y603807D01*
G01X1131145Y604537D02*
X1131143Y604209D01*
G01X1131150Y604733D02*
X1131145Y604537D01*
G01X1131154Y604763D02*
X1131150Y604733D01*
G01X1135086Y588624D02*
X1135087Y588627D01*
G01X1135085Y588622D02*
X1135086Y588624D01*
G01X1135085Y588621D02*
Y588622D01*
G01X1105098Y604181D02*
X1105099Y603807D01*
G01X1105096Y604491D02*
X1105098Y604181D01*
G01X1105092Y604698D02*
X1105096Y604491D01*
G01X1105088Y604772D02*
X1105092Y604698D01*
G01X1111453Y590197D02*
X1111452Y590571D01*
G01X1111455Y589887D02*
X1111453Y590197D01*
G01X1111459Y589680D02*
X1111455Y589887D01*
G01X1111463Y589606D02*
X1111459Y589680D01*
G01X1112972Y604181D02*
X1112973Y603807D01*
G01X1112970Y604491D02*
X1112972Y604181D01*
G01X1112967Y604698D02*
X1112970Y604491D01*
G01X1112962Y604772D02*
X1112967Y604698D01*
G01X1119327Y590197D02*
X1119326Y590571D01*
G01X1119329Y589887D02*
X1119327Y590197D01*
G01X1119333Y589680D02*
X1119329Y589887D01*
G01X1119337Y589606D02*
X1119333Y589680D01*
G01X1120846Y604181D02*
X1120847Y603807D01*
G01X1120844Y604491D02*
X1120846Y604181D01*
G01X1120841Y604698D02*
X1120844Y604491D01*
G01X1120836Y604772D02*
X1120841Y604698D01*
G01X1127201Y590197D02*
X1127200Y590571D01*
G01X1127203Y589887D02*
X1127201Y590197D01*
G01X1127207Y589680D02*
X1127203Y589887D01*
G01X1127211Y589606D02*
X1127207Y589680D01*
G01X1128720Y604181D02*
X1128721Y603807D01*
G01X1128718Y604491D02*
X1128720Y604181D01*
G01X1128715Y604698D02*
X1128718Y604491D01*
G01X1128710Y604772D02*
X1128715Y604698D01*
G01X1109288Y587893D02*
X1109295Y587840D01*
G01X1109282Y588025D02*
X1109288Y587893D01*
G01X1109277Y588231D02*
X1109282Y588025D01*
G01X1111195Y606485D02*
X1111189Y606538D01*
G01X1111201Y606353D02*
X1111195Y606485D01*
G01X1111207Y606147D02*
X1111201Y606353D01*
G01X1113230Y587893D02*
X1113236Y587840D01*
G01X1113224Y588025D02*
X1113230Y587893D01*
G01X1113218Y588231D02*
X1113224Y588025D01*
G01X1115137Y606485D02*
X1115131Y606538D01*
G01X1115143Y606353D02*
X1115137Y606485D01*
G01X1115149Y606147D02*
X1115143Y606353D01*
G01X1117162Y587893D02*
X1117169Y587840D01*
G01X1117156Y588025D02*
X1117162Y587893D01*
G01X1117151Y588231D02*
X1117156Y588025D01*
G01X1119069Y606485D02*
X1119063Y606538D01*
G01X1119075Y606353D02*
X1119069Y606485D01*
G01X1119081Y606147D02*
X1119075Y606353D01*
G01X1121104Y587893D02*
X1121110Y587840D01*
G01X1121098Y588025D02*
X1121104Y587893D01*
G01X1121092Y588231D02*
X1121098Y588025D01*
G01X1123011Y606485D02*
X1123005Y606538D01*
G01X1123017Y606353D02*
X1123011Y606485D01*
G01X1123023Y606147D02*
X1123017Y606353D01*
G01X1125036Y587893D02*
X1125043Y587840D01*
G01X1125030Y588025D02*
X1125036Y587893D01*
G01X1125025Y588231D02*
X1125030Y588025D01*
G01X1126943Y606485D02*
X1126937Y606538D01*
G01X1126949Y606353D02*
X1126943Y606485D01*
G01X1126955Y606147D02*
X1126949Y606353D01*
G01X1128978Y587893D02*
X1128984Y587840D01*
G01X1128972Y588025D02*
X1128978Y587893D01*
G01X1128966Y588231D02*
X1128972Y588025D01*
G01X1130885Y606485D02*
X1130879Y606538D01*
G01X1130891Y606353D02*
X1130885Y606485D01*
G01X1130897Y606147D02*
X1130891Y606353D01*
G01X1132910Y587893D02*
X1132917Y587840D01*
G01X1132904Y588025D02*
X1132910Y587893D01*
G01X1132899Y588231D02*
X1132904Y588025D01*
G01X1109290Y588867D02*
X1109295Y588825D01*
G01X1109286Y588965D02*
X1109290Y588867D01*
G01X1109281Y589117D02*
X1109286Y588965D01*
G01X1111194Y605511D02*
X1111189Y605553D01*
G01X1111198Y605413D02*
X1111194Y605511D01*
G01X1111202Y605261D02*
X1111198Y605413D01*
G01X1113232Y588867D02*
X1113236Y588825D01*
G01X1113227Y588965D02*
X1113232Y588867D01*
G01X1113223Y589117D02*
X1113227Y588965D01*
G01X1115135Y605511D02*
X1115131Y605553D01*
G01X1115140Y605413D02*
X1115135Y605511D01*
G01X1115144Y605261D02*
X1115140Y605413D01*
G01X1117164Y588867D02*
X1117169Y588825D01*
G01X1117160Y588965D02*
X1117164Y588867D01*
G01X1117155Y589117D02*
X1117160Y588965D01*
G01X1119068Y605511D02*
X1119063Y605553D01*
G01X1119072Y605413D02*
X1119068Y605511D01*
G01X1119076Y605261D02*
X1119072Y605413D01*
G01X1121106Y588867D02*
X1121110Y588825D01*
G01X1121101Y588965D02*
X1121106Y588867D01*
G01X1121097Y589117D02*
X1121101Y588965D01*
G01X1123009Y605511D02*
X1123005Y605553D01*
G01X1123014Y605413D02*
X1123009Y605511D01*
G01X1123018Y605261D02*
X1123014Y605413D01*
G01X1125038Y588867D02*
X1125043Y588825D01*
G01X1125034Y588965D02*
X1125038Y588867D01*
G01X1125029Y589117D02*
X1125034Y588965D01*
G01X1126942Y605511D02*
X1126937Y605553D01*
G01X1126946Y605413D02*
X1126942Y605511D01*
G01X1126950Y605261D02*
X1126946Y605413D01*
G01X1128980Y588867D02*
X1128984Y588825D01*
G01X1128975Y588965D02*
X1128980Y588867D01*
G01X1128971Y589117D02*
X1128975Y588965D01*
G01X1130883Y605511D02*
X1130879Y605553D01*
G01X1130888Y605413D02*
X1130883Y605511D01*
G01X1130892Y605261D02*
X1130888Y605413D01*
G01X1132912Y588867D02*
X1132917Y588825D01*
G01X1132908Y588965D02*
X1132912Y588867D01*
G01X1132903Y589117D02*
X1132908Y588965D01*
G01X1115392Y589645D02*
X1115397Y589615D01*
G01X1115388Y589841D02*
X1115392Y589645D01*
G01X1115385Y590169D02*
X1115388Y589841D01*
G01X1115384Y590571D02*
X1115385Y590169D01*
G01X1116907Y604733D02*
X1116902Y604763D01*
G01X1116911Y604537D02*
X1116907Y604733D01*
G01X1116914Y604209D02*
X1116911Y604537D01*
G01X1116915Y603807D02*
X1116914Y604209D01*
G01X1123266Y589645D02*
X1123271Y589615D01*
G01X1123262Y589841D02*
X1123266Y589645D01*
G01X1123259Y590169D02*
X1123262Y589841D01*
G01X1123258Y590571D02*
X1123259Y590169D01*
G01X1124781Y604733D02*
X1124777Y604763D01*
G01X1124785Y604537D02*
X1124781Y604733D01*
G01X1124788Y604209D02*
X1124785Y604537D01*
G01X1124789Y603807D02*
X1124788Y604209D01*
G01X1131140Y589645D02*
X1131145Y589615D01*
G01X1131136Y589841D02*
X1131140Y589645D01*
G01X1131133Y590169D02*
X1131136Y589841D01*
G01X1131132Y590571D02*
X1131133Y590169D01*
G01X1132655Y604733D02*
X1132651Y604763D01*
G01X1132659Y604537D02*
X1132655Y604733D01*
G01X1132662Y604209D02*
X1132659Y604537D01*
G01X1132663Y603807D02*
X1132662Y604209D01*
G01X1112971Y605608D02*
X1112962Y605757D01*
G01X1112978Y605193D02*
X1112971Y605608D01*
G01X1112982Y604573D02*
X1112978Y605193D01*
G01X1112984Y603826D02*
X1112982Y604573D01*
G01X1119329Y588770D02*
X1119337Y588621D01*
G01X1119322Y589184D02*
X1119329Y588770D01*
G01X1119317Y589804D02*
X1119322Y589184D01*
G01X1119315Y590552D02*
X1119317Y589804D01*
G01X1120845Y605608D02*
X1120836Y605757D01*
G01X1120852Y605193D02*
X1120845Y605608D01*
G01X1120856Y604573D02*
X1120852Y605193D01*
G01X1120858Y603826D02*
X1120856Y604573D01*
G01X1127203Y588770D02*
X1127211Y588621D01*
G01X1127196Y589184D02*
X1127203Y588770D01*
G01X1127191Y589804D02*
X1127196Y589184D01*
G01X1127189Y590552D02*
X1127191Y589804D01*
G01X1128719Y605608D02*
X1128710Y605757D01*
G01X1128726Y605193D02*
X1128719Y605608D01*
G01X1128730Y604573D02*
X1128726Y605193D01*
G01X1128732Y603826D02*
X1128730Y604573D01*
G01X1135077Y588770D02*
X1135085Y588621D01*
G01X1135070Y589184D02*
X1135077Y588770D01*
G01X1135065Y589804D02*
X1135070Y589184D01*
G01X1135063Y590552D02*
X1135065Y589804D01*
G01X1136593Y605608D02*
X1136584Y605757D01*
G01X1136600Y605193D02*
X1136593Y605608D01*
G01X1136604Y604573D02*
X1136600Y605193D01*
G01X1136606Y603826D02*
X1136604Y604573D01*
G01X1119333Y604698D02*
X1119337Y604772D01*
G01X1119329Y604491D02*
X1119333Y604698D01*
G01X1119327Y604181D02*
X1119329Y604491D01*
G01X1119326Y603807D02*
X1119327Y604181D01*
G01X1120841Y589680D02*
X1120836Y589606D01*
G01X1120844Y589887D02*
X1120841Y589680D01*
G01X1120846Y590197D02*
X1120844Y589887D01*
G01X1120847Y590571D02*
X1120846Y590197D01*
G01X1127207Y604698D02*
X1127211Y604772D01*
G01X1127203Y604491D02*
X1127207Y604698D01*
G01X1127201Y604181D02*
X1127203Y604491D01*
G01X1127200Y603807D02*
X1127201Y604181D01*
G01X1128715Y589680D02*
X1128710Y589606D01*
G01X1128718Y589887D02*
X1128715Y589680D01*
G01X1128720Y590197D02*
X1128718Y589887D01*
G01X1128721Y590571D02*
X1128720Y590197D01*
G01X1135081Y604698D02*
X1135085Y604772D01*
G01X1135077Y604491D02*
X1135081Y604698D01*
G01X1135075Y604181D02*
X1135077Y604491D01*
G01X1135074Y603807D02*
X1135075Y604181D01*
G01X1136589Y589680D02*
X1136584Y589606D01*
G01X1136592Y589887D02*
X1136589Y589680D01*
G01X1136594Y590197D02*
X1136592Y589887D01*
G01X1136595Y590571D02*
X1136594Y590197D01*
G01X1120856Y589804D02*
X1120858Y590552D01*
G01X1120852Y589184D02*
X1120856Y589804D01*
G01X1120845Y588770D02*
X1120852Y589184D01*
G01X1120836Y588621D02*
X1120845Y588770D01*
G01X1127191Y604573D02*
X1127189Y603826D01*
G01X1127196Y605193D02*
X1127191Y604573D01*
G01X1127203Y605608D02*
X1127196Y605193D01*
G01X1127211Y605757D02*
X1127203Y605608D01*
G01X1128730Y589804D02*
X1128732Y590552D01*
G01X1128726Y589184D02*
X1128730Y589804D01*
G01X1128719Y588770D02*
X1128726Y589184D01*
G01X1128710Y588621D02*
X1128719Y588770D01*
G01X1135065Y604573D02*
X1135063Y603826D01*
G01X1135070Y605193D02*
X1135065Y604573D01*
G01X1135077Y605608D02*
X1135070Y605193D01*
G01X1135085Y605757D02*
X1135077Y605608D01*
G01X1136604Y589804D02*
X1136606Y590552D01*
G01X1136600Y589184D02*
X1136604Y589804D01*
G01X1136593Y588770D02*
X1136600Y589184D01*
G01X1136584Y588621D02*
X1136593Y588770D01*
G01X1127211Y589607D02*
Y589606D01*
G01X1127212Y589610D02*
X1127211Y589607D01*
G01X1127213Y589617D02*
X1127212Y589610D01*
G01X1128710Y604771D02*
Y604772D01*
G01X1128709Y604768D02*
X1128710Y604771D01*
G01X1128709Y604761D02*
Y604768D01*
G01X1135085Y589607D02*
Y589606D01*
G01X1135086Y589610D02*
X1135085Y589607D01*
G01X1135087Y589617D02*
X1135086Y589610D01*
G01X1136584Y604771D02*
Y604772D01*
G01X1136583Y604768D02*
X1136584Y604771D01*
G01X1136583Y604761D02*
Y604768D01*
G01X1126946Y588965D02*
X1126950Y589117D01*
G01X1126942Y588867D02*
X1126946Y588965D01*
G01X1126937Y588825D02*
X1126942Y588867D01*
G01X1128975Y605413D02*
X1128971Y605261D01*
G01X1128980Y605511D02*
X1128975Y605413D01*
G01X1128984Y605553D02*
X1128980Y605511D01*
G01X1130878Y588965D02*
X1130883Y589117D01*
G01X1130874Y588867D02*
X1130878Y588965D01*
G01X1130869Y588825D02*
X1130874Y588867D01*
G01X1132917Y605413D02*
X1132913Y605261D01*
G01X1132921Y605511D02*
X1132917Y605413D01*
G01X1132926Y605553D02*
X1132921Y605511D01*
G01X1134820Y588965D02*
X1134824Y589117D01*
G01X1134816Y588867D02*
X1134820Y588965D01*
G01X1134811Y588825D02*
X1134816Y588867D01*
G01X1136849Y605413D02*
X1136845Y605261D01*
G01X1136854Y605511D02*
X1136849Y605413D01*
G01X1136858Y605553D02*
X1136854Y605511D01*
G01X1138752Y588965D02*
X1138757Y589117D01*
G01X1138748Y588867D02*
X1138752Y588965D01*
G01X1138743Y588825D02*
X1138748Y588867D01*
G01X1140791Y605413D02*
X1140787Y605261D01*
G01X1140795Y605511D02*
X1140791Y605413D01*
G01X1140800Y605553D02*
X1140795Y605511D01*
G01X1128972Y606353D02*
X1128966Y606147D01*
G01X1128978Y606485D02*
X1128972Y606353D01*
G01X1128984Y606538D02*
X1128978Y606485D01*
G01X1126949Y588025D02*
X1126955Y588231D01*
G01X1126943Y587893D02*
X1126949Y588025D01*
G01X1126937Y587840D02*
X1126943Y587893D01*
G01X1132914Y606353D02*
X1132908Y606147D01*
G01X1132920Y606485D02*
X1132914Y606353D01*
G01X1132926Y606538D02*
X1132920Y606485D01*
G01X1130882Y588025D02*
X1130887Y588231D01*
G01X1130876Y587893D02*
X1130882Y588025D01*
G01X1130869Y587840D02*
X1130876Y587893D01*
G01X1136846Y606353D02*
X1136840Y606147D01*
G01X1136852Y606485D02*
X1136846Y606353D01*
G01X1136858Y606538D02*
X1136852Y606485D01*
G01X1134823Y588025D02*
X1134829Y588231D01*
G01X1134817Y587893D02*
X1134823Y588025D01*
G01X1134811Y587840D02*
X1134817Y587893D01*
G01X1140788Y606353D02*
X1140782Y606147D01*
G01X1140794Y606485D02*
X1140788Y606353D01*
G01X1140800Y606538D02*
X1140794Y606485D01*
G01X1138756Y588025D02*
X1138761Y588231D01*
G01X1138750Y587893D02*
X1138756Y588025D01*
G01X1138743Y587840D02*
X1138750Y587893D01*
G01X1132653Y590169D02*
X1132654Y590571D01*
G01X1132650Y589841D02*
X1132653Y590169D01*
G01X1132646Y589645D02*
X1132650Y589841D01*
G01X1132641Y589615D02*
X1132646Y589645D01*
G01X1139017Y604209D02*
X1139016Y603807D01*
G01X1139019Y604537D02*
X1139017Y604209D01*
G01X1139024Y604733D02*
X1139019Y604537D01*
G01X1139028Y604763D02*
X1139024Y604733D01*
G01X1140527Y590169D02*
X1140528Y590571D01*
G01X1140524Y589841D02*
X1140527Y590169D01*
G01X1140520Y589645D02*
X1140524Y589841D01*
G01X1140515Y589615D02*
X1140520Y589645D01*
G01X1105088Y588622D02*
Y588621D01*
G01X1105087Y588624D02*
X1105088Y588622D01*
G01X1105087Y588627D02*
Y588624D01*
G01X1103589Y605756D02*
Y605757D01*
G01X1103590Y605754D02*
X1103589Y605756D01*
G01X1103591Y605751D02*
X1103590Y605754D01*
G01X1135075Y590197D02*
X1135074Y590571D01*
G01X1135077Y589887D02*
X1135075Y590197D01*
G01X1135081Y589680D02*
X1135077Y589887D01*
G01X1135085Y589606D02*
X1135081Y589680D01*
G01X1136594Y604181D02*
X1136595Y603807D01*
G01X1136592Y604491D02*
X1136594Y604181D01*
G01X1136589Y604698D02*
X1136592Y604491D01*
G01X1136584Y604772D02*
X1136589Y604698D01*
G01X1134817Y606485D02*
X1134811Y606538D01*
G01X1134823Y606353D02*
X1134817Y606485D01*
G01X1134829Y606147D02*
X1134823Y606353D01*
G01X1136852Y587893D02*
X1136858Y587840D01*
G01X1136846Y588025D02*
X1136852Y587893D01*
G01X1136840Y588231D02*
X1136846Y588025D01*
G01X1138759Y606485D02*
X1138753Y606538D01*
G01X1138765Y606353D02*
X1138759Y606485D01*
G01X1138771Y606147D02*
X1138765Y606353D01*
G01X1140784Y587893D02*
X1140791Y587840D01*
G01X1140778Y588025D02*
X1140784Y587893D01*
G01X1140773Y588231D02*
X1140778Y588025D01*
G01X1134816Y605511D02*
X1134811Y605553D01*
G01X1134820Y605413D02*
X1134816Y605511D01*
G01X1134824Y605261D02*
X1134820Y605413D01*
G01X1136854Y588867D02*
X1136858Y588825D01*
G01X1136849Y588965D02*
X1136854Y588867D01*
G01X1136845Y589117D02*
X1136849Y588965D01*
G01X1138757Y605511D02*
X1138753Y605553D01*
G01X1138762Y605413D02*
X1138757Y605511D01*
G01X1138766Y605261D02*
X1138762Y605413D01*
G01X1140786Y588867D02*
X1140791Y588825D01*
G01X1140782Y588965D02*
X1140786Y588867D01*
G01X1140777Y589117D02*
X1140782Y588965D01*
G01X1139014Y589645D02*
X1139019Y589615D01*
G01X1139010Y589841D02*
X1139014Y589645D01*
G01X1139007Y590169D02*
X1139010Y589841D01*
G01X1139006Y590571D02*
X1139007Y590169D01*
G01X1140529Y604733D02*
X1140525Y604763D01*
G01X1140533Y604537D02*
X1140529Y604733D01*
G01X1140536Y604209D02*
X1140533Y604537D01*
G01X1140537Y603807D02*
X1140536Y604209D01*
G01X1112962Y588622D02*
Y588621D01*
G01X1112961Y588624D02*
X1112962Y588622D01*
G01X1112961Y588627D02*
Y588624D01*
G01X1111463Y605756D02*
Y605757D01*
G01X1111464Y605754D02*
X1111463Y605756D01*
G01X1111465Y605751D02*
X1111464Y605754D01*
G01X1120836Y588622D02*
Y588621D01*
G01X1120835Y588624D02*
X1120836Y588622D01*
G01X1120835Y588627D02*
Y588624D01*
G01X1119337Y605756D02*
Y605757D01*
G01X1119338Y605754D02*
X1119337Y605756D01*
G01X1119339Y605751D02*
X1119338Y605754D01*
G01X1128710Y588622D02*
Y588621D01*
G01X1128709Y588624D02*
X1128710Y588622D01*
G01X1128709Y588627D02*
Y588624D01*
G01X1127211Y605756D02*
Y605757D01*
G01X1127212Y605754D02*
X1127211Y605756D01*
G01X1127213Y605751D02*
X1127212Y605754D01*
G01X1136584Y588622D02*
Y588621D01*
G01X1136583Y588624D02*
X1136584Y588622D01*
G01X1136583Y588627D02*
Y588624D01*
G01X1105087Y589610D02*
Y589617D01*
G01X1105088Y589607D02*
X1105087Y589610D01*
G01X1105088Y589606D02*
Y589607D01*
G01X1135085Y605756D02*
Y605757D01*
G01X1135086Y605754D02*
X1135085Y605756D01*
G01X1135087Y605751D02*
X1135086Y605754D01*
G01X1103590Y604768D02*
X1103591Y604761D01*
G01X1103589Y604771D02*
X1103590Y604768D01*
G01X1103589Y604772D02*
Y604771D01*
G01X1112961Y589610D02*
Y589617D01*
G01X1112962Y589607D02*
X1112961Y589610D01*
G01X1112962Y589606D02*
Y589607D01*
G01X1111464Y604768D02*
X1111465Y604761D01*
G01X1111463Y604771D02*
X1111464Y604768D01*
G01X1111463Y604772D02*
Y604771D01*
G01X1120835Y589610D02*
Y589617D01*
G01X1120836Y589607D02*
X1120835Y589610D01*
G01X1120836Y589606D02*
Y589607D01*
G01X1119338Y604768D02*
X1119339Y604761D01*
G01X1119337Y604771D02*
X1119338Y604768D01*
G01X1119337Y604772D02*
Y604771D01*
G01X1128709Y589610D02*
Y589617D01*
G01X1128710Y589607D02*
X1128709Y589610D01*
G01X1128710Y589606D02*
Y589607D01*
G01X1127212Y604768D02*
X1127213Y604761D01*
G01X1127211Y604771D02*
X1127212Y604768D01*
G01X1127211Y604772D02*
Y604771D01*
G01X1136583Y589610D02*
Y589617D01*
G01X1136584Y589607D02*
X1136583Y589610D01*
G01X1136584Y589606D02*
Y589607D01*
G01X1135086Y604768D02*
X1135087Y604761D01*
G01X1135085Y604771D02*
X1135086Y604768D01*
G01X1135085Y604772D02*
Y604771D01*
G01X1145457Y590714D02*
X1145677Y590693D01*
G01X1145234Y590771D02*
X1145457Y590714D01*
G01X1145014Y590864D02*
X1145234Y590771D01*
G01X1144800Y590998D02*
X1145014Y590864D01*
G01X1144599Y591177D02*
X1144800Y590998D01*
G01X1144420Y591402D02*
X1144599Y591177D01*
G01X1145897Y603663D02*
X1145677Y603685D01*
G01X1146120Y603607D02*
X1145897Y603663D01*
G01X1146340Y603514D02*
X1146120Y603607D01*
G01X1146554Y603380D02*
X1146340Y603514D01*
G01X1146755Y603201D02*
X1146554Y603380D01*
G01X1146935Y602976D02*
X1146755Y603201D01*
G01X1109325Y588823D02*
X1109340D01*
G01X1109310Y588824D02*
X1109325Y588823D01*
G01X1109295Y588825D02*
X1109310Y588824D01*
G01X1117199Y588823D02*
X1117214D01*
G01X1117184Y588824D02*
X1117199Y588823D01*
G01X1117169Y588825D02*
X1117184Y588824D01*
G01X1146755Y591177D02*
X1146935Y591402D01*
G01X1146555Y590999D02*
X1146755Y591177D01*
G01X1146341Y590864D02*
X1146555Y590999D01*
G01X1146121Y590771D02*
X1146341Y590864D01*
G01X1145898Y590714D02*
X1146121Y590771D01*
G01X1145677Y590693D02*
X1145898Y590714D01*
G01X1134781Y588823D02*
X1134766D01*
G01X1134796Y588824D02*
X1134781Y588823D01*
G01X1134811Y588825D02*
X1134796Y588824D01*
G01X1126907Y588823D02*
X1126892D01*
G01X1126922Y588824D02*
X1126907Y588823D01*
G01X1126937Y588825D02*
X1126922Y588824D01*
G01X1119033Y588823D02*
X1119018D01*
G01X1119048Y588824D02*
X1119033Y588823D01*
G01X1119063Y588825D02*
X1119048Y588824D01*
G01X1111159Y588823D02*
X1111144D01*
G01X1111174Y588824D02*
X1111159Y588823D01*
G01X1111189Y588825D02*
X1111174Y588824D01*
G01X1103285Y588823D02*
X1103270D01*
G01X1103300Y588824D02*
X1103285Y588823D01*
G01X1103315Y588825D02*
X1103300Y588824D01*
G01X1138713Y587839D02*
X1138698D01*
G01X1138728D02*
X1138713D01*
G01X1138743Y587840D02*
X1138728Y587839D01*
G01X1130839D02*
X1130824D01*
G01X1130854D02*
X1130839D01*
G01X1130869Y587840D02*
X1130854Y587839D01*
G01X1122965D02*
X1122950D01*
G01X1122980D02*
X1122965D01*
G01X1122995Y587840D02*
X1122980Y587839D01*
G01X1115091D02*
X1115076D01*
G01X1115106D02*
X1115091D01*
G01X1115121Y587840D02*
X1115106Y587839D01*
G01X1107217D02*
X1107202D01*
G01X1107232D02*
X1107217D01*
G01X1107247Y587840D02*
X1107232Y587839D01*
G01X1099343D02*
X1099328D01*
G01X1099358D02*
X1099343D01*
G01X1099373Y587840D02*
X1099358Y587839D01*
G01X1101436D02*
X1101421Y587840D01*
G01X1101451Y587839D02*
X1101436D01*
G01X1101466D02*
X1101451D01*
G01X1105377D02*
X1105362Y587840D01*
G01X1105392Y587839D02*
X1105377D01*
G01X1105407D02*
X1105392D01*
G01X1109310D02*
X1109295Y587840D01*
G01X1109325Y587839D02*
X1109310D01*
G01X1109340D02*
X1109325D01*
G01X1113251D02*
X1113236Y587840D01*
G01X1113266Y587839D02*
X1113251D01*
G01X1113281D02*
X1113266D01*
G01X1117184D02*
X1117169Y587840D01*
G01X1117199Y587839D02*
X1117184D01*
G01X1117214D02*
X1117199D01*
G01X1121125D02*
X1121110Y587840D01*
G01X1121140Y587839D02*
X1121125D01*
G01X1121155D02*
X1121140D01*
G01X1125058D02*
X1125043Y587840D01*
G01X1125073Y587839D02*
X1125058D01*
G01X1125088D02*
X1125073D01*
G01X1128999D02*
X1128984Y587840D01*
G01X1129014Y587839D02*
X1128999D01*
G01X1129029D02*
X1129014D01*
G01X1132932D02*
X1132917Y587840D01*
G01X1132947Y587839D02*
X1132932D01*
G01X1132962D02*
X1132947D01*
G01X1136873D02*
X1136858Y587840D01*
G01X1136888Y587839D02*
X1136873D01*
G01X1136903D02*
X1136888D01*
G01X1140806D02*
X1140791Y587840D01*
G01X1140821Y587839D02*
X1140806D01*
G01X1140836D02*
X1140821D01*
G01X1099368Y606539D02*
X1099383Y606538D01*
G01X1099353Y606539D02*
X1099368D01*
G01X1099338D02*
X1099353D01*
G01X1103300D02*
X1103315Y606538D01*
G01X1103285Y606539D02*
X1103300D01*
G01X1103270D02*
X1103285D01*
G01X1107242D02*
X1107257Y606538D01*
G01X1107227Y606539D02*
X1107242D01*
G01X1107212D02*
X1107227D01*
G01X1111174D02*
X1111189Y606538D01*
G01X1111159Y606539D02*
X1111174D01*
G01X1111144D02*
X1111159D01*
G01X1115116D02*
X1115131Y606538D01*
G01X1115101Y606539D02*
X1115116D01*
G01X1115086D02*
X1115101D01*
G01X1119048D02*
X1119063Y606538D01*
G01X1119033Y606539D02*
X1119048D01*
G01X1119018D02*
X1119033D01*
G01X1122990D02*
X1123005Y606538D01*
G01X1122975Y606539D02*
X1122990D01*
G01X1122960D02*
X1122975D01*
G01X1126922D02*
X1126937Y606538D01*
G01X1126907Y606539D02*
X1126922D01*
G01X1126892D02*
X1126907D01*
G01X1130864D02*
X1130879Y606538D01*
G01X1130849Y606539D02*
X1130864D01*
G01X1130834D02*
X1130849D01*
G01X1134796D02*
X1134811Y606538D01*
G01X1134781Y606539D02*
X1134796D01*
G01X1134766D02*
X1134781D01*
G01X1138738D02*
X1138753Y606538D01*
G01X1138723Y606539D02*
X1138738D01*
G01X1138708D02*
X1138723D01*
G01X1101436Y588824D02*
X1101421Y588825D01*
G01X1101451Y588823D02*
X1101436Y588824D01*
G01X1101466Y588823D02*
X1101451D01*
G01X1105377Y588824D02*
X1105362Y588825D01*
G01X1105392Y588823D02*
X1105377Y588824D01*
G01X1105407Y588823D02*
X1105392D01*
G01X1113251Y588824D02*
X1113236Y588825D01*
G01X1113266Y588823D02*
X1113251Y588824D01*
G01X1113281Y588823D02*
X1113266D01*
G01X1121125Y588824D02*
X1121110Y588825D01*
G01X1121140Y588823D02*
X1121125Y588824D01*
G01X1121155Y588823D02*
X1121140D01*
G01X1125058Y588824D02*
X1125043Y588825D01*
G01X1125073Y588823D02*
X1125058Y588824D01*
G01X1125088Y588823D02*
X1125073D01*
G01X1128999Y588824D02*
X1128984Y588825D01*
G01X1129014Y588823D02*
X1128999Y588824D01*
G01X1129029Y588823D02*
X1129014D01*
G01X1132932Y588824D02*
X1132917Y588825D01*
G01X1132947Y588823D02*
X1132932Y588824D01*
G01X1132962Y588823D02*
X1132947D01*
G01X1136873Y588824D02*
X1136858Y588825D01*
G01X1136888Y588823D02*
X1136873Y588824D01*
G01X1136903Y588823D02*
X1136888D01*
G01X1140806Y588824D02*
X1140791Y588825D01*
G01X1140821Y588823D02*
X1140806Y588824D01*
G01X1140836Y588823D02*
X1140821D01*
G01X1103300Y605554D02*
X1103315Y605553D01*
G01X1103285Y605555D02*
X1103300Y605554D01*
G01X1103270Y605555D02*
X1103285D01*
G01X1107242Y605554D02*
X1107257Y605553D01*
G01X1107227Y605555D02*
X1107242Y605554D01*
G01X1107212Y605555D02*
X1107227D01*
G01X1111174Y605554D02*
X1111189Y605553D01*
G01X1111159Y605555D02*
X1111174Y605554D01*
G01X1111144Y605555D02*
X1111159D01*
G01X1115116Y605554D02*
X1115131Y605553D01*
G01X1115101Y605555D02*
X1115116Y605554D01*
G01X1115086Y605555D02*
X1115101D01*
G01X1119048Y605554D02*
X1119063Y605553D01*
G01X1119033Y605555D02*
X1119048Y605554D01*
G01X1119018Y605555D02*
X1119033D01*
G01X1126922Y605554D02*
X1126937Y605553D01*
G01X1126907Y605555D02*
X1126922Y605554D01*
G01X1126892Y605555D02*
X1126907D01*
G01X1134796Y605554D02*
X1134811Y605553D01*
G01X1134781Y605555D02*
X1134796Y605554D01*
G01X1134766Y605555D02*
X1134781D01*
G01X1099353D02*
X1099338D01*
G01X1099368Y605554D02*
X1099353Y605555D01*
G01X1099383Y605553D02*
X1099368Y605554D01*
G01X1122975Y605555D02*
X1122960D01*
G01X1122990Y605554D02*
X1122975Y605555D01*
G01X1123005Y605553D02*
X1122990Y605554D01*
G01X1130849Y605555D02*
X1130834D01*
G01X1130864Y605554D02*
X1130849Y605555D01*
G01X1130879Y605553D02*
X1130864Y605554D01*
G01X1138723Y605555D02*
X1138708D01*
G01X1138738Y605554D02*
X1138723Y605555D01*
G01X1138753Y605553D02*
X1138738Y605554D01*
G01X1144599Y603201D02*
X1144420Y602976D01*
G01X1144800Y603379D02*
X1144599Y603201D01*
G01X1145014Y603514D02*
X1144800Y603379D01*
G01X1145234Y603607D02*
X1145014Y603514D01*
G01X1145457Y603663D02*
X1145234Y603607D01*
G01X1145677Y603685D02*
X1145457Y603663D01*
G01X1140830Y605555D02*
X1140845D01*
G01X1140815Y605554D02*
X1140830Y605555D01*
G01X1140800Y605553D02*
X1140815Y605554D01*
G01X1136888Y605555D02*
X1136903D01*
G01X1136873Y605554D02*
X1136888Y605555D01*
G01X1136858Y605553D02*
X1136873Y605554D01*
G01X1132956Y605555D02*
X1132971D01*
G01X1132941Y605554D02*
X1132956Y605555D01*
G01X1132926Y605553D02*
X1132941Y605554D01*
G01X1129014Y605555D02*
X1129029D01*
G01X1128999Y605554D02*
X1129014Y605555D01*
G01X1128984Y605553D02*
X1128999Y605554D01*
G01X1125082Y605555D02*
X1125097D01*
G01X1125067Y605554D02*
X1125082Y605555D01*
G01X1125052Y605553D02*
X1125067Y605554D01*
G01X1121140Y605555D02*
X1121155D01*
G01X1121125Y605554D02*
X1121140Y605555D01*
G01X1121110Y605553D02*
X1121125Y605554D01*
G01X1117208Y605555D02*
X1117223D01*
G01X1117193Y605554D02*
X1117208Y605555D01*
G01X1117178Y605553D02*
X1117193Y605554D01*
G01X1113266Y605555D02*
X1113281D01*
G01X1113251Y605554D02*
X1113266Y605555D01*
G01X1113236Y605553D02*
X1113251Y605554D01*
G01X1109334Y605555D02*
X1109349D01*
G01X1109319Y605554D02*
X1109334Y605555D01*
G01X1109304Y605553D02*
X1109319Y605554D01*
G01X1105392Y605555D02*
X1105407D01*
G01X1105377Y605554D02*
X1105392Y605555D01*
G01X1105362Y605553D02*
X1105377Y605554D01*
G01X1101460Y605555D02*
X1101475D01*
G01X1101445Y605554D02*
X1101460Y605555D01*
G01X1101430Y605553D02*
X1101445Y605554D01*
G01X1140830Y606539D02*
X1140845D01*
G01X1140815D02*
X1140830D01*
G01X1140800Y606538D02*
X1140815Y606539D01*
G01X1132956D02*
X1132971D01*
G01X1132941D02*
X1132956D01*
G01X1132926Y606538D02*
X1132941Y606539D01*
G01X1125082D02*
X1125097D01*
G01X1125067D02*
X1125082D01*
G01X1125052Y606538D02*
X1125067Y606539D01*
G01X1101460D02*
X1101475D01*
G01X1101445D02*
X1101460D01*
G01X1101430Y606538D02*
X1101445Y606539D01*
G01X1148020Y599783D02*
G03Y594595I-1752J-2594D01*
G01X1149122Y600314D02*
G03Y594064I-2854J-3125D01*
G01X1150894Y597189D02*
G03I-4626J0D01*
G01X1093020Y617189D02*
X1093512D01*
G01X1089903D02*
X1090559D01*
G01X1446858Y616008D02*
X1080717D01*
G01X1090969Y614592D02*
X1089493D01*
G01X1091051Y614257D02*
X1089411D01*
G01X1089083Y613252D02*
X1088591D01*
G01X1091871D02*
X1091379D01*
G01X1093512D02*
X1093020D01*
G01X1438984Y611854D02*
X1088591D01*
G01X1101583Y610476D02*
X1099220D01*
G01X1105520D02*
X1103157D01*
G01X1109457D02*
X1107094D01*
G01X1113394D02*
X1111031D01*
G01X1117331D02*
X1114968D01*
G01X1121268D02*
X1118906D01*
G01X1125205D02*
X1122843D01*
G01X1129142D02*
X1126780D01*
G01X1133079D02*
X1130717D01*
G01X1137016D02*
X1134654D01*
G01X1140953D02*
X1138591D01*
G01X1105008Y609492D02*
X1103669D01*
G01X1112882D02*
X1111543D01*
G01X1120756D02*
X1119417D01*
G01X1128630D02*
X1127291D01*
G01X1136504D02*
X1135165D01*
G01X1148177D02*
X1143177D01*
G01X1135008Y609394D02*
X1136661D01*
G01X1127134D02*
X1128787D01*
G01X1119260D02*
X1120913D01*
G01X1111386D02*
X1113039D01*
G01X1103512D02*
X1105165D01*
G01X1094240Y609295D02*
X1089516D01*
G01X1101583D02*
X1099220D01*
G01X1105520D02*
X1103157D01*
G01X1109457D02*
X1107094D01*
G01X1113394D02*
X1111031D01*
G01X1117331D02*
X1114968D01*
G01X1121268D02*
X1118906D01*
G01X1125205D02*
X1122843D01*
G01X1129142D02*
X1126780D01*
G01X1133079D02*
X1130717D01*
G01X1137016D02*
X1134654D01*
G01X1140953D02*
X1138591D01*
G01X1105165Y608902D02*
X1103512D01*
G01X1113039D02*
X1111386D01*
G01X1120913D02*
X1119260D01*
G01X1128787D02*
X1127134D01*
G01X1136661D02*
X1135008D01*
G01X1095855Y608735D02*
X1092269D01*
G01X1101819Y608035D02*
X1098984D01*
G01X1105756D02*
X1102921D01*
G01X1109693D02*
X1106858D01*
G01X1113630D02*
X1110795D01*
G01X1117567D02*
X1114732D01*
G01X1121504D02*
X1118669D01*
G01X1125441D02*
X1122606D01*
G01X1129378D02*
X1126543D01*
G01X1133315D02*
X1130480D01*
G01X1137252D02*
X1134417D01*
G01X1141189D02*
X1138354D01*
G01X1105165Y607130D02*
X1103512D01*
G01X1113039D02*
X1111386D01*
G01X1120913D02*
X1119260D01*
G01X1128787D02*
X1127134D01*
G01X1136661D02*
X1135008D01*
G01Y606638D02*
X1136661D01*
G01X1127134D02*
X1128787D01*
G01X1119260D02*
X1120913D01*
G01X1111386D02*
X1113039D01*
G01X1103512D02*
X1105165D01*
G01X1101819Y606539D02*
X1098984D01*
G01X1105756D02*
X1102921D01*
G01X1109693D02*
X1106858D01*
G01X1113630D02*
X1110795D01*
G01X1117567D02*
X1114732D01*
G01X1121504D02*
X1118669D01*
G01X1125441D02*
X1122606D01*
G01X1129378D02*
X1126543D01*
G01X1133315D02*
X1130480D01*
G01X1137252D02*
X1134417D01*
G01X1141189D02*
X1138354D01*
G01X1140598Y606382D02*
X1141189D01*
G01X1138354D02*
X1138945D01*
G01X1136661D02*
X1137252D01*
G01X1134417D02*
X1135008D01*
G01X1132724D02*
X1133315D01*
G01X1130480D02*
X1131071D01*
G01X1128787D02*
X1129378D01*
G01X1126543D02*
X1127134D01*
G01X1124850D02*
X1125441D01*
G01X1122606D02*
X1123197D01*
G01X1120913D02*
X1121504D01*
G01X1118669D02*
X1119260D01*
G01X1116976D02*
X1117567D01*
G01X1114732D02*
X1115323D01*
G01X1113039D02*
X1113630D01*
G01X1110795D02*
X1111386D01*
G01X1109102D02*
X1109693D01*
G01X1106858D02*
X1107449D01*
G01X1105165D02*
X1105756D01*
G01X1102921D02*
X1103512D01*
G01X1101228D02*
X1101819D01*
G01X1098984D02*
X1099575D01*
G01X1138771Y606147D02*
X1140782D01*
G01X1134829D02*
X1136840D01*
G01X1130897D02*
X1132908D01*
G01X1126955D02*
X1128966D01*
G01X1123023D02*
X1125034D01*
G01X1119081D02*
X1121092D01*
G01X1115149D02*
X1117160D01*
G01X1111207D02*
X1113218D01*
G01X1107275D02*
X1109286D01*
G01X1103333D02*
X1105344D01*
G01X1099401D02*
X1101412D01*
G01X1101156Y605757D02*
X1099657D01*
G01X1105088D02*
X1103589D01*
G01X1109030D02*
X1107531D01*
G01X1112962D02*
X1111463D01*
G01X1116904D02*
X1115405D01*
G01X1120836D02*
X1119337D01*
G01X1124778D02*
X1123279D01*
G01X1128710D02*
X1127211D01*
G01X1132652D02*
X1131153D01*
G01X1136584D02*
X1135085D01*
G01X1140526D02*
X1139027D01*
G01X1139040Y605738D02*
X1140513D01*
G01X1135098D02*
X1136571D01*
G01X1131166D02*
X1132639D01*
G01X1127224D02*
X1128697D01*
G01X1123292D02*
X1124765D01*
G01X1119350D02*
X1120823D01*
G01X1115418D02*
X1116891D01*
G01X1111476D02*
X1112949D01*
G01X1107544D02*
X1109017D01*
G01X1103602D02*
X1105075D01*
G01X1099670D02*
X1101143D01*
G01X1099575Y605713D02*
X1098984D01*
G01X1101819D02*
X1101228D01*
G01X1103512D02*
X1102921D01*
G01X1105756D02*
X1105165D01*
G01X1107449D02*
X1106858D01*
G01X1109693D02*
X1109102D01*
G01X1111386D02*
X1110795D01*
G01X1113630D02*
X1113039D01*
G01X1115323D02*
X1114732D01*
G01X1117567D02*
X1116976D01*
G01X1119260D02*
X1118669D01*
G01X1121504D02*
X1120913D01*
G01X1123197D02*
X1122606D01*
G01X1125441D02*
X1124850D01*
G01X1127134D02*
X1126543D01*
G01X1129378D02*
X1128787D01*
G01X1131071D02*
X1130480D01*
G01X1133315D02*
X1132724D01*
G01X1135008D02*
X1134417D01*
G01X1137252D02*
X1136661D01*
G01X1138945D02*
X1138354D01*
G01X1141189D02*
X1140598D01*
G01X1134417Y605555D02*
X1137252D01*
G01X1126543D02*
X1129378D01*
G01X1122606D02*
X1125441D01*
G01X1118669D02*
X1121504D01*
G01X1114732D02*
X1117567D01*
G01X1110795D02*
X1113630D01*
G01X1106858D02*
X1109693D01*
G01X1102921D02*
X1105756D01*
G01X1101819D02*
X1098984D01*
G01X1133315D02*
X1130480D01*
G01X1141189D02*
X1138354D01*
G01X1101228Y605457D02*
X1099575D01*
G01X1109102D02*
X1107449D01*
G01X1116976D02*
X1115323D01*
G01X1124850D02*
X1123197D01*
G01X1132724D02*
X1131071D01*
G01X1140598D02*
X1138945D01*
G01X1100889Y605368D02*
X1099924D01*
G01X1104821D02*
X1103856D01*
G01X1108763D02*
X1107798D01*
G01X1112695D02*
X1111730D01*
G01X1116637D02*
X1115672D01*
G01X1120569D02*
X1119604D01*
G01X1124511D02*
X1123546D01*
G01X1128443D02*
X1127478D01*
G01X1132385D02*
X1131420D01*
G01X1136317D02*
X1135352D01*
G01X1140259D02*
X1139294D01*
G01X1138354Y605358D02*
X1138669D01*
G01X1130480D02*
X1130795D01*
G01X1122606D02*
X1122921D01*
G01X1114732D02*
X1115047D01*
G01X1106858D02*
X1107173D01*
G01X1098984D02*
X1099299D01*
G01X1101819D02*
X1101504D01*
G01X1103236D02*
X1102921D01*
G01X1105756D02*
X1105441D01*
G01X1109693D02*
X1109378D01*
G01X1111110D02*
X1110795D01*
G01X1113630D02*
X1113315D01*
G01X1117567D02*
X1117252D01*
G01X1118984D02*
X1118669D01*
G01X1121504D02*
X1121189D01*
G01X1125441D02*
X1125126D01*
G01X1126858D02*
X1126543D01*
G01X1129378D02*
X1129063D01*
G01X1133315D02*
X1133000D01*
G01X1134732D02*
X1134417D01*
G01X1137252D02*
X1136937D01*
G01X1141189D02*
X1140874D01*
G01X1101417Y605261D02*
X1099396D01*
G01X1105349D02*
X1103328D01*
G01X1109291D02*
X1107270D01*
G01X1113223D02*
X1111202D01*
G01X1117165D02*
X1115144D01*
G01X1121097D02*
X1119076D01*
G01X1125039D02*
X1123018D01*
G01X1128971D02*
X1126950D01*
G01X1132913D02*
X1130892D01*
G01X1136845D02*
X1134824D01*
G01X1140787D02*
X1138766D01*
G01X1138945Y604965D02*
X1140598D01*
G01X1131071D02*
X1132724D01*
G01X1123197D02*
X1124850D01*
G01X1115323D02*
X1116976D01*
G01X1107449D02*
X1109102D01*
G01X1099575D02*
X1101228D01*
G01X1101156Y604772D02*
X1099657D01*
G01X1105088D02*
X1103589D01*
G01X1109030D02*
X1107531D01*
G01X1112962D02*
X1111463D01*
G01X1116904D02*
X1115405D01*
G01X1120836D02*
X1119337D01*
G01X1124778D02*
X1123279D01*
G01X1128710D02*
X1127211D01*
G01X1132652D02*
X1131153D01*
G01X1136584D02*
X1135085D01*
G01X1140526D02*
X1139027D01*
G01X1143177Y604768D02*
X1148177D01*
G01X1101154Y604763D02*
X1099658D01*
G01X1105087D02*
X1103590D01*
G01X1109028D02*
X1107532D01*
G01X1112961D02*
X1111464D01*
G01X1116902D02*
X1115406D01*
G01X1120835D02*
X1119338D01*
G01X1124777D02*
X1123280D01*
G01X1128709D02*
X1127212D01*
G01X1132651D02*
X1131154D01*
G01X1136583D02*
X1135086D01*
G01X1140525D02*
X1139028D01*
G01X1139248Y604441D02*
X1140305D01*
G01X1135306D02*
X1136363D01*
G01X1131374D02*
X1132431D01*
G01X1127432D02*
X1128489D01*
G01X1123500D02*
X1124557D01*
G01X1119558D02*
X1120615D01*
G01X1115626D02*
X1116683D01*
G01X1111684D02*
X1112741D01*
G01X1107752D02*
X1108809D01*
G01X1103810D02*
X1104867D01*
G01X1099878D02*
X1100935D01*
G01X1138591Y604394D02*
X1140953D01*
G01X1134654D02*
X1137016D01*
G01X1130717D02*
X1133079D01*
G01X1126780D02*
X1129142D01*
G01X1122843D02*
X1125205D01*
G01X1118906D02*
X1121268D01*
G01X1114968D02*
X1117331D01*
G01X1111031D02*
X1113394D01*
G01X1107094D02*
X1109457D01*
G01X1103157D02*
X1105520D01*
G01X1099220D02*
X1101583D01*
G01X1140874Y603862D02*
X1141189D01*
G01X1138354D02*
X1138669D01*
G01X1136937D02*
X1137252D01*
G01X1134417D02*
X1134732D01*
G01X1133000D02*
X1133315D01*
G01X1130480D02*
X1130795D01*
G01X1129063D02*
X1129378D01*
G01X1126543D02*
X1126858D01*
G01X1125126D02*
X1125441D01*
G01X1122606D02*
X1122921D01*
G01X1121189D02*
X1121504D01*
G01X1118669D02*
X1118984D01*
G01X1117252D02*
X1117567D01*
G01X1114732D02*
X1115047D01*
G01X1113315D02*
X1113630D01*
G01X1110795D02*
X1111110D01*
G01X1109378D02*
X1109693D01*
G01X1106858D02*
X1107173D01*
G01X1105441D02*
X1105756D01*
G01X1102921D02*
X1103236D01*
G01X1101504D02*
X1101819D01*
G01X1098984D02*
X1099299D01*
G01X1139005Y603826D02*
X1140548D01*
G01X1135063D02*
X1136606D01*
G01X1131131D02*
X1132674D01*
G01X1127189D02*
X1128732D01*
G01X1123257D02*
X1124800D01*
G01X1119315D02*
X1120858D01*
G01X1115383D02*
X1116926D01*
G01X1111441D02*
X1112984D01*
G01X1107509D02*
X1109052D01*
G01X1103567D02*
X1105110D01*
G01X1099635D02*
X1101178D01*
G01X1139016Y603807D02*
X1140537D01*
G01X1135074D02*
X1136595D01*
G01X1131142D02*
X1132663D01*
G01X1127200D02*
X1128721D01*
G01X1123268D02*
X1124789D01*
G01X1119326D02*
X1120847D01*
G01X1115394D02*
X1116915D01*
G01X1111452D02*
X1112973D01*
G01X1107520D02*
X1109041D01*
G01X1103578D02*
X1105099D01*
G01X1099646D02*
X1101167D01*
G01X1434575Y603685D02*
X1093000D01*
G01X1094240Y603390D02*
X1089516D01*
G01X1138945Y603193D02*
X1140598D01*
G01X1131071D02*
X1132724D01*
G01X1123197D02*
X1124850D01*
G01X1115323D02*
X1116976D01*
G01X1107449D02*
X1109102D01*
G01X1099575D02*
X1101228D01*
G01Y602701D02*
X1099575D01*
G01X1109102D02*
X1107449D01*
G01X1116976D02*
X1115323D01*
G01X1124850D02*
X1123197D01*
G01X1132724D02*
X1131071D01*
G01X1140598D02*
X1138945D01*
G01X1101071Y602602D02*
X1099732D01*
G01X1108945D02*
X1107606D01*
G01X1116819D02*
X1115480D01*
G01X1124693D02*
X1123354D01*
G01X1132567D02*
X1131228D01*
G01X1140441D02*
X1139102D01*
G01Y601618D02*
X1140441D01*
G01X1131228D02*
X1132567D01*
G01X1123354D02*
X1124693D01*
G01X1115480D02*
X1116819D01*
G01X1107606D02*
X1108945D01*
G01X1099732D02*
X1101071D01*
G01X1094496Y601126D02*
X1090559D01*
G01X1101204Y600999D02*
X1099609D01*
G01X1105136D02*
X1103541D01*
G01X1109078D02*
X1107483D01*
G01X1113010D02*
X1111415D01*
G01X1116952D02*
X1115357D01*
G01X1120884D02*
X1119289D01*
G01X1124826D02*
X1123231D01*
G01X1128758D02*
X1127163D01*
G01X1132700D02*
X1131105D01*
G01X1136632D02*
X1135037D01*
G01X1140574D02*
X1138979D01*
G01X1101504Y600890D02*
X1099299D01*
G01X1105441D02*
X1103236D01*
G01X1109378D02*
X1107173D01*
G01X1113315D02*
X1111110D01*
G01X1117252D02*
X1115047D01*
G01X1121189D02*
X1118984D01*
G01X1125126D02*
X1122921D01*
G01X1129063D02*
X1126858D01*
G01X1133000D02*
X1130795D01*
G01X1136937D02*
X1134732D01*
G01X1140874D02*
X1138669D01*
G01X1142932Y600732D02*
X1094957D01*
G01X1101276Y600239D02*
X1099537D01*
G01X1105208D02*
X1103469D01*
G01X1109150D02*
X1107411D01*
G01X1113082D02*
X1111343D01*
G01X1117024D02*
X1115285D01*
G01X1120956D02*
X1119217D01*
G01X1124898D02*
X1123159D01*
G01X1128830D02*
X1127091D01*
G01X1132772D02*
X1131033D01*
G01X1136704D02*
X1134965D01*
G01X1140646D02*
X1138907D01*
G01X1138981Y600037D02*
X1140572D01*
G01X1135039D02*
X1136630D01*
G01X1131107D02*
X1132698D01*
G01X1127165D02*
X1128756D01*
G01X1123233D02*
X1124824D01*
G01X1119291D02*
X1120882D01*
G01X1115359D02*
X1116950D01*
G01X1111417D02*
X1113008D01*
G01X1107485D02*
X1109076D01*
G01X1103543D02*
X1105134D01*
G01X1099611D02*
X1101201D01*
G01X1138928Y600013D02*
X1140624D01*
G01X1134987D02*
X1136683D01*
G01X1131054D02*
X1132750D01*
G01X1127113D02*
X1128809D01*
G01X1123180D02*
X1124876D01*
G01X1119239D02*
X1120935D01*
G01X1115306D02*
X1117002D01*
G01X1111365D02*
X1113061D01*
G01X1107432D02*
X1109128D01*
G01X1103491D02*
X1105187D01*
G01X1099558D02*
X1101254D01*
G01X1101261Y599945D02*
X1099551D01*
G01X1105194D02*
X1103484D01*
G01X1109135D02*
X1107425D01*
G01X1113068D02*
X1111358D01*
G01X1117009D02*
X1115299D01*
G01X1120942D02*
X1119232D01*
G01X1124883D02*
X1123173D01*
G01X1128816D02*
X1127106D01*
G01X1132757D02*
X1131047D01*
G01X1136690D02*
X1134980D01*
G01X1140631D02*
X1138921D01*
G01X1138902Y599353D02*
X1140650D01*
G01X1134960D02*
X1136709D01*
G01X1131028D02*
X1132776D01*
G01X1127086D02*
X1128835D01*
G01X1123154D02*
X1124902D01*
G01X1119212D02*
X1120961D01*
G01X1115280D02*
X1117028D01*
G01X1111338D02*
X1113087D01*
G01X1107406D02*
X1109154D01*
G01X1103464D02*
X1105213D01*
G01X1099532D02*
X1101280D01*
G01X1101252Y599051D02*
X1099560D01*
G01X1105184D02*
X1103493D01*
G01X1109126D02*
X1107435D01*
G01X1113058D02*
X1111367D01*
G01X1117000D02*
X1115309D01*
G01X1120932D02*
X1119241D01*
G01X1124874D02*
X1123183D01*
G01X1128806D02*
X1127115D01*
G01X1132748D02*
X1131057D01*
G01X1136680D02*
X1134989D01*
G01X1140622D02*
X1138931D01*
G01X1101261Y598961D02*
X1099551D01*
G01X1105194D02*
X1103484D01*
G01X1109135D02*
X1107425D01*
G01X1113068D02*
X1111358D01*
G01X1117009D02*
X1115299D01*
G01X1120942D02*
X1119232D01*
G01X1124883D02*
X1123173D01*
G01X1128816D02*
X1127106D01*
G01X1132757D02*
X1131047D01*
G01X1136690D02*
X1134980D01*
G01X1140631D02*
X1138921D01*
G01X1101504Y598635D02*
X1099299D01*
G01X1105441D02*
X1103236D01*
G01X1109378D02*
X1107173D01*
G01X1113315D02*
X1111110D01*
G01X1117252D02*
X1115047D01*
G01X1121189D02*
X1118984D01*
G01X1125126D02*
X1122921D01*
G01X1129063D02*
X1126858D01*
G01X1133000D02*
X1130795D01*
G01X1136937D02*
X1134732D01*
G01X1140874D02*
X1138669D01*
G01Y598468D02*
X1140874D01*
G01X1134732D02*
X1136937D01*
G01X1130795D02*
X1133000D01*
G01X1126858D02*
X1129063D01*
G01X1122921D02*
X1125126D01*
G01X1118984D02*
X1121189D01*
G01X1115047D02*
X1117252D01*
G01X1111110D02*
X1113315D01*
G01X1107173D02*
X1109378D01*
G01X1103236D02*
X1105441D01*
G01X1099299D02*
X1101504D01*
G01Y595910D02*
X1099299D01*
G01X1105441D02*
X1103236D01*
G01X1109378D02*
X1107173D01*
G01X1113315D02*
X1111110D01*
G01X1117252D02*
X1115047D01*
G01X1121189D02*
X1118984D01*
G01X1125126D02*
X1122921D01*
G01X1129063D02*
X1126858D01*
G01X1133000D02*
X1130795D01*
G01X1136937D02*
X1134732D01*
G01X1140874D02*
X1138669D01*
G01Y595743D02*
X1140874D01*
G01X1134732D02*
X1136937D01*
G01X1130795D02*
X1133000D01*
G01X1126858D02*
X1129063D01*
G01X1122921D02*
X1125126D01*
G01X1118984D02*
X1121189D01*
G01X1115047D02*
X1117252D01*
G01X1111110D02*
X1113315D01*
G01X1107173D02*
X1109378D01*
G01X1103236D02*
X1105441D01*
G01X1099299D02*
X1101504D01*
G01X1138912Y595417D02*
X1140622D01*
G01X1134980D02*
X1136690D01*
G01X1131038D02*
X1132748D01*
G01X1127106D02*
X1128816D01*
G01X1123164D02*
X1124874D01*
G01X1119232D02*
X1120942D01*
G01X1115290D02*
X1117000D01*
G01X1111358D02*
X1113068D01*
G01X1107416D02*
X1109126D01*
G01X1103484D02*
X1105194D01*
G01X1099542D02*
X1101252D01*
G01X1138921Y595327D02*
X1140613D01*
G01X1134989D02*
X1136680D01*
G01X1131047D02*
X1132739D01*
G01X1127115D02*
X1128806D01*
G01X1123173D02*
X1124865D01*
G01X1119241D02*
X1120932D01*
G01X1115299D02*
X1116991D01*
G01X1111367D02*
X1113058D01*
G01X1107425D02*
X1109117D01*
G01X1103493D02*
X1105184D01*
G01X1099551D02*
X1101243D01*
G01X1101271Y595025D02*
X1099523D01*
G01X1105213D02*
X1103464D01*
G01X1109145D02*
X1107397D01*
G01X1113087D02*
X1111338D01*
G01X1117019D02*
X1115271D01*
G01X1120961D02*
X1119212D01*
G01X1124893D02*
X1123145D01*
G01X1128835D02*
X1127086D01*
G01X1132767D02*
X1131019D01*
G01X1136709D02*
X1134960D01*
G01X1140641D02*
X1138893D01*
G01X1138912Y594433D02*
X1140622D01*
G01X1134980D02*
X1136690D01*
G01X1131038D02*
X1132748D01*
G01X1127106D02*
X1128816D01*
G01X1123164D02*
X1124874D01*
G01X1119232D02*
X1120942D01*
G01X1115290D02*
X1117000D01*
G01X1111358D02*
X1113068D01*
G01X1107416D02*
X1109126D01*
G01X1103484D02*
X1105194D01*
G01X1099542D02*
X1101252D01*
G01X1101245Y594365D02*
X1099549D01*
G01X1105187D02*
X1103491D01*
G01X1109119D02*
X1107423D01*
G01X1113061D02*
X1111365D01*
G01X1116993D02*
X1115297D01*
G01X1120935D02*
X1119239D01*
G01X1124867D02*
X1123171D01*
G01X1128809D02*
X1127113D01*
G01X1132741D02*
X1131045D01*
G01X1136683D02*
X1134987D01*
G01X1140615D02*
X1138919D01*
G01X1101192Y594341D02*
X1099602D01*
G01X1105134D02*
X1103543D01*
G01X1109066D02*
X1107476D01*
G01X1113008D02*
X1111417D01*
G01X1116940D02*
X1115350D01*
G01X1120882D02*
X1119291D01*
G01X1124814D02*
X1123224D01*
G01X1128756D02*
X1127165D01*
G01X1132688D02*
X1131098D01*
G01X1136630D02*
X1135039D01*
G01X1140562D02*
X1138972D01*
G01X1138898Y594139D02*
X1140636D01*
G01X1134965D02*
X1136704D01*
G01X1131024D02*
X1132762D01*
G01X1127091D02*
X1128830D01*
G01X1123150D02*
X1124888D01*
G01X1119217D02*
X1120956D01*
G01X1115276D02*
X1117014D01*
G01X1111343D02*
X1113082D01*
G01X1107402D02*
X1109140D01*
G01X1103469D02*
X1105208D01*
G01X1099527D02*
X1101266D01*
G01X1094957Y593646D02*
X1142932D01*
G01X1138669Y593488D02*
X1140874D01*
G01X1134732D02*
X1136937D01*
G01X1130795D02*
X1133000D01*
G01X1126858D02*
X1129063D01*
G01X1122921D02*
X1125126D01*
G01X1118984D02*
X1121189D01*
G01X1115047D02*
X1117252D01*
G01X1111110D02*
X1113315D01*
G01X1107173D02*
X1109378D01*
G01X1103236D02*
X1105441D01*
G01X1099299D02*
X1101504D01*
G01X1138969Y593379D02*
X1140565D01*
G01X1135037D02*
X1136632D01*
G01X1131095D02*
X1132691D01*
G01X1127163D02*
X1128758D01*
G01X1123221D02*
X1124817D01*
G01X1119289D02*
X1120884D01*
G01X1115347D02*
X1116943D01*
G01X1111415D02*
X1113010D01*
G01X1107473D02*
X1109068D01*
G01X1103541D02*
X1105136D01*
G01X1099599D02*
X1101194D01*
G01X1090559Y593252D02*
X1094496D01*
G01X1101071Y592760D02*
X1099732D01*
G01X1108945D02*
X1107606D01*
G01X1116819D02*
X1115480D01*
G01X1124693D02*
X1123354D01*
G01X1132567D02*
X1131228D01*
G01X1140441D02*
X1139102D01*
G01X1101071Y591776D02*
X1099732D01*
G01X1108945D02*
X1107606D01*
G01X1116819D02*
X1115480D01*
G01X1124693D02*
X1123354D01*
G01X1132567D02*
X1131228D01*
G01X1140441D02*
X1139102D01*
G01X1138945Y591677D02*
X1140598D01*
G01X1131071D02*
X1132724D01*
G01X1123197D02*
X1124850D01*
G01X1115323D02*
X1116976D01*
G01X1107449D02*
X1109102D01*
G01X1099575D02*
X1101228D01*
G01Y591185D02*
X1099575D01*
G01X1109102D02*
X1107449D01*
G01X1116976D02*
X1115323D01*
G01X1124850D02*
X1123197D01*
G01X1132724D02*
X1131071D01*
G01X1140598D02*
X1138945D01*
G01X1094240Y590988D02*
X1089516D01*
G01X1093000Y590693D02*
X1434575D01*
G01X1101158Y590571D02*
X1099636D01*
G01X1105099D02*
X1103578D01*
G01X1109032D02*
X1107510D01*
G01X1112973D02*
X1111452D01*
G01X1116906D02*
X1115384D01*
G01X1120847D02*
X1119326D01*
G01X1124780D02*
X1123258D01*
G01X1128721D02*
X1127200D01*
G01X1132654D02*
X1131132D01*
G01X1136595D02*
X1135074D01*
G01X1140528D02*
X1139006D01*
G01X1101169Y590552D02*
X1099625D01*
G01X1105110D02*
X1103567D01*
G01X1109043D02*
X1107499D01*
G01X1112984D02*
X1111441D01*
G01X1116917D02*
X1115373D01*
G01X1120858D02*
X1119315D01*
G01X1124791D02*
X1123247D01*
G01X1128732D02*
X1127189D01*
G01X1132665D02*
X1131121D01*
G01X1136606D02*
X1135063D01*
G01X1140539D02*
X1138995D01*
G01X1099299Y590516D02*
X1098984D01*
G01X1101819D02*
X1101504D01*
G01X1103236D02*
X1102921D01*
G01X1105756D02*
X1105441D01*
G01X1107173D02*
X1106858D01*
G01X1109693D02*
X1109378D01*
G01X1111110D02*
X1110795D01*
G01X1113630D02*
X1113315D01*
G01X1115047D02*
X1114732D01*
G01X1117567D02*
X1117252D01*
G01X1118984D02*
X1118669D01*
G01X1122921D02*
X1122606D01*
G01X1121504D02*
X1121189D01*
G01X1125441D02*
X1125126D01*
G01X1126858D02*
X1126543D01*
G01X1129378D02*
X1129063D01*
G01X1130795D02*
X1130480D01*
G01X1133315D02*
X1133000D01*
G01X1134732D02*
X1134417D01*
G01X1137252D02*
X1136937D01*
G01X1138669D02*
X1138354D01*
G01X1141189D02*
X1140874D01*
G01X1101583Y589984D02*
X1099220D01*
G01X1105520D02*
X1103157D01*
G01X1109457D02*
X1107094D01*
G01X1113394D02*
X1111031D01*
G01X1117331D02*
X1114968D01*
G01X1121268D02*
X1118906D01*
G01X1125205D02*
X1122843D01*
G01X1129142D02*
X1126780D01*
G01X1133079D02*
X1130717D01*
G01X1137016D02*
X1134654D01*
G01X1140953D02*
X1138591D01*
G01X1100925Y589937D02*
X1099869D01*
G01X1104867D02*
X1103810D01*
G01X1108799D02*
X1107743D01*
G01X1112741D02*
X1111684D01*
G01X1116673D02*
X1115617D01*
G01X1120615D02*
X1119558D01*
G01X1124547D02*
X1123491D01*
G01X1128489D02*
X1127432D01*
G01X1132421D02*
X1131365D01*
G01X1136363D02*
X1135306D01*
G01X1140295D02*
X1139239D01*
G01X1139019Y589615D02*
X1140515D01*
G01X1135086D02*
X1136583D01*
G01X1131145D02*
X1132641D01*
G01X1127212D02*
X1128709D01*
G01X1123271D02*
X1124767D01*
G01X1119338D02*
X1120835D01*
G01X1115397D02*
X1116893D01*
G01X1111464D02*
X1112961D01*
G01X1107523D02*
X1109019D01*
G01X1103590D02*
X1105087D01*
G01X1099649D02*
X1101145D01*
G01X1148177Y589610D02*
X1143177D01*
G01X1139017Y589606D02*
X1140517D01*
G01X1135085D02*
X1136584D01*
G01X1131143D02*
X1132643D01*
G01X1127211D02*
X1128710D01*
G01X1123269D02*
X1124769D01*
G01X1119337D02*
X1120836D01*
G01X1115395D02*
X1116895D01*
G01X1111463D02*
X1112962D01*
G01X1107521D02*
X1109021D01*
G01X1103589D02*
X1105088D01*
G01X1099647D02*
X1101147D01*
G01X1101228Y589413D02*
X1099575D01*
G01X1109102D02*
X1107449D01*
G01X1116976D02*
X1115323D01*
G01X1124850D02*
X1123197D01*
G01X1132724D02*
X1131071D01*
G01X1140598D02*
X1138945D01*
G01X1138757Y589117D02*
X1140777D01*
G01X1134824D02*
X1136845D01*
G01X1130883D02*
X1132903D01*
G01X1126950D02*
X1128971D01*
G01X1123009D02*
X1125029D01*
G01X1119076D02*
X1121097D01*
G01X1115135D02*
X1117155D01*
G01X1111202D02*
X1113223D01*
G01X1107261D02*
X1109281D01*
G01X1103328D02*
X1105349D01*
G01X1099386D02*
X1101407D01*
G01X1140874Y589020D02*
X1141189D01*
G01X1133000D02*
X1133315D01*
G01X1125126D02*
X1125441D01*
G01X1117252D02*
X1117567D01*
G01X1109378D02*
X1109693D01*
G01X1101504D02*
X1101819D01*
G01X1099299D02*
X1098984D01*
G01X1103236D02*
X1102921D01*
G01X1105756D02*
X1105441D01*
G01X1107173D02*
X1106858D01*
G01X1111110D02*
X1110795D01*
G01X1113630D02*
X1113315D01*
G01X1115047D02*
X1114732D01*
G01X1118984D02*
X1118669D01*
G01X1122921D02*
X1122606D01*
G01X1121504D02*
X1121189D01*
G01X1126858D02*
X1126543D01*
G01X1129378D02*
X1129063D01*
G01X1130795D02*
X1130480D01*
G01X1134732D02*
X1134417D01*
G01X1137252D02*
X1136937D01*
G01X1138669D02*
X1138354D01*
G01X1139284Y589010D02*
X1140250D01*
G01X1135352D02*
X1136317D01*
G01X1131410D02*
X1132376D01*
G01X1127478D02*
X1128443D01*
G01X1123536D02*
X1124502D01*
G01X1119604D02*
X1120569D01*
G01X1115662D02*
X1116628D01*
G01X1111730D02*
X1112695D01*
G01X1107788D02*
X1108754D01*
G01X1103856D02*
X1104821D01*
G01X1099914D02*
X1100880D01*
G01X1138945Y588921D02*
X1140598D01*
G01X1131071D02*
X1132724D01*
G01X1123197D02*
X1124850D01*
G01X1115323D02*
X1116976D01*
G01X1107449D02*
X1109102D01*
G01X1099575D02*
X1101228D01*
G01X1138354Y588823D02*
X1141189D01*
G01X1134417D02*
X1137252D01*
G01X1130480D02*
X1133315D01*
G01X1126543D02*
X1129378D01*
G01X1122606D02*
X1125441D01*
G01X1118669D02*
X1121504D01*
G01X1114732D02*
X1117567D01*
G01X1110795D02*
X1113630D01*
G01X1106858D02*
X1109693D01*
G01X1102921D02*
X1105756D01*
G01X1098984D02*
X1101819D01*
G01X1140598Y588665D02*
X1141189D01*
G01X1138354D02*
X1138945D01*
G01X1136661D02*
X1137252D01*
G01X1134417D02*
X1135008D01*
G01X1132724D02*
X1133315D01*
G01X1130480D02*
X1131071D01*
G01X1128787D02*
X1129378D01*
G01X1126543D02*
X1127134D01*
G01X1124850D02*
X1125441D01*
G01X1122606D02*
X1123197D01*
G01X1120913D02*
X1121504D01*
G01X1118669D02*
X1119260D01*
G01X1116976D02*
X1117567D01*
G01X1114732D02*
X1115323D01*
G01X1113039D02*
X1113630D01*
G01X1110795D02*
X1111386D01*
G01X1109102D02*
X1109693D01*
G01X1106858D02*
X1107449D01*
G01X1105165D02*
X1105756D01*
G01X1102921D02*
X1103512D01*
G01X1101228D02*
X1101819D01*
G01X1098984D02*
X1099575D01*
G01X1101133Y588640D02*
X1099660D01*
G01X1105075D02*
X1103602D01*
G01X1109007D02*
X1107534D01*
G01X1112949D02*
X1111476D01*
G01X1116881D02*
X1115408D01*
G01X1120823D02*
X1119350D01*
G01X1124755D02*
X1123282D01*
G01X1128697D02*
X1127224D01*
G01X1132629D02*
X1131156D01*
G01X1136571D02*
X1135098D01*
G01X1140503D02*
X1139030D01*
G01X1139017Y588621D02*
X1140517D01*
G01X1135085D02*
X1136584D01*
G01X1131143D02*
X1132643D01*
G01X1127211D02*
X1128710D01*
G01X1123269D02*
X1124769D01*
G01X1119337D02*
X1120836D01*
G01X1115395D02*
X1116895D01*
G01X1111463D02*
X1112962D01*
G01X1107521D02*
X1109021D01*
G01X1103589D02*
X1105088D01*
G01X1099647D02*
X1101147D01*
G01X1101403Y588231D02*
X1099391D01*
G01X1105344D02*
X1103333D01*
G01X1109277D02*
X1107265D01*
G01X1113218D02*
X1111207D01*
G01X1117151D02*
X1115139D01*
G01X1121092D02*
X1119081D01*
G01X1125025D02*
X1123013D01*
G01X1128966D02*
X1126955D01*
G01X1132899D02*
X1130887D01*
G01X1136840D02*
X1134829D01*
G01X1140773D02*
X1138761D01*
G01X1099575Y587996D02*
X1098984D01*
G01X1101819D02*
X1101228D01*
G01X1103512D02*
X1102921D01*
G01X1105756D02*
X1105165D01*
G01X1107449D02*
X1106858D01*
G01X1109693D02*
X1109102D01*
G01X1111386D02*
X1110795D01*
G01X1113630D02*
X1113039D01*
G01X1115323D02*
X1114732D01*
G01X1117567D02*
X1116976D01*
G01X1119260D02*
X1118669D01*
G01X1121504D02*
X1120913D01*
G01X1123197D02*
X1122606D01*
G01X1125441D02*
X1124850D01*
G01X1127134D02*
X1126543D01*
G01X1129378D02*
X1128787D01*
G01X1131071D02*
X1130480D01*
G01X1133315D02*
X1132724D01*
G01X1135008D02*
X1134417D01*
G01X1137252D02*
X1136661D01*
G01X1138945D02*
X1138354D01*
G01X1141189D02*
X1140598D01*
G01X1101819Y587839D02*
X1098984D01*
G01X1105756D02*
X1102921D01*
G01X1109693D02*
X1106858D01*
G01X1113630D02*
X1110795D01*
G01X1117567D02*
X1114732D01*
G01X1121504D02*
X1118669D01*
G01X1125441D02*
X1122606D01*
G01X1129378D02*
X1126543D01*
G01X1133315D02*
X1130480D01*
G01X1137252D02*
X1134417D01*
G01X1141189D02*
X1138354D01*
G01X1105165Y587740D02*
X1103512D01*
G01X1113039D02*
X1111386D01*
G01X1120913D02*
X1119260D01*
G01X1128787D02*
X1127134D01*
G01X1136661D02*
X1135008D01*
G01Y587248D02*
X1136661D01*
G01X1127134D02*
X1128787D01*
G01X1119260D02*
X1120913D01*
G01X1111386D02*
X1113039D01*
G01X1103512D02*
X1105165D01*
G01X1138354Y586343D02*
X1141189D01*
G01X1134417D02*
X1137252D01*
G01X1130480D02*
X1133315D01*
G01X1126543D02*
X1129378D01*
G01X1122606D02*
X1125441D01*
G01X1118669D02*
X1121504D01*
G01X1114732D02*
X1117567D01*
G01X1110795D02*
X1113630D01*
G01X1106858D02*
X1109693D01*
G01X1102921D02*
X1105756D01*
G01X1098984D02*
X1101819D01*
G01X1135008Y585476D02*
X1136661D01*
G01X1127134D02*
X1128787D01*
G01X1119260D02*
X1120913D01*
G01X1111386D02*
X1113039D01*
G01X1103512D02*
X1105165D01*
G01X1138591Y585083D02*
X1140953D01*
G01X1134654D02*
X1137016D01*
G01X1130717D02*
X1133079D01*
G01X1126780D02*
X1129142D01*
G01X1122843D02*
X1125205D01*
G01X1118906D02*
X1121268D01*
G01X1114968D02*
X1117331D01*
G01X1111031D02*
X1113394D01*
G01X1107094D02*
X1109457D01*
G01X1103157D02*
X1105520D01*
G01X1099220D02*
X1101583D01*
G01X1094240D02*
X1089516D01*
G01X1105165Y584984D02*
X1103512D01*
G01X1113039D02*
X1111386D01*
G01X1120913D02*
X1119260D01*
G01X1128787D02*
X1127134D01*
G01X1136661D02*
X1135008D01*
G01X1143177Y584886D02*
X1148177D01*
G01X1105008D02*
X1103669D01*
G01X1112882D02*
X1111543D01*
G01X1120756D02*
X1119417D01*
G01X1128630D02*
X1127291D01*
G01X1136504D02*
X1135165D01*
G01X1138591Y583902D02*
X1140953D01*
G01X1134654D02*
X1137016D01*
G01X1130717D02*
X1133079D01*
G01X1126780D02*
X1129142D01*
G01X1122843D02*
X1125205D01*
G01X1118906D02*
X1121268D01*
G01X1114968D02*
X1117331D01*
G01X1111031D02*
X1113394D01*
G01X1107094D02*
X1109457D01*
G01X1103157D02*
X1105520D01*
G01X1099220D02*
X1101583D01*
G01X1438984Y582524D02*
X1088591D01*
G01X1148422Y600732D02*
X1146935Y602976D01*
G01X1142932Y593646D02*
X1144420Y591402D01*
G01X1139294Y605368D02*
X1139040Y605738D01*
G01X1139248Y604441D02*
X1139027Y604763D01*
G01X1135352Y605368D02*
X1135098Y605738D01*
G01X1135087Y604760D02*
X1135306Y604441D01*
G01X1131420Y605368D02*
X1131166Y605738D01*
G01X1131374Y604441D02*
X1131153Y604763D01*
G01X1140295Y589937D02*
X1140517Y589615D01*
G01X1140250Y589010D02*
X1140503Y588640D01*
G01X1127478Y605368D02*
X1127224Y605738D01*
G01X1127213Y604760D02*
X1127432Y604441D01*
G01X1136583Y589618D02*
X1136363Y589937D01*
G01X1136317Y589010D02*
X1136571Y588640D01*
G01X1123546Y605368D02*
X1123292Y605738D01*
G01X1123500Y604441D02*
X1123279Y604763D01*
G01X1132421Y589937D02*
X1132643Y589615D01*
G01X1132376Y589010D02*
X1132629Y588640D01*
G01X1119604Y605368D02*
X1119350Y605738D01*
G01X1119339Y604760D02*
X1119558Y604441D01*
G01X1128709Y589618D02*
X1128489Y589937D01*
G01X1128443Y589010D02*
X1128697Y588640D01*
G01X1115672Y605368D02*
X1115418Y605738D01*
G01X1115626Y604441D02*
X1115405Y604763D01*
G01X1124547Y589937D02*
X1124769Y589615D01*
G01X1124502Y589010D02*
X1124755Y588640D01*
G01X1111730Y605368D02*
X1111476Y605738D01*
G01X1111465Y604760D02*
X1111684Y604441D01*
G01X1120835Y589618D02*
X1120615Y589937D01*
G01X1120569Y589010D02*
X1120823Y588640D01*
G01X1107798Y605368D02*
X1107544Y605738D01*
G01X1107752Y604441D02*
X1107531Y604763D01*
G01X1116673Y589937D02*
X1116895Y589615D01*
G01X1116628Y589010D02*
X1116881Y588640D01*
G01X1103856Y605368D02*
X1103602Y605738D01*
G01X1103591Y604760D02*
X1103810Y604441D01*
G01X1112961Y589618D02*
X1112741Y589937D01*
G01X1112695Y589010D02*
X1112949Y588640D01*
G01X1099924Y605368D02*
X1099670Y605738D01*
G01X1099878Y604441D02*
X1099657Y604763D01*
G01X1108799Y589937D02*
X1109021Y589615D01*
G01X1108754Y589010D02*
X1109007Y588640D01*
G01X1105087Y589618D02*
X1104867Y589937D01*
G01X1104821Y589010D02*
X1105075Y588640D01*
G01X1100925Y589937D02*
X1101147Y589615D01*
G01X1093000Y603685D02*
X1094957Y600732D01*
G01X1100880Y589010D02*
X1101133Y588640D01*
G01X1139248Y604441D02*
X1139258Y604394D01*
G01X1140295Y589937D02*
X1140286Y589984D01*
G01X1135316Y604394D02*
X1135306Y604441D01*
G01X1136353Y589984D02*
X1136363Y589937D01*
G01X1131374Y604441D02*
X1131384Y604394D01*
G01X1132421Y589937D02*
X1132412Y589984D01*
G01X1127442Y604394D02*
X1127432Y604441D01*
G01X1128479Y589984D02*
X1128489Y589937D01*
G01X1123500Y604441D02*
X1123510Y604394D01*
G01X1124547Y589937D02*
X1124538Y589984D01*
G01X1119568Y604394D02*
X1119558Y604441D01*
G01X1120605Y589984D02*
X1120615Y589937D01*
G01X1115626Y604441D02*
X1115636Y604394D01*
G01X1116673Y589937D02*
X1116664Y589984D01*
G01X1111694Y604394D02*
X1111684Y604441D01*
G01X1112731Y589984D02*
X1112741Y589937D01*
G01X1107752Y604441D02*
X1107762Y604394D01*
G01X1108799Y589937D02*
X1108790Y589984D01*
G01X1090231Y616854D02*
X1090969Y614592D01*
G01X1091379Y613252D02*
X1091051Y614257D01*
G01X1090559Y617189D02*
X1091871Y613252D01*
G01X1140650Y599353D02*
X1140787Y605261D01*
G01X1140782Y606147D02*
X1140646Y600239D01*
G01X1140263Y589984D02*
X1140250Y589010D01*
G01X1139281Y604394D02*
X1139294Y605368D01*
G01X1146935Y591402D02*
Y602976D01*
G01X1144420D02*
Y591402D01*
G01X1143177Y589610D02*
Y584886D01*
G01Y609492D02*
Y604768D01*
G01X1142628Y593646D02*
Y600732D01*
G01X1142272D02*
Y593646D01*
G01X1141189Y603862D02*
Y608035D01*
G01Y586343D02*
Y590516D01*
G01X1141154Y606539D02*
Y605555D01*
G01X1141150Y588823D02*
Y587839D01*
G01X1141145Y588823D02*
Y587839D01*
G01X1140953Y589984D02*
Y583902D01*
G01Y610476D02*
Y604394D01*
G01X1140874Y587839D02*
Y606539D01*
G01X1140800Y606538D02*
Y605553D01*
G01X1140791Y588825D02*
Y587840D01*
G01X1140598Y601698D02*
Y606539D01*
G01Y587839D02*
Y592680D01*
G01X1140524Y604760D02*
Y605751D01*
G01X1140515Y588627D02*
Y589618D01*
G01X1140441Y592760D02*
Y591696D01*
G01Y602681D02*
Y601618D01*
G01X1140165D02*
Y602602D01*
G01Y592760D02*
Y591776D01*
G01X1139378Y592760D02*
Y591776D01*
G01Y602602D02*
Y601618D01*
G01X1139102Y592760D02*
Y591696D01*
G01Y602682D02*
Y601618D01*
G01X1139028Y605751D02*
Y604760D01*
G01X1139019Y589618D02*
Y588627D01*
G01X1138945Y601698D02*
Y606539D01*
G01Y587839D02*
Y592680D01*
G01X1138753Y605553D02*
Y606538D01*
G01X1138743Y587840D02*
Y588825D01*
G01X1138669Y606539D02*
Y587839D01*
G01X1138591Y589984D02*
Y583902D01*
G01Y610476D02*
Y604394D01*
G01X1138398Y606539D02*
Y605555D01*
G01X1138394Y606539D02*
Y605555D01*
G01X1138389Y588823D02*
Y587839D01*
G01X1138354Y590516D02*
Y586343D01*
G01Y608035D02*
Y603862D01*
G01X1140259Y605368D02*
X1140272Y604394D01*
G01X1139284Y589010D02*
X1139271Y589984D01*
G01X1136317Y605368D02*
X1136330Y604394D01*
G01X1140777Y589117D02*
X1140641Y595025D01*
G01X1140636Y594139D02*
X1140773Y588231D01*
G01X1138907Y600239D02*
X1138771Y606147D01*
G01X1138766Y605261D02*
X1138902Y599353D01*
G01X1136845Y589117D02*
X1136709Y595025D01*
G01X1136704Y594139D02*
X1136840Y588231D01*
G01X1134965Y600239D02*
X1134829Y606147D01*
G01X1134824Y605261D02*
X1134960Y599353D01*
G01X1140624Y600013D02*
X1140574Y600999D01*
G01X1140572Y600037D02*
X1140622Y599051D01*
G01X1138972Y594341D02*
X1138921Y595327D01*
G01X1138919Y594365D02*
X1138969Y593379D01*
G01X1136683Y600013D02*
X1136632Y600999D01*
G01X1136630Y600037D02*
X1136680Y599051D01*
G01X1135039Y594341D02*
X1134989Y595327D01*
G01X1134987Y594365D02*
X1135037Y593379D01*
G01X1132750Y600013D02*
X1132700Y600999D01*
G01X1132698Y600037D02*
X1132748Y599051D01*
G01X1131098Y594341D02*
X1131047Y595327D01*
G01X1131045Y594365D02*
X1131095Y593379D01*
G01X1103820Y604394D02*
X1103810Y604441D01*
G01X1104857Y589984D02*
X1104867Y589937D01*
G01X1099878Y604441D02*
X1099888Y604394D01*
G01X1100925Y589937D02*
X1100916Y589984D01*
G01X1139248D02*
X1139239Y589937D01*
G01X1140295Y604394D02*
X1140305Y604441D01*
G01X1140565Y593379D02*
X1140615Y594365D01*
G01X1140613Y595327D02*
X1140562Y594341D01*
G01X1138931Y599051D02*
X1138981Y600037D01*
G01X1138979Y600999D02*
X1138928Y600013D01*
G01X1136632Y593379D02*
X1136683Y594365D01*
G01X1136680Y595327D02*
X1136630Y594341D01*
G01X1134989Y599051D02*
X1135039Y600037D01*
G01X1135037Y600999D02*
X1134987Y600013D01*
G01X1132691Y593379D02*
X1132741Y594365D01*
G01X1132739Y595327D02*
X1132688Y594341D01*
G01X1131057Y599051D02*
X1131107Y600037D01*
G01X1131105Y600999D02*
X1131054Y600013D01*
G01X1128758Y593379D02*
X1128809Y594365D01*
G01X1128806Y595327D02*
X1128756Y594341D01*
G01X1127115Y599051D02*
X1127165Y600037D01*
G01X1127163Y600999D02*
X1127113Y600013D01*
G01X1124817Y593379D02*
X1124867Y594365D01*
G01X1124865Y595327D02*
X1124814Y594341D01*
G01X1123183Y599051D02*
X1123233Y600037D01*
G01X1123231Y600999D02*
X1123180Y600013D01*
G01X1120884Y593379D02*
X1120935Y594365D01*
G01X1120932Y595327D02*
X1120882Y594341D01*
G01X1138761Y588231D02*
X1138898Y594139D01*
G01X1138893Y595025D02*
X1138757Y589117D01*
G01X1136709Y599353D02*
X1136845Y605261D01*
G01X1136840Y606147D02*
X1136704Y600239D01*
G01X1134829Y588231D02*
X1134965Y594139D01*
G01X1134960Y595025D02*
X1134824Y589117D01*
G01X1132776Y599353D02*
X1132913Y605261D01*
G01X1132908Y606147D02*
X1132772Y600239D01*
G01X1130887Y588231D02*
X1131024Y594139D01*
G01X1131019Y595025D02*
X1130883Y589117D01*
G01X1128835Y599353D02*
X1128971Y605261D01*
G01X1128966Y606147D02*
X1128830Y600239D01*
G01X1126955Y588231D02*
X1127091Y594139D01*
G01X1127086Y595025D02*
X1126950Y589117D01*
G01X1124902Y599353D02*
X1125039Y605261D01*
G01X1125034Y606147D02*
X1124898Y600239D01*
G01X1123013Y588231D02*
X1123150Y594139D01*
G01X1123145Y595025D02*
X1123009Y589117D01*
G01X1120961Y599353D02*
X1121097Y605261D01*
G01X1121092Y606147D02*
X1120956Y600239D01*
G01X1119081Y588231D02*
X1119217Y594139D01*
G01X1119212Y595025D02*
X1119076Y589117D01*
G01X1117028Y599353D02*
X1117165Y605261D01*
G01X1117160Y606147D02*
X1117024Y600239D01*
G01X1136330Y589984D02*
X1136317Y589010D01*
G01X1135339Y604394D02*
X1135352Y605368D01*
G01X1132389Y589984D02*
X1132376Y589010D01*
G01X1131406Y604394D02*
X1131420Y605368D01*
G01X1128456Y589984D02*
X1128443Y589010D01*
G01X1127465Y604394D02*
X1127478Y605368D01*
G01X1124515Y589984D02*
X1124502Y589010D01*
G01X1123532Y604394D02*
X1123546Y605368D01*
G01X1120582Y589984D02*
X1120569Y589010D01*
G01X1119591Y604394D02*
X1119604Y605368D01*
G01X1116641Y589984D02*
X1116628Y589010D01*
G01X1115658Y604394D02*
X1115672Y605368D01*
G01X1137252Y603862D02*
Y608035D01*
G01Y586343D02*
Y590516D01*
G01X1137217Y588823D02*
Y587839D01*
G01X1137213Y588823D02*
Y587839D01*
G01Y606539D02*
Y605555D01*
G01X1137016Y589984D02*
Y583902D01*
G01Y610476D02*
Y604394D01*
G01X1136937Y587839D02*
Y606539D01*
G01X1136858Y588825D02*
Y587840D01*
G01Y606538D02*
Y605553D01*
G01X1136661Y605555D02*
Y610396D01*
G01Y583982D02*
Y588823D01*
G01X1136583Y604760D02*
Y605751D01*
G01Y588627D02*
Y589618D01*
G01X1136504Y584965D02*
Y583902D01*
G01Y610476D02*
Y609413D01*
G01X1136228Y583902D02*
Y584886D01*
G01Y610476D02*
Y609492D01*
G01X1135441Y584886D02*
Y583902D01*
G01Y610476D02*
Y609492D01*
G01X1135165Y584965D02*
Y583902D01*
G01Y610476D02*
Y609413D01*
G01X1135087Y589618D02*
Y588627D01*
G01Y605751D02*
Y604760D01*
G01X1135008Y605555D02*
Y610396D01*
G01Y583982D02*
Y588823D01*
G01X1134811Y605553D02*
Y606538D01*
G01Y587840D02*
Y588825D01*
G01X1134732Y606539D02*
Y587839D01*
G01X1134654Y589984D02*
Y583902D01*
G01Y610476D02*
Y604394D01*
G01X1134457Y588823D02*
Y587839D01*
G01Y606539D02*
Y605555D01*
G01X1134452Y606539D02*
Y605555D01*
G01X1134417Y590516D02*
Y586343D01*
G01Y608035D02*
Y603862D01*
G01X1133315D02*
Y608035D01*
G01Y586343D02*
Y590516D01*
G01X1133280Y606539D02*
Y605555D01*
G01X1133276Y588823D02*
Y587839D01*
G01X1133271Y588823D02*
Y587839D01*
G01X1133079Y589984D02*
Y583902D01*
G01Y610476D02*
Y604394D01*
G01X1133000Y587839D02*
Y606539D01*
G01X1132926Y606538D02*
Y605553D01*
G01X1132917Y588825D02*
Y587840D01*
G01X1132724Y601698D02*
Y606539D01*
G01Y587839D02*
Y592680D01*
G01X1132650Y604760D02*
Y605751D01*
G01X1132641Y588627D02*
Y589618D01*
G01X1132567Y592760D02*
Y591696D01*
G01Y602681D02*
Y601618D01*
G01X1132291D02*
Y602602D01*
G01Y592760D02*
Y591776D01*
G01X1131504Y592760D02*
Y591776D01*
G01Y602602D02*
Y601618D01*
G01X1131228Y592760D02*
Y591696D01*
G01Y602682D02*
Y601618D01*
G01X1131154Y605751D02*
Y604760D01*
G01X1131145Y589618D02*
Y588627D01*
G01X1131071Y601698D02*
Y606539D01*
G01Y587839D02*
Y592680D01*
G01X1130879Y605553D02*
Y606538D01*
G01X1130869Y587840D02*
Y588825D01*
G01X1130795Y606539D02*
Y587839D01*
G01X1130717Y589984D02*
Y583902D01*
G01Y610476D02*
Y604394D01*
G01X1130524Y606539D02*
Y605555D01*
G01X1130520Y606539D02*
Y605555D01*
G01X1130515Y588823D02*
Y587839D01*
G01X1130480Y590516D02*
Y586343D01*
G01Y608035D02*
Y603862D01*
G01X1129378D02*
Y608035D01*
G01Y586343D02*
Y590516D01*
G01X1129343Y588823D02*
Y587839D01*
G01X1129339Y588823D02*
Y587839D01*
G01Y606539D02*
Y605555D01*
G01X1129142Y589984D02*
Y583902D01*
G01Y610476D02*
Y604394D01*
G01X1129063Y587839D02*
Y606539D01*
G01X1128984Y588825D02*
Y587840D01*
G01Y606538D02*
Y605553D01*
G01X1128787Y605555D02*
Y610396D01*
G01Y583982D02*
Y588823D01*
G01X1128709Y604760D02*
Y605751D01*
G01Y588627D02*
Y589618D01*
G01X1128630Y584965D02*
Y583902D01*
G01Y610476D02*
Y609413D01*
G01X1128354Y583902D02*
Y584886D01*
G01Y610476D02*
Y609492D01*
G01X1127567Y584886D02*
Y583902D01*
G01Y610476D02*
Y609492D01*
G01X1127291Y584965D02*
Y583902D01*
G01Y610476D02*
Y609413D01*
G01X1127213Y589618D02*
Y588627D01*
G01Y605751D02*
Y604760D01*
G01X1127134Y605555D02*
Y610396D01*
G01Y583982D02*
Y588823D01*
G01X1126937Y605553D02*
Y606538D01*
G01Y587840D02*
Y588825D01*
G01X1126858Y606539D02*
Y587839D01*
G01X1126780Y589984D02*
Y583902D01*
G01Y610476D02*
Y604394D01*
G01X1126583Y588823D02*
Y587839D01*
G01Y606539D02*
Y605555D01*
G01X1126578Y606539D02*
Y605555D01*
G01X1126543Y590516D02*
Y586343D01*
G01Y608035D02*
Y603862D01*
G01X1125441D02*
Y608035D01*
G01Y586343D02*
Y590516D01*
G01X1125406Y606539D02*
Y605555D01*
G01X1125402Y588823D02*
Y587839D01*
G01X1125397Y588823D02*
Y587839D01*
G01X1125205Y589984D02*
Y583902D01*
G01Y610476D02*
Y604394D01*
G01X1125126Y587839D02*
Y606539D01*
G01X1125052Y606538D02*
Y605553D01*
G01X1125043Y588825D02*
Y587840D01*
G01X1124850Y601698D02*
Y606539D01*
G01Y587839D02*
Y592680D01*
G01X1124776Y604760D02*
Y605751D01*
G01X1124767Y588627D02*
Y589618D01*
G01X1124693Y592760D02*
Y591696D01*
G01Y602681D02*
Y601618D01*
G01X1124417D02*
Y602602D01*
G01Y592760D02*
Y591776D01*
G01X1123630Y592760D02*
Y591776D01*
G01Y602602D02*
Y601618D01*
G01X1123354Y592760D02*
Y591696D01*
G01Y602682D02*
Y601618D01*
G01X1123280Y605751D02*
Y604760D01*
G01X1123271Y589618D02*
Y588627D01*
G01X1123197Y601698D02*
Y606539D01*
G01Y587839D02*
Y592680D01*
G01X1123005Y605553D02*
Y606538D01*
G01X1122995Y587840D02*
Y588825D01*
G01X1122921Y606539D02*
Y587839D01*
G01X1122843Y589984D02*
Y583902D01*
G01Y610476D02*
Y604394D01*
G01X1122650Y606539D02*
Y605555D01*
G01X1122646Y606539D02*
Y605555D01*
G01X1122641Y588823D02*
Y587839D01*
G01X1122606Y590516D02*
Y586343D01*
G01Y608035D02*
Y603862D01*
G01X1121504D02*
Y608035D01*
G01Y586343D02*
Y590516D01*
G01X1121469Y588823D02*
Y587839D01*
G01X1121465Y588823D02*
Y587839D01*
G01Y606539D02*
Y605555D01*
G01X1121268Y589984D02*
Y583902D01*
G01Y610476D02*
Y604394D01*
G01X1121189Y587839D02*
Y606539D01*
G01X1121110Y588825D02*
Y587840D01*
G01Y606538D02*
Y605553D01*
G01X1120913Y605555D02*
Y610396D01*
G01Y583982D02*
Y588823D01*
G01X1120835Y604760D02*
Y605751D01*
G01Y588627D02*
Y589618D01*
G01X1120756Y584965D02*
Y583902D01*
G01Y610476D02*
Y609413D01*
G01X1120480Y583902D02*
Y584886D01*
G01Y610476D02*
Y609492D01*
G01X1119693Y584886D02*
Y583902D01*
G01Y610476D02*
Y609492D01*
G01X1119417Y584965D02*
Y583902D01*
G01Y610476D02*
Y609413D01*
G01X1119339Y589618D02*
Y588627D01*
G01Y605751D02*
Y604760D01*
G01X1119260Y605555D02*
Y610396D01*
G01Y583982D02*
Y588823D01*
G01X1119063Y587840D02*
Y588825D01*
G01Y605553D02*
Y606538D01*
G01X1118984Y606539D02*
Y587839D01*
G01X1118906Y589984D02*
Y583902D01*
G01Y610476D02*
Y604394D01*
G01X1118709Y588823D02*
Y587839D01*
G01Y606539D02*
Y605555D01*
G01X1118704Y606539D02*
Y605555D01*
G01X1118669Y590516D02*
Y586343D01*
G01Y608035D02*
Y603862D01*
G01X1117567D02*
Y608035D01*
G01Y586343D02*
Y590516D01*
G01X1117532Y606539D02*
Y605555D01*
G01X1117528Y588823D02*
Y587839D01*
G01X1117523Y588823D02*
Y587839D01*
G01X1117331Y589984D02*
Y583902D01*
G01Y610476D02*
Y604394D01*
G01X1117252Y587839D02*
Y606539D01*
G01X1117178Y606538D02*
Y605553D01*
G01X1117169Y588825D02*
Y587840D01*
G01X1116976Y601698D02*
Y606539D01*
G01Y587839D02*
Y592680D01*
G01X1116902Y604760D02*
Y605751D01*
G01X1116893Y588627D02*
Y589618D01*
G01X1116819Y592760D02*
Y591696D01*
G01Y602681D02*
Y601618D01*
G01X1116543D02*
Y602602D01*
G01Y592760D02*
Y591776D01*
G01X1115756Y601618D02*
Y602602D01*
G01Y592760D02*
Y591776D01*
G01X1115480Y592760D02*
Y591696D01*
G01Y602682D02*
Y601618D01*
G01X1115406Y605751D02*
Y604760D01*
G01X1115397Y589618D02*
Y588627D01*
G01X1115323Y601698D02*
Y606539D01*
G01Y587839D02*
Y592680D01*
G01X1115131Y605553D02*
Y606538D01*
G01X1115121Y587840D02*
Y588825D01*
G01X1115047Y606539D02*
Y587839D01*
G01X1114968Y589984D02*
Y583902D01*
G01Y610476D02*
Y604394D01*
G01X1114776Y606539D02*
Y605555D01*
G01X1114772Y606539D02*
Y605555D01*
G01X1114767Y588823D02*
Y587839D01*
G01X1114732Y590516D02*
Y586343D01*
G01Y608035D02*
Y603862D01*
G01X1113630D02*
Y608035D01*
G01Y586343D02*
Y590516D01*
G01X1113595Y588823D02*
Y587839D01*
G01X1113591Y588823D02*
Y587839D01*
G01Y606539D02*
Y605555D01*
G01X1113394Y589984D02*
Y583902D01*
G01Y610476D02*
Y604394D01*
G01X1113315Y587839D02*
Y606539D01*
G01X1113236Y588825D02*
Y587840D01*
G01Y606538D02*
Y605553D01*
G01X1113039Y605555D02*
Y610396D01*
G01Y583982D02*
Y588823D01*
G01X1112961Y604760D02*
Y605751D01*
G01Y588627D02*
Y589618D01*
G01X1112882Y584965D02*
Y583902D01*
G01Y610476D02*
Y609413D01*
G01X1135352Y589010D02*
X1135339Y589984D01*
G01X1132385Y605368D02*
X1132398Y604394D01*
G01X1131410Y589010D02*
X1131397Y589984D01*
G01X1128443Y605368D02*
X1128456Y604394D01*
G01X1127478Y589010D02*
X1127465Y589984D01*
G01X1124511Y605368D02*
X1124524Y604394D01*
G01X1123536Y589010D02*
X1123523Y589984D01*
G01X1120569Y605368D02*
X1120582Y604394D01*
G01X1119604Y589010D02*
X1119591Y589984D01*
G01X1116637Y605368D02*
X1116650Y604394D01*
G01X1115662Y589010D02*
X1115649Y589984D01*
G01X1112695Y605368D02*
X1112708Y604394D01*
G01X1111730Y589010D02*
X1111717Y589984D01*
G01X1132903Y589117D02*
X1132767Y595025D01*
G01X1132762Y594139D02*
X1132899Y588231D01*
G01X1131033Y600239D02*
X1130897Y606147D01*
G01X1130892Y605261D02*
X1131028Y599353D01*
G01X1128971Y589117D02*
X1128835Y595025D01*
G01X1128830Y594139D02*
X1128966Y588231D01*
G01X1127091Y600239D02*
X1126955Y606147D01*
G01X1126950Y605261D02*
X1127086Y599353D01*
G01X1125029Y589117D02*
X1124893Y595025D01*
G01X1124888Y594139D02*
X1125025Y588231D01*
G01X1123159Y600239D02*
X1123023Y606147D01*
G01X1123018Y605261D02*
X1123154Y599353D01*
G01X1121097Y589117D02*
X1120961Y595025D01*
G01X1120956Y594139D02*
X1121092Y588231D01*
G01X1119217Y600239D02*
X1119081Y606147D01*
G01X1119076Y605261D02*
X1119212Y599353D01*
G01X1117155Y589117D02*
X1117019Y595025D01*
G01X1117014Y594139D02*
X1117151Y588231D01*
G01X1115285Y600239D02*
X1115149Y606147D01*
G01X1115144Y605261D02*
X1115280Y599353D01*
G01X1113223Y589117D02*
X1113087Y595025D01*
G01X1113082Y594139D02*
X1113218Y588231D01*
G01X1111343Y600239D02*
X1111207Y606147D01*
G01X1111202Y605261D02*
X1111338Y599353D01*
G01X1128809Y600013D02*
X1128758Y600999D01*
G01X1128756Y600037D02*
X1128806Y599051D01*
G01X1127165Y594341D02*
X1127115Y595327D01*
G01X1127113Y594365D02*
X1127163Y593379D01*
G01X1124876Y600013D02*
X1124826Y600999D01*
G01X1124824Y600037D02*
X1124874Y599051D01*
G01X1123224Y594341D02*
X1123173Y595327D01*
G01X1123171Y594365D02*
X1123221Y593379D01*
G01X1120935Y600013D02*
X1120884Y600999D01*
G01X1120882Y600037D02*
X1120932Y599051D01*
G01X1119291Y594341D02*
X1119241Y595327D01*
G01X1119239Y594365D02*
X1119289Y593379D01*
G01X1117002Y600013D02*
X1116952Y600999D01*
G01X1116950Y600037D02*
X1117000Y599051D01*
G01X1115350Y594341D02*
X1115299Y595327D01*
G01X1115297Y594365D02*
X1115347Y593379D01*
G01X1113061Y600013D02*
X1113010Y600999D01*
G01X1113008Y600037D02*
X1113058Y599051D01*
G01X1111417Y594341D02*
X1111367Y595327D01*
G01X1111365Y594365D02*
X1111415Y593379D01*
G01X1109128Y600013D02*
X1109078Y600999D01*
G01X1109076Y600037D02*
X1109126Y599051D01*
G01X1107476Y594341D02*
X1107425Y595327D01*
G01X1107423Y594365D02*
X1107473Y593379D01*
G01X1139030Y588640D02*
X1139284Y589010D01*
G01X1139017Y589615D02*
X1139239Y589937D01*
G01X1135098Y588640D02*
X1135352Y589010D01*
G01X1135306Y589937D02*
X1135087Y589618D01*
G01X1146935Y591402D02*
X1148422Y593646D01*
G01X1144420Y602976D02*
X1142932Y600732D01*
G01X1135306Y589937D02*
X1135316Y589984D01*
G01X1136363Y604441D02*
X1136353Y604394D01*
G01X1131374Y589984D02*
X1131365Y589937D01*
G01X1132421Y604394D02*
X1132431Y604441D01*
G01X1127432Y589937D02*
X1127442Y589984D01*
G01X1128489Y604441D02*
X1128479Y604394D01*
G01X1123500Y589984D02*
X1123491Y589937D01*
G01X1124547Y604394D02*
X1124557Y604441D01*
G01X1119558Y589937D02*
X1119568Y589984D01*
G01X1120615Y604441D02*
X1120605Y604394D01*
G01X1115626Y589984D02*
X1115617Y589937D01*
G01X1116673Y604394D02*
X1116683Y604441D01*
G01X1111684Y589937D02*
X1111694Y589984D01*
G01X1119241Y599051D02*
X1119291Y600037D01*
G01X1119289Y600999D02*
X1119239Y600013D01*
G01X1116943Y593379D02*
X1116993Y594365D01*
G01X1116991Y595327D02*
X1116940Y594341D01*
G01X1115309Y599051D02*
X1115359Y600037D01*
G01X1115357Y600999D02*
X1115306Y600013D01*
G01X1113010Y593379D02*
X1113061Y594365D01*
G01X1113058Y595327D02*
X1113008Y594341D01*
G01X1111367Y599051D02*
X1111417Y600037D01*
G01X1111415Y600999D02*
X1111365Y600013D01*
G01X1109068Y593379D02*
X1109119Y594365D01*
G01X1109117Y595327D02*
X1109066Y594341D01*
G01X1107435Y599051D02*
X1107485Y600037D01*
G01X1107483Y600999D02*
X1107432Y600013D01*
G01X1105136Y593379D02*
X1105187Y594365D01*
G01X1105184Y595327D02*
X1105134Y594341D01*
G01X1103493Y599051D02*
X1103543Y600037D01*
G01X1103541Y600999D02*
X1103491Y600013D01*
G01X1101194Y593379D02*
X1101245Y594365D01*
G01X1101243Y595327D02*
X1101192Y594341D01*
G01X1099560Y599051D02*
X1099611Y600037D01*
G01X1099609Y600999D02*
X1099558Y600013D01*
G01X1115139Y588231D02*
X1115276Y594139D01*
G01X1115271Y595025D02*
X1115135Y589117D01*
G01X1113087Y599353D02*
X1113223Y605261D01*
G01X1113218Y606147D02*
X1113082Y600239D01*
G01X1111207Y588231D02*
X1111343Y594139D01*
G01X1111338Y595025D02*
X1111202Y589117D01*
G01X1109154Y599353D02*
X1109291Y605261D01*
G01X1109286Y606147D02*
X1109150Y600239D01*
G01X1107265Y588231D02*
X1107402Y594139D01*
G01X1107397Y595025D02*
X1107261Y589117D01*
G01X1105213Y599353D02*
X1105349Y605261D01*
G01X1105344Y606147D02*
X1105208Y600239D01*
G01X1103333Y588231D02*
X1103469Y594139D01*
G01X1103464Y595025D02*
X1103328Y589117D01*
G01X1101280Y599353D02*
X1101417Y605261D01*
G01X1101412Y606147D02*
X1101276Y600239D01*
G01X1099391Y588231D02*
X1099527Y594139D01*
G01X1099523Y595025D02*
X1099386Y589117D01*
G01X1112708Y589984D02*
X1112695Y589010D01*
G01X1111717Y604394D02*
X1111730Y605368D01*
G01X1108767Y589984D02*
X1108754Y589010D01*
G01X1107784Y604394D02*
X1107798Y605368D01*
G01X1104834Y589984D02*
X1104821Y589010D01*
G01X1103843Y604394D02*
X1103856Y605368D01*
G01X1100893Y589984D02*
X1100880Y589010D01*
G01X1099910Y604394D02*
X1099924Y605368D01*
G01X1112606Y583902D02*
Y584886D01*
G01Y610476D02*
Y609492D01*
G01X1111819Y584886D02*
Y583902D01*
G01Y610476D02*
Y609492D01*
G01X1111543Y584965D02*
Y583902D01*
G01Y610476D02*
Y609413D01*
G01X1111465Y589618D02*
Y588627D01*
G01Y605751D02*
Y604760D01*
G01X1111386Y605555D02*
Y610396D01*
G01Y583982D02*
Y588823D01*
G01X1111189Y605553D02*
Y606538D01*
G01Y587840D02*
Y588825D01*
G01X1111110Y606539D02*
Y587839D01*
G01X1111031Y589984D02*
Y583902D01*
G01Y610476D02*
Y604394D01*
G01X1110835Y588823D02*
Y587839D01*
G01Y606539D02*
Y605555D01*
G01X1110830Y606539D02*
Y605555D01*
G01X1110795Y590516D02*
Y586343D01*
G01Y608035D02*
Y603862D01*
G01X1109693D02*
Y608035D01*
G01Y586343D02*
Y590516D01*
G01X1109658Y606539D02*
Y605555D01*
G01X1109654Y588823D02*
Y587839D01*
G01X1109649Y588823D02*
Y587839D01*
G01X1109457Y589984D02*
Y583902D01*
G01Y610476D02*
Y604394D01*
G01X1109378Y587839D02*
Y606539D01*
G01X1109304Y606538D02*
Y605553D01*
G01X1109295Y588825D02*
Y587840D01*
G01X1109102Y601698D02*
Y606539D01*
G01Y587839D02*
Y592680D01*
G01X1109028Y604760D02*
Y605751D01*
G01X1109019Y588627D02*
Y589618D01*
G01X1108945Y592760D02*
Y591696D01*
G01Y602681D02*
Y601618D01*
G01X1108669D02*
Y602602D01*
G01Y592760D02*
Y591776D01*
G01X1107882Y601618D02*
Y602602D01*
G01Y592760D02*
Y591776D01*
G01X1107606Y592760D02*
Y591696D01*
G01Y602682D02*
Y601618D01*
G01X1107532Y605751D02*
Y604760D01*
G01X1107523Y589618D02*
Y588627D01*
G01X1107449Y601698D02*
Y606539D01*
G01Y587839D02*
Y592680D01*
G01X1107257Y605553D02*
Y606538D01*
G01X1107247Y587840D02*
Y588825D01*
G01X1107173Y606539D02*
Y587839D01*
G01X1107094Y589984D02*
Y583902D01*
G01Y610476D02*
Y604394D01*
G01X1106902Y606539D02*
Y605555D01*
G01X1106898Y606539D02*
Y605555D01*
G01X1106893Y588823D02*
Y587839D01*
G01X1106858Y590516D02*
Y586343D01*
G01Y608035D02*
Y603862D01*
G01X1105756D02*
Y608035D01*
G01Y586343D02*
Y590516D01*
G01X1105721Y588823D02*
Y587839D01*
G01X1105717Y588823D02*
Y587839D01*
G01Y606539D02*
Y605555D01*
G01X1105520Y589984D02*
Y583902D01*
G01Y610476D02*
Y604394D01*
G01X1105441Y587839D02*
Y606539D01*
G01X1105362Y588825D02*
Y587840D01*
G01Y606538D02*
Y605553D01*
G01X1105165Y605555D02*
Y610396D01*
G01Y583982D02*
Y588823D01*
G01X1105087Y604760D02*
Y605751D01*
G01Y588627D02*
Y589618D01*
G01X1105008Y584965D02*
Y583902D01*
G01Y610476D02*
Y609413D01*
G01X1104732Y583902D02*
Y584886D01*
G01Y610476D02*
Y609492D01*
G01X1103945Y584886D02*
Y583902D01*
G01Y610476D02*
Y609492D01*
G01X1103669Y584965D02*
Y583902D01*
G01Y610476D02*
Y609413D01*
G01X1103591Y589618D02*
Y588627D01*
G01Y605751D02*
Y604760D01*
G01X1103512Y605555D02*
Y610396D01*
G01Y583982D02*
Y588823D01*
G01X1103315Y605553D02*
Y606538D01*
G01Y587840D02*
Y588825D01*
G01X1103236Y606539D02*
Y587839D01*
G01X1103157Y589984D02*
Y583902D01*
G01Y610476D02*
Y604394D01*
G01X1102961Y588823D02*
Y587839D01*
G01Y606539D02*
Y605555D01*
G01X1102956Y606539D02*
Y605555D01*
G01X1102921Y590516D02*
Y586343D01*
G01Y608035D02*
Y603862D01*
G01X1101819D02*
Y608035D01*
G01Y586343D02*
Y590516D01*
G01X1101784Y606539D02*
Y605555D01*
G01X1101780Y588823D02*
Y587839D01*
G01X1101775Y588823D02*
Y587839D01*
G01X1101583Y589984D02*
Y583902D01*
G01Y610476D02*
Y604394D01*
G01X1101504Y587839D02*
Y606539D01*
G01X1101430Y606538D02*
Y605553D01*
G01X1101421Y588825D02*
Y587840D01*
G01X1101228Y601698D02*
Y606539D01*
G01Y587839D02*
Y592680D01*
G01X1101154Y604760D02*
Y605751D01*
G01X1101145Y588627D02*
Y589618D01*
G01X1101071Y592760D02*
Y591696D01*
G01Y602681D02*
Y601618D01*
G01X1100795D02*
Y602602D01*
G01Y592760D02*
Y591776D01*
G01X1100008Y592760D02*
Y591776D01*
G01Y602602D02*
Y601618D01*
G01X1099732Y592760D02*
Y591696D01*
G01Y602682D02*
Y601618D01*
G01X1099658Y605751D02*
Y604760D01*
G01X1099649Y589618D02*
Y588627D01*
G01X1099575Y601698D02*
Y606539D01*
G01Y587839D02*
Y592680D01*
G01X1099383Y605553D02*
Y606538D01*
G01X1099373Y587840D02*
Y588825D01*
G01X1099299Y606539D02*
Y587839D01*
G01X1099220Y589984D02*
Y583902D01*
G01Y610476D02*
Y604394D01*
G01X1099028Y606539D02*
Y605555D01*
G01X1099024Y606539D02*
Y605555D01*
G01X1099019Y588823D02*
Y587839D01*
G01X1098984Y590516D02*
Y586343D01*
G01Y608035D02*
Y603862D01*
G01X1096406Y600732D02*
Y593646D01*
G01X1095855Y611854D02*
Y608735D01*
G01X1094496Y593252D02*
Y601126D01*
G01X1094240Y590988D02*
Y585083D01*
G01Y609295D02*
Y603390D01*
G01X1093512Y617189D02*
Y613252D01*
G01X1093020D02*
Y616519D01*
G01X1093000Y603685D02*
Y590693D01*
G01X1092528Y615932D02*
Y616603D01*
G01X1092269Y611854D02*
Y608735D01*
G01X1090559Y601126D02*
Y593252D01*
G01X1089516Y590988D02*
Y585083D01*
G01Y609295D02*
Y603390D01*
G01X1108763Y605368D02*
X1108776Y604394D01*
G01X1107788Y589010D02*
X1107775Y589984D01*
G01X1104821Y605368D02*
X1104834Y604394D01*
G01X1103856Y589010D02*
X1103843Y589984D01*
G01X1100889Y605368D02*
X1100902Y604394D01*
G01X1099914Y589010D02*
X1099901Y589984D01*
G01X1109281Y589117D02*
X1109145Y595025D01*
G01X1109140Y594139D02*
X1109277Y588231D01*
G01X1107411Y600239D02*
X1107275Y606147D01*
G01X1107270Y605261D02*
X1107406Y599353D01*
G01X1105349Y589117D02*
X1105213Y595025D01*
G01X1105208Y594139D02*
X1105344Y588231D01*
G01X1103469Y600239D02*
X1103333Y606147D01*
G01X1103328Y605261D02*
X1103464Y599353D01*
G01X1101407Y589117D02*
X1101271Y595025D01*
G01X1101266Y594139D02*
X1101403Y588231D01*
G01X1099537Y600239D02*
X1099401Y606147D01*
G01X1099396Y605261D02*
X1099532Y599353D01*
G01X1105187Y600013D02*
X1105136Y600999D01*
G01X1105134Y600037D02*
X1105184Y599051D01*
G01X1103543Y594341D02*
X1103493Y595327D01*
G01X1103491Y594365D02*
X1103541Y593379D01*
G01X1101254Y600013D02*
X1101204Y600999D01*
G01X1101201Y600037D02*
X1101252Y599051D01*
G01X1099602Y594341D02*
X1099551Y595327D01*
G01X1099549Y594365D02*
X1099599Y593379D01*
G01X1131156Y588640D02*
X1131410Y589010D01*
G01X1131143Y589615D02*
X1131365Y589937D01*
G01X1140526Y604763D02*
X1140305Y604441D01*
G01X1140513Y605738D02*
X1140259Y605368D01*
G01X1127224Y588640D02*
X1127478Y589010D01*
G01X1127432Y589937D02*
X1127213Y589618D01*
G01X1136363Y604441D02*
X1136583Y604760D01*
G01X1136571Y605738D02*
X1136317Y605368D01*
G01X1123282Y588640D02*
X1123536Y589010D01*
G01X1123269Y589615D02*
X1123491Y589937D01*
G01X1132652Y604763D02*
X1132431Y604441D01*
G01X1132639Y605738D02*
X1132385Y605368D01*
G01X1119350Y588640D02*
X1119604Y589010D01*
G01X1119558Y589937D02*
X1119339Y589618D01*
G01X1128489Y604441D02*
X1128709Y604760D01*
G01X1128697Y605738D02*
X1128443Y605368D01*
G01X1115408Y588640D02*
X1115662Y589010D01*
G01X1115395Y589615D02*
X1115617Y589937D01*
G01X1124778Y604763D02*
X1124557Y604441D01*
G01X1124765Y605738D02*
X1124511Y605368D01*
G01X1111476Y588640D02*
X1111730Y589010D01*
G01X1111684Y589937D02*
X1111465Y589618D01*
G01X1120615Y604441D02*
X1120835Y604760D01*
G01X1120823Y605738D02*
X1120569Y605368D01*
G01X1107534Y588640D02*
X1107788Y589010D01*
G01X1107521Y589615D02*
X1107743Y589937D01*
G01X1116904Y604763D02*
X1116683Y604441D01*
G01X1116891Y605738D02*
X1116637Y605368D01*
G01X1103602Y588640D02*
X1103856Y589010D01*
G01X1103810Y589937D02*
X1103591Y589618D01*
G01X1112741Y604441D02*
X1112961Y604760D01*
G01X1112741Y604441D02*
X1112731Y604394D01*
G01X1107752Y589984D02*
X1107743Y589937D01*
G01X1108799Y604394D02*
X1108809Y604441D01*
G01X1103810Y589937D02*
X1103820Y589984D01*
G01X1104867Y604441D02*
X1104857Y604394D01*
G01X1099878Y589984D02*
X1099869Y589937D01*
G01X1100925Y604394D02*
X1100935Y604441D01*
G01X1093020Y616519D02*
X1092528Y615932D01*
G01Y616603D02*
X1093020Y617189D01*
G01X1112949Y605738D02*
X1112695Y605368D01*
G01X1099660Y588640D02*
X1099914Y589010D01*
G01X1099647Y589615D02*
X1099869Y589937D01*
G01X1109030Y604763D02*
X1108809Y604441D01*
G01X1109017Y605738D02*
X1108763Y605368D01*
G01X1104867Y604441D02*
X1105087Y604760D01*
G01X1105075Y605738D02*
X1104821Y605368D01*
G01X1101156Y604763D02*
X1100935Y604441D01*
G01X1101143Y605738D02*
X1100889Y605368D01*
G01X1094957Y593646D02*
X1093000Y590693D01*
G01X1088591Y613252D02*
X1089903Y617189D01*
G01X1089411Y614257D02*
X1089083Y613252D01*
G01X1089493Y614592D02*
X1090231Y616854D01*
G01X1074951Y771135D02*
X1075499Y771240D01*
X1076126Y771555D01*
X1076518Y772080D01*
X1076674Y772815D01*
X1076518Y773550D01*
X1076048Y774180D01*
X1075343Y774495D01*
X1074559D01*
X1074089Y774705D01*
X1073698Y775230D01*
X1073541Y775965D01*
X1073776Y776700D01*
X1074324Y777225D01*
X1074951Y777435D01*
X1075578Y777225D01*
X1076126Y776700D01*
X1076361Y775965D01*
X1076204Y775230D01*
X1075813Y774705D01*
X1075343Y774495D01*
X1074559D01*
X1073854Y774180D01*
X1073384Y773550D01*
X1073228Y772815D01*
X1073384Y772080D01*
X1073776Y771555D01*
X1074403Y771240D01*
X1074951Y771135D01*
G01X1154215Y-578426D02*
Y-595749D01*
G01X1154698Y-227685D02*
Y-223300D01*
G01X1148202Y-224274D02*
X1154698Y-227685D01*
G01X1156863Y-224274D02*
X1148202D01*
G01X1148924Y-216966D02*
X1149645Y-216479D01*
G01X1148202Y-217941D02*
X1148924Y-216966D01*
G01Y-218915D02*
X1148202Y-217941D01*
G01X1149645Y-219402D02*
X1148924Y-218915D01*
G01X1151089Y-219890D02*
X1149645Y-219402D01*
G01X1153976Y-219890D02*
X1151089D01*
G01X1155420Y-219402D02*
X1153976Y-219890D01*
G01X1156141Y-218915D02*
X1155420Y-219402D01*
G01X1156863Y-217941D02*
X1156141Y-218915D01*
G01Y-216966D02*
X1156863Y-217941D01*
G01X1155420Y-216479D02*
X1156141Y-216966D01*
G01X1153976Y-215992D02*
X1155420Y-216479D01*
G01X1152532D02*
X1153976Y-215992D01*
G01X1151811Y-217941D02*
X1152532Y-216479D01*
G01Y-219402D02*
X1151811Y-217941D01*
G01X1153976Y-219890D02*
X1152532Y-219402D01*
G01X1156141Y-203812D02*
X1155420Y-204299D01*
G01X1156863Y-202837D02*
X1156141Y-203812D01*
G01X1156863Y-201863D02*
Y-202837D01*
G01X1156141Y-200889D02*
X1156863Y-201863D01*
G01X1154698Y-199914D02*
X1156141Y-200889D01*
G01X1148924Y-193580D02*
X1149645Y-193093D01*
G01X1148202Y-194555D02*
X1148924Y-193580D01*
G01Y-195529D02*
X1148202Y-194555D01*
G01X1149645Y-196016D02*
X1148924Y-195529D01*
G01X1151089Y-196504D02*
X1149645Y-196016D01*
G01X1153976Y-196504D02*
X1151089D01*
G01X1155420Y-196016D02*
X1153976Y-196504D01*
G01X1156141Y-195529D02*
X1155420Y-196016D01*
G01X1156863Y-194555D02*
X1156141Y-195529D01*
G01Y-193580D02*
X1156863Y-194555D01*
G01X1155420Y-193093D02*
X1156141Y-193580D01*
G01X1153976Y-192606D02*
X1155420Y-193093D01*
G01X1152532D02*
X1153976Y-192606D01*
G01X1151811Y-194555D02*
X1152532Y-193093D01*
G01Y-196016D02*
X1151811Y-194555D01*
G01X1153976Y-196504D02*
X1152532Y-196016D01*
G01X1153976Y-199914D02*
X1154698D01*
G01X1153254Y-200401D02*
X1153976Y-199914D01*
G01X1152532Y-200889D02*
X1153254Y-200401D01*
G01X1151811Y-201863D02*
X1152532Y-200889D01*
G01X1151089D02*
X1151811Y-201863D01*
G01X1150367Y-200401D02*
X1151089Y-200889D01*
G01X1149645Y-200401D02*
X1150367D01*
G01X1148924Y-200889D02*
X1149645Y-200401D01*
G01X1148202Y-201863D02*
X1148924Y-200889D01*
G01X1148202Y-202837D02*
Y-201863D01*
G01X1148924Y-203812D02*
X1148202Y-202837D01*
G01X1156141Y-210633D02*
X1156863Y-210145D01*
G01Y-210633D02*
X1156141D01*
G01X1156863Y-210145D02*
Y-210633D01*
G01X1152336Y-167994D02*
X1154304Y-166026D01*
G01X1152336Y-167994D02*
X1154304Y-166026D01*
G01D02*
Y-147522D01*
G01Y-166026D02*
Y-147522D01*
G01X1152237Y-153033D02*
Y-164057D01*
G01X1151811Y-202837D02*
Y-201863D01*
G01X1150072Y-164057D02*
Y-153033D01*
G01X1149088Y-164057D02*
Y-153033D01*
G01X1152237Y-164057D02*
X1150072D01*
G01X1155091Y-147522D02*
X1148081D01*
G01X1163753D02*
G03X1154304I-4725J0D01*
G01X1163753D02*
G03X1154304I-4725J0D01*
G01X1151254Y-152796D02*
X1151300Y-152780D01*
G01X1151145Y-152478D02*
X1151098Y-152494D01*
G01X1150599Y-152446D02*
X1150646Y-152430D01*
G01X1151098Y-152223D02*
X1151145Y-152208D01*
G01X1151316Y-152860D02*
X1151394Y-152812D01*
G01X1151082Y-152144D02*
X1151004Y-152192D01*
G01X1151300Y-152780D02*
X1151347Y-152749D01*
G01X1151098Y-152494D02*
X1151051Y-152526D01*
G01X1151082Y-152414D02*
X1150989Y-152478D01*
G01X1151051Y-152255D02*
X1151098Y-152223D01*
G01X1150724Y-152478D02*
X1150662Y-152526D01*
G01X1151051D02*
X1151020Y-152558D01*
G01X1150646Y-152430D02*
X1150677Y-152399D01*
G01X1151706Y-152558D02*
X1151971Y-152255D01*
G01X1151597Y-152558D02*
X1151971Y-152128D01*
G01X1151394Y-152812D02*
X1151441Y-152749D01*
G01X1151004Y-152192D02*
X1150958Y-152255D01*
G01X1150771Y-152414D02*
X1150724Y-152478D01*
G01X1151347Y-152749D02*
X1151378Y-152701D01*
G01X1151020Y-152303D02*
X1151051Y-152255D01*
G01X1151441Y-152749D02*
X1151472Y-152669D01*
G01X1150958Y-152255D02*
X1150926Y-152335D01*
G01X1151378Y-152701D02*
X1151394Y-152653D01*
G01X1151020Y-152558D02*
X1151004Y-152605D01*
G01Y-152351D02*
X1151020Y-152303D01*
G01X1150786Y-152367D02*
X1150771Y-152414D01*
G01X1150677Y-152399D02*
X1150693Y-152351D01*
G01X1151160Y-152128D02*
X1151082Y-152144D01*
G01X1150989Y-152446D02*
X1151004Y-152351D01*
G01X1150926Y-152335D02*
X1150911Y-152446D01*
G01X1151160Y-152399D02*
X1151082Y-152414D01*
G01X1150662Y-152526D02*
X1150584Y-152542D01*
G01X1151238Y-152876D02*
X1151316Y-152860D01*
G01X1152220Y-152558D02*
Y-152653D01*
G01X1152064D02*
Y-152876D01*
G01Y-152128D02*
Y-152558D01*
G01X1151971Y-152876D02*
Y-152653D01*
G01Y-152255D02*
Y-152558D01*
G01X1151597Y-152653D02*
Y-152558D01*
G01X1151472Y-152669D02*
Y-152590D01*
G01X1151394Y-152653D02*
Y-152605D01*
G01X1151004D02*
Y-152653D01*
G01X1150989Y-152478D02*
Y-152446D01*
G01X1150911D02*
Y-152558D01*
G01X1150786Y-152303D02*
Y-152367D01*
G01X1150693Y-152351D02*
Y-152303D01*
G01X1150303Y-152208D02*
Y-152446D01*
G01Y-152542D02*
Y-152876D01*
G01X1150210D02*
Y-152128D01*
G01X1150911Y-152558D02*
X1150926Y-152669D01*
G01X1151971Y-152128D02*
X1152064D01*
G01X1150210D02*
X1150584D01*
G01X1151223D02*
X1151160D01*
G01X1151145Y-152208D02*
X1151238D01*
G01X1150599D02*
X1150303D01*
G01X1151363Y-152303D02*
X1151441D01*
G01X1151238Y-152399D02*
X1151160D01*
G01X1150303Y-152446D02*
X1150599D01*
G01X1151254Y-152478D02*
X1151145D01*
G01X1150584Y-152542D02*
X1150303D01*
G01X1152064Y-152558D02*
X1152220D01*
G01X1151971D02*
X1151706D01*
G01X1151971Y-152653D02*
X1151597D01*
G01X1152220D02*
X1152064D01*
G01X1151145Y-152796D02*
X1151254D01*
G01X1151160Y-152876D02*
X1151238D01*
G01X1150303D02*
X1150210D01*
G01X1152064D02*
X1151971D01*
G01X1150072Y-153033D02*
X1152237D01*
G01X1151441Y-152303D02*
X1151425Y-152255D01*
G01X1151394Y-152605D02*
X1151378Y-152558D01*
G01X1151004Y-152653D02*
X1151020Y-152701D01*
G01X1150771Y-152255D02*
X1150786Y-152303D01*
G01X1150693D02*
X1150677Y-152255D01*
G01X1151472Y-152590D02*
X1151441Y-152510D01*
G01X1150926Y-152669D02*
X1150958Y-152749D01*
G01X1151238Y-152208D02*
X1151285Y-152223D01*
G01X1150646D02*
X1150599Y-152208D01*
G01X1151300Y-152494D02*
X1151254Y-152478D01*
G01X1151098Y-152780D02*
X1151145Y-152796D01*
G01X1151300Y-152144D02*
X1151223Y-152128D01*
G01X1150584D02*
X1150662Y-152144D01*
G01X1151316Y-152414D02*
X1151238Y-152399D01*
G01X1151082Y-152860D02*
X1151160Y-152876D01*
G01X1151332Y-152255D02*
X1151363Y-152303D01*
G01X1151020Y-152701D02*
X1151051Y-152749D01*
G01X1151425Y-152255D02*
X1151378Y-152192D01*
G01X1150724D02*
X1150771Y-152255D01*
G01X1150958Y-152749D02*
X1151004Y-152812D01*
G01X1151441Y-152510D02*
X1151394Y-152462D01*
G01X1151378Y-152558D02*
X1151347Y-152526D01*
G01X1150677Y-152255D02*
X1150646Y-152223D01*
G01X1150662Y-152144D02*
X1150724Y-152192D01*
G01X1151285Y-152223D02*
X1151332Y-152255D01*
G01X1151347Y-152526D02*
X1151300Y-152494D01*
G01X1151051Y-152749D02*
X1151098Y-152780D01*
G01X1151378Y-152192D02*
X1151300Y-152144D01*
G01X1151394Y-152462D02*
X1151316Y-152414D01*
G01X1151004Y-152812D02*
X1151082Y-152860D01*
G01X1159028Y-151459D02*
Y-186327D01*
G01X1225662Y-153033D02*
Y-164057D01*
G01X1224678D02*
Y-153033D01*
G01X1222513D02*
Y-164057D01*
G01X1221528D02*
Y-153033D01*
G01X1219363D02*
Y-164057D01*
G01X1218379D02*
Y-153033D01*
G01X1216214D02*
Y-164057D01*
G01X1215229D02*
Y-153033D01*
G01X1213064D02*
Y-164057D01*
G01X1212080D02*
Y-153033D01*
G01X1209914D02*
Y-164057D01*
G01X1208930D02*
Y-153033D01*
G01X1206765D02*
Y-164057D01*
G01X1205780D02*
Y-153033D01*
G01X1203615D02*
Y-164057D01*
G01X1202631D02*
Y-153033D01*
G01X1200466D02*
Y-164057D01*
G01X1199481D02*
Y-153033D01*
G01X1197316D02*
Y-164057D01*
G01X1196332D02*
Y-153033D01*
G01X1194166D02*
Y-164057D01*
G01X1193182D02*
Y-153033D01*
G01X1191017D02*
Y-164057D01*
G01X1190032D02*
Y-153033D01*
G01X1187867D02*
Y-164057D01*
G01X1186883D02*
Y-153033D01*
G01X1184717D02*
Y-164057D01*
G01X1183733D02*
Y-153033D01*
G01X1181568D02*
Y-164057D01*
G01X1180584D02*
Y-153033D01*
G01X1178418D02*
Y-164057D01*
G01X1177434D02*
Y-153033D01*
G01X1175269D02*
Y-164057D01*
G01X1174284D02*
Y-153033D01*
G01X1172119D02*
Y-164057D01*
G01X1171135D02*
Y-153033D01*
G01X1168969D02*
Y-164057D01*
G01X1167985Y-153033D02*
Y-164057D01*
G01X1165820D02*
Y-153033D01*
G01X1163753Y-166026D02*
Y-147522D01*
G01D02*
Y-166026D01*
G01X1225662Y-164057D02*
X1227828D01*
G01X1222513D02*
X1224678D01*
G01X1219363D02*
X1221528D01*
G01X1216214D02*
X1218379D01*
G01X1213064D02*
X1215229D01*
G01X1209914D02*
X1212080D01*
G01X1206765D02*
X1208930D01*
G01X1203615D02*
X1205780D01*
G01X1200466D02*
X1202631D01*
G01X1197316D02*
X1199481D01*
G01X1194166D02*
X1196332D01*
G01X1191017D02*
X1193182D01*
G01X1187867D02*
X1190032D01*
G01X1184717D02*
X1186883D01*
G01X1181568D02*
X1183733D01*
G01X1178418D02*
X1180584D01*
G01X1175269D02*
X1177434D01*
G01X1172119D02*
X1174284D01*
G01X1168969D02*
X1171135D01*
G01X1167985D02*
X1165820D01*
G01X1165721Y-167994D02*
X1379973D01*
G01X1165721D02*
X1379973D01*
G01X1163753Y-166026D02*
X1165721Y-167994D01*
G01D02*
X1163753Y-166026D01*
G01X1165820Y-153033D02*
X1167985D01*
G01X1171135D02*
X1168969D01*
G01X1174284D02*
X1172119D01*
G01X1177434D02*
X1175269D01*
G01X1180584D02*
X1178418D01*
G01X1183733D02*
X1181568D01*
G01X1186883D02*
X1184717D01*
G01X1190032D02*
X1187867D01*
G01X1193182D02*
X1191017D01*
G01X1196332D02*
X1194166D01*
G01X1199481D02*
X1197316D01*
G01X1202631D02*
X1200466D01*
G01X1205780D02*
X1203615D01*
G01X1208930D02*
X1206765D01*
G01X1212080D02*
X1209914D01*
G01X1215229D02*
X1213064D01*
G01X1218379D02*
X1216214D01*
G01X1221528D02*
X1219363D01*
G01X1224678D02*
X1222513D01*
G01X1227828D02*
X1225662D01*
G01X1148879Y-104357D02*
X1150519Y-103352D01*
G01X1148551Y-102681D02*
X1149535Y-102011D01*
G01X1150519Y-103352D02*
X1151504Y-102346D01*
G01X1149535Y-102011D02*
X1150847Y-100001D01*
G01X1151504Y-102346D02*
X1152160Y-101006D01*
G01X1155441Y-103016D02*
X1157081D01*
G01Y-104692D02*
X1155441D01*
G01X1152160Y-101006D02*
X1152488Y-100001D01*
G01D02*
X1152816Y-98326D01*
G01X1150847Y-100001D02*
X1151175Y-97991D01*
G01X1157081Y-103016D02*
Y-104692D01*
G01X1155441D02*
Y-103016D01*
G01X1152816Y-98326D02*
Y-95310D01*
G01X1151175Y-97991D02*
Y-95645D01*
G01D02*
X1150847Y-93635D01*
G01X1152816Y-95310D02*
X1152488Y-93635D01*
G01D02*
X1152160Y-92630D01*
G01D02*
X1151504Y-91289D01*
G01X1150847Y-93635D02*
X1149535Y-91624D01*
G01X1151504Y-91289D02*
X1150519Y-90284D01*
G01X1149535Y-91624D02*
X1148551Y-90954D01*
G01X1150519Y-90284D02*
X1148879Y-89279D01*
G01X1196451Y-94305D02*
X1197435Y-93970D01*
G01X1192186Y-95310D02*
X1191202Y-95645D01*
G01Y-94305D02*
X1192186Y-93970D01*
G01X1181687Y-94305D02*
X1182672Y-93970D01*
G01X1177422Y-95310D02*
X1176438Y-95645D01*
G01Y-94305D02*
X1177422Y-93970D01*
G01X1197107Y-95310D02*
X1196451Y-95645D01*
G01X1182343Y-95310D02*
X1181687Y-95645D01*
G01X1161674Y-89949D02*
X1162986Y-89279D01*
G01X1163315Y-90954D02*
X1162330Y-91624D01*
G01X1170532Y-95645D02*
X1162330Y-103016D01*
G01X1159706D02*
X1168892Y-94640D01*
G01X1196451Y-95645D02*
X1196123Y-95980D01*
G01X1195467Y-95310D02*
X1196451Y-94305D01*
G01X1191202Y-95645D02*
X1190546Y-96315D01*
G01Y-94975D02*
X1191202Y-94305D01*
G01X1181687Y-95645D02*
X1181359Y-95980D01*
G01X1180703Y-95310D02*
X1181687Y-94305D01*
G01X1176438Y-95645D02*
X1175782Y-96315D01*
G01Y-94975D02*
X1176438Y-94305D01*
G01X1160362Y-91289D02*
X1161674Y-89949D01*
G01X1196123Y-95980D02*
X1195795Y-96650D01*
G01X1162986Y-89279D02*
X1165283Y-88944D01*
G01X1164955Y-90619D02*
X1163315Y-90954D01*
G01X1171189Y-94640D02*
X1170532Y-95645D01*
G01X1162330Y-91624D02*
X1161674Y-92630D01*
G01X1181359Y-95980D02*
X1181031Y-96650D01*
G01X1168892Y-94640D02*
X1169548Y-93300D01*
G01X1165283Y-88944D02*
X1166595D01*
G01X1166267Y-90619D02*
X1164955D01*
G01X1161674Y-92630D02*
X1160034D01*
G01X1197435Y-93970D02*
X1198748D01*
G01X1192186D02*
X1193498D01*
G01X1188905D02*
X1190546D01*
G01X1182672D02*
X1183984D01*
G01X1177422D02*
X1178734D01*
G01X1174141D02*
X1175782D01*
G01X1178078Y-95310D02*
X1177422D01*
G01X1183328D02*
X1182343D01*
G01X1192842D02*
X1192186D01*
G01X1198091D02*
X1197107D01*
G01X1171517Y-93300D02*
X1171189Y-94640D01*
G01X1201044Y-96650D02*
Y-104692D01*
G01X1199404D02*
Y-96650D01*
G01X1195795D02*
Y-104692D01*
G01X1194154D02*
Y-96650D01*
G01X1200388Y-94975D02*
X1201044Y-96650D01*
G01X1198748Y-93970D02*
X1199732Y-94305D01*
G01X1193498Y-93970D02*
X1194483Y-94305D01*
G01X1183984Y-93970D02*
X1184968Y-94305D01*
G01X1167908Y-90954D02*
X1166267Y-90619D01*
G01X1166595Y-88944D02*
X1168564Y-89279D01*
G01X1162330Y-103016D02*
X1171517D01*
G01Y-104692D02*
X1159706D01*
G01X1175782D02*
X1174141D01*
G01X1181031D02*
X1179391D01*
G01X1186280D02*
X1184640D01*
G01X1190546D02*
X1188905D01*
G01X1195795D02*
X1194154D01*
G01X1201044D02*
X1199404D01*
G01X1160034Y-92630D02*
X1160362Y-91289D01*
G01X1190546Y-96315D02*
Y-104692D01*
G01Y-93970D02*
Y-94975D01*
G01X1188905Y-104692D02*
Y-93970D01*
G01X1186280Y-96650D02*
Y-104692D01*
G01X1184640D02*
Y-96650D01*
G01X1181031D02*
Y-104692D01*
G01X1179391D02*
Y-96650D01*
G01X1175782Y-96315D02*
Y-104692D01*
G01Y-93970D02*
Y-94975D01*
G01X1174141Y-104692D02*
Y-93970D01*
G01X1171517Y-103016D02*
Y-104692D01*
G01Y-92630D02*
Y-93300D01*
G01X1171189Y-91289D02*
X1171517Y-92630D01*
G01X1185624Y-94975D02*
X1186280Y-96650D01*
G01X1199404D02*
X1199076Y-95980D01*
G01X1194154Y-96650D02*
X1193826Y-95980D01*
G01X1184640Y-96650D02*
X1184312Y-95980D01*
G01X1179391Y-96650D02*
X1179063Y-95980D01*
G01X1199732Y-94305D02*
X1200388Y-94975D01*
G01X1199076Y-95980D02*
X1198748Y-95645D01*
G01X1194483Y-94305D02*
X1195467Y-95310D01*
G01X1193826Y-95980D02*
X1193498Y-95645D01*
G01X1184968Y-94305D02*
X1185624Y-94975D01*
G01X1184312Y-95980D02*
X1183984Y-95645D01*
G01X1179719Y-94305D02*
X1180703Y-95310D01*
G01X1179063Y-95980D02*
X1178734Y-95645D01*
G01X1168892Y-91624D02*
X1167908Y-90954D01*
G01X1198748Y-95645D02*
X1198091Y-95310D01*
G01X1193498Y-95645D02*
X1192842Y-95310D01*
G01X1183984Y-95645D02*
X1183328Y-95310D01*
G01X1168564Y-89279D02*
X1169876Y-89949D01*
G01X1178734Y-95645D02*
X1178078Y-95310D01*
G01X1178734Y-93970D02*
X1179719Y-94305D01*
G01X1169548Y-93300D02*
Y-92630D01*
G01X1159706Y-104692D02*
Y-103016D01*
G01X1169548Y-92630D02*
X1168892Y-91624D01*
G01X1169876Y-89949D02*
X1171189Y-91289D01*
G01X1226509Y-18841D02*
X1227711D01*
G01Y-28683D02*
X1226509D01*
G01D02*
Y-18841D01*
G01X1246627Y101967D02*
X1187572D01*
G01Y147341D02*
Y101967D01*
G01X1167213Y300654D02*
X1381465D01*
G01X1167213D02*
X1381465D01*
G01X1153827D02*
X1155795Y302622D01*
G01X1153827Y300654D02*
X1155795Y302622D01*
G01X1148413Y304591D02*
X1150579D01*
G01X1153728D02*
X1151563D01*
G01X1155795Y302622D02*
Y321126D01*
G01Y302622D02*
Y321126D01*
G01X1153728Y315614D02*
Y304591D01*
G01X1151563D02*
Y315614D01*
G01X1150579Y304591D02*
Y315614D01*
G01X1148413D02*
Y304591D01*
G01X1165244Y321126D02*
G03X1155795I-4725J0D01*
G01X1165244D02*
G03X1155795I-4725J0D01*
G01X1151563Y315614D02*
X1153728D01*
G01X1150579D02*
X1148413D01*
G01X1227154D02*
Y304591D01*
G01X1226169D02*
Y315614D01*
G01X1224004D02*
Y304591D01*
G01X1223020D02*
Y315614D01*
G01X1220854D02*
Y304591D01*
G01X1219870D02*
Y315614D01*
G01X1217705D02*
Y304591D01*
G01X1216720D02*
Y315614D01*
G01X1214555D02*
Y304591D01*
G01X1213571D02*
Y315614D01*
G01X1211406D02*
Y304591D01*
G01X1210421D02*
Y315614D01*
G01X1208256D02*
Y304591D01*
G01X1207272D02*
Y315614D01*
G01X1205106D02*
Y304591D01*
G01X1204122D02*
Y315614D01*
G01X1201957D02*
Y304591D01*
G01X1200972D02*
Y315614D01*
G01X1198807D02*
Y304591D01*
G01X1197823D02*
Y315614D01*
G01X1195657D02*
Y304591D01*
G01X1194673D02*
Y315614D01*
G01X1192508D02*
Y304591D01*
G01X1191524D02*
Y315614D01*
G01X1189358D02*
Y304591D01*
G01X1188374D02*
Y315614D01*
G01X1186209D02*
Y304591D01*
G01X1185224D02*
Y315614D01*
G01X1183059D02*
Y304591D01*
G01X1182075D02*
Y315614D01*
G01X1179909D02*
Y304591D01*
G01X1178925D02*
Y315614D01*
G01X1176760D02*
Y304591D01*
G01X1175776D02*
Y315614D01*
G01X1173610D02*
Y304591D01*
G01X1172626D02*
Y315614D01*
G01X1170461D02*
Y304591D01*
G01X1169476Y315614D02*
Y304591D01*
G01X1167311D02*
Y315614D01*
G01X1165244Y302622D02*
Y321126D01*
G01D02*
Y302622D01*
G01X1227154Y304591D02*
X1229319D01*
G01X1224004D02*
X1226169D01*
G01X1220854D02*
X1223020D01*
G01X1217705D02*
X1219870D01*
G01X1214555D02*
X1216720D01*
G01X1211406D02*
X1213571D01*
G01X1208256D02*
X1210421D01*
G01X1205106D02*
X1207272D01*
G01X1201957D02*
X1204122D01*
G01X1198807D02*
X1200972D01*
G01X1195657D02*
X1197823D01*
G01X1192508D02*
X1194673D01*
G01X1189358D02*
X1191524D01*
G01X1186209D02*
X1188374D01*
G01X1183059D02*
X1185224D01*
G01X1179909D02*
X1182075D01*
G01X1176760D02*
X1178925D01*
G01X1173610D02*
X1175776D01*
G01X1170461D02*
X1172626D01*
G01X1169476D02*
X1167311D01*
G01X1167213Y300654D02*
X1165244Y302622D01*
G01D02*
X1167213Y300654D01*
G01X1167311Y315614D02*
X1169476D01*
G01X1172626D02*
X1170461D01*
G01X1175776D02*
X1173610D01*
G01X1178925D02*
X1176760D01*
G01X1182075D02*
X1179909D01*
G01X1185224D02*
X1183059D01*
G01X1188374D02*
X1186209D01*
G01X1191524D02*
X1189358D01*
G01X1194673D02*
X1192508D01*
G01X1197823D02*
X1195657D01*
G01X1200972D02*
X1198807D01*
G01X1204122D02*
X1201957D01*
G01X1207272D02*
X1205106D01*
G01X1210421D02*
X1208256D01*
G01X1213571D02*
X1211406D01*
G01X1216720D02*
X1214555D01*
G01X1219870D02*
X1217705D01*
G01X1223020D02*
X1220854D01*
G01X1226169D02*
X1224004D01*
G01X1229319D02*
X1227154D01*
G01X1223935Y351587D02*
X1220215Y349687D01*
G01X1218354D02*
X1223404Y352401D01*
G01X1227921Y354844D02*
X1227124Y354029D01*
G01X1223935Y347787D02*
X1223404Y346973D01*
G01X1227124Y354029D02*
X1226593Y352944D01*
G01D02*
X1226327Y352130D01*
G01D02*
X1226061Y350772D01*
G01X1227656Y352130D02*
X1227390Y350501D01*
G01D02*
Y348601D01*
G01X1226061Y350772D02*
Y348330D01*
G01X1216228Y355929D02*
Y343173D01*
G01X1214634Y350772D02*
Y355929D01*
G01Y343173D02*
Y349144D01*
G01X1227390Y348601D02*
X1227656Y346973D01*
G01X1226061Y348330D02*
X1226327Y346973D01*
G01D02*
X1226593Y346159D01*
G01X1214634Y355929D02*
X1216228D01*
G01X1205598D02*
X1207193D01*
G01Y350772D02*
X1214634D01*
G01Y349144D02*
X1207193D01*
G01Y343173D02*
X1205598D01*
G01X1216228D02*
X1214634D01*
G01X1207193Y349144D02*
Y343173D01*
G01Y355929D02*
Y350772D01*
G01X1205598Y343173D02*
Y355929D01*
G01X1226593Y346159D02*
X1227124Y345073D01*
G01X1223404Y352401D02*
X1223935Y351587D01*
G01X1227124Y345073D02*
X1227921Y344259D01*
G01X1223404Y346973D02*
X1218354Y349687D01*
G01X1220215D02*
X1223935Y347787D01*
G01X1223412Y410164D02*
X1218336Y407572D01*
G01X1215798D02*
X1222687Y411275D01*
G01X1210721Y416089D02*
X1212897D01*
G01X1198394D02*
X1200569D01*
G01X1228488Y413127D02*
X1226312Y410534D01*
G01Y413497D02*
X1228488Y416089D01*
G01X1223412Y404980D02*
X1222687Y403869D01*
G01X1200569Y409053D02*
X1210721D01*
G01Y406832D02*
X1200569D01*
G01Y398685D02*
X1198394D01*
G01X1212897D02*
X1210721D01*
G01X1222687Y403869D02*
X1215798Y407572D01*
G01X1218336D02*
X1223412Y404980D01*
G01X1226312Y410534D02*
Y413497D01*
G01X1212897Y416089D02*
Y398685D01*
G01X1222687Y411275D02*
X1223412Y410164D01*
G01X1210721Y409053D02*
Y416089D01*
G01Y398685D02*
Y406832D01*
G01X1200569D02*
Y398685D01*
G01Y416089D02*
Y409053D01*
G01X1198394Y398685D02*
Y416089D01*
G01X1155520Y502524D02*
Y497012D01*
G01X1152370Y502524D02*
Y497012D01*
G01X1159457D02*
X1179142D01*
G01Y502524D02*
Y497012D01*
G01X1175992Y502524D02*
Y497012D01*
G01X1162606Y502524D02*
Y497012D01*
G01X1159457Y502524D02*
Y497012D01*
G01X1221661Y484217D02*
X1223138D01*
G01Y479442D02*
X1230028D01*
G01Y477934D02*
X1223138D01*
G01Y472406D02*
X1221661D01*
G01X1223138Y477934D02*
Y472406D01*
G01Y484217D02*
Y479442D01*
G01X1221661Y472406D02*
Y484217D01*
G01X1206701Y497012D02*
X1226386D01*
G01X1183079D02*
X1202764D01*
G01X1226386Y502524D02*
Y497012D01*
G01X1223236Y502524D02*
Y497012D01*
G01X1209850Y502524D02*
Y497012D01*
G01X1206701Y502524D02*
Y497012D01*
G01X1202764Y502524D02*
Y497012D01*
G01X1199614Y502524D02*
Y497012D01*
G01X1186228Y502524D02*
Y497012D01*
G01X1183079Y502524D02*
Y497012D01*
G01X1150823Y510197D02*
X1150822Y510571D01*
G01X1150825Y509887D02*
X1150823Y510197D01*
G01X1150829Y509680D02*
X1150825Y509887D01*
G01X1150833Y509606D02*
X1150829Y509680D01*
G01X1152342Y524181D02*
X1152343Y523807D01*
G01X1152340Y524491D02*
X1152342Y524181D01*
G01X1152337Y524698D02*
X1152340Y524491D01*
G01X1152332Y524772D02*
X1152337Y524698D01*
G01X1150565Y526485D02*
X1150559Y526538D01*
G01X1150571Y526353D02*
X1150565Y526485D01*
G01X1150577Y526147D02*
X1150571Y526353D01*
G01X1152600Y507893D02*
X1152606Y507840D01*
G01X1152594Y508025D02*
X1152600Y507893D01*
G01X1152588Y508231D02*
X1152594Y508025D01*
G01X1154507Y526485D02*
X1154501Y526538D01*
G01X1154513Y526353D02*
X1154507Y526485D01*
G01X1154519Y526147D02*
X1154513Y526353D01*
G01X1156532Y507893D02*
X1156539Y507840D01*
G01X1156526Y508025D02*
X1156532Y507893D01*
G01X1156521Y508231D02*
X1156526Y508025D01*
G01X1158439Y526485D02*
X1158433Y526538D01*
G01X1158445Y526353D02*
X1158439Y526485D01*
G01X1158451Y526147D02*
X1158445Y526353D01*
G01X1150564Y525511D02*
X1150559Y525553D01*
G01X1150568Y525413D02*
X1150564Y525511D01*
G01X1150572Y525261D02*
X1150568Y525413D01*
G01X1152602Y508867D02*
X1152606Y508825D01*
G01X1152597Y508965D02*
X1152602Y508867D01*
G01X1152593Y509117D02*
X1152597Y508965D01*
G01X1154505Y525511D02*
X1154501Y525553D01*
G01X1154510Y525413D02*
X1154505Y525511D01*
G01X1154514Y525261D02*
X1154510Y525413D01*
G01X1156534Y508867D02*
X1156539Y508825D01*
G01X1156530Y508965D02*
X1156534Y508867D01*
G01X1156525Y509117D02*
X1156530Y508965D01*
G01X1158438Y525511D02*
X1158433Y525553D01*
G01X1158442Y525413D02*
X1158438Y525511D01*
G01X1158446Y525261D02*
X1158442Y525413D01*
G01X1154762Y509645D02*
X1154767Y509615D01*
G01X1154758Y509841D02*
X1154762Y509645D01*
G01X1154755Y510169D02*
X1154758Y509841D01*
G01X1154754Y510571D02*
X1154755Y510169D01*
G01X1156277Y524733D02*
X1156273Y524763D01*
G01X1156281Y524537D02*
X1156277Y524733D01*
G01X1156284Y524209D02*
X1156281Y524537D01*
G01X1156285Y523807D02*
X1156284Y524209D01*
G01X1150825Y508770D02*
X1150833Y508621D01*
G01X1150818Y509184D02*
X1150825Y508770D01*
G01X1150813Y509804D02*
X1150818Y509184D01*
G01X1150811Y510552D02*
X1150813Y509804D01*
G01X1152341Y525608D02*
X1152332Y525757D01*
G01X1152348Y525193D02*
X1152341Y525608D01*
G01X1152353Y524573D02*
X1152348Y525193D01*
G01X1152354Y523826D02*
X1152353Y524573D01*
G01X1158699Y508770D02*
X1158707Y508621D01*
G01X1158692Y509184D02*
X1158699Y508770D01*
G01X1158687Y509804D02*
X1158692Y509184D01*
G01X1158685Y510552D02*
X1158687Y509804D01*
G01X1150829Y524698D02*
X1150833Y524772D01*
G01X1150825Y524491D02*
X1150829Y524698D01*
G01X1150823Y524181D02*
X1150825Y524491D01*
G01X1150822Y523807D02*
X1150823Y524181D01*
G01X1152337Y509680D02*
X1152332Y509606D01*
G01X1152340Y509887D02*
X1152337Y509680D01*
G01X1152342Y510197D02*
X1152340Y509887D01*
G01X1152343Y510571D02*
X1152342Y510197D01*
G01X1158703Y524698D02*
X1158707Y524772D01*
G01X1158699Y524491D02*
X1158703Y524698D01*
G01X1158697Y524181D02*
X1158699Y524491D01*
G01X1158696Y523807D02*
X1158697Y524181D01*
G01X1150813Y524573D02*
X1150811Y523826D01*
G01X1150818Y525193D02*
X1150813Y524573D01*
G01X1150825Y525608D02*
X1150818Y525193D01*
G01X1150833Y525757D02*
X1150825Y525608D01*
G01X1152353Y509804D02*
X1152354Y510552D01*
G01X1152348Y509184D02*
X1152353Y509804D01*
G01X1152341Y508770D02*
X1152348Y509184D01*
G01X1152332Y508621D02*
X1152341Y508770D01*
G01X1158687Y524573D02*
X1158685Y523826D01*
G01X1158692Y525193D02*
X1158687Y524573D01*
G01X1158699Y525608D02*
X1158692Y525193D01*
G01X1158707Y525757D02*
X1158699Y525608D01*
G01X1150833Y509607D02*
Y509606D01*
G01X1150834Y509610D02*
X1150833Y509607D01*
G01X1150835Y509617D02*
X1150834Y509610D01*
G01X1152332Y524771D02*
Y524772D01*
G01X1152331Y524768D02*
X1152332Y524771D01*
G01X1152331Y524761D02*
Y524768D01*
G01X1158707Y509607D02*
Y509606D01*
G01X1158708Y509610D02*
X1158707Y509607D01*
G01X1158709Y509617D02*
X1158708Y509610D01*
G01X1150568Y508965D02*
X1150572Y509117D01*
G01X1150564Y508867D02*
X1150568Y508965D01*
G01X1150559Y508825D02*
X1150564Y508867D01*
G01X1152597Y525413D02*
X1152593Y525261D01*
G01X1152602Y525511D02*
X1152597Y525413D01*
G01X1152606Y525553D02*
X1152602Y525511D01*
G01X1154500Y508965D02*
X1154505Y509117D01*
G01X1154496Y508867D02*
X1154500Y508965D01*
G01X1154491Y508825D02*
X1154496Y508867D01*
G01X1156539Y525413D02*
X1156535Y525261D01*
G01X1156543Y525511D02*
X1156539Y525413D01*
G01X1156548Y525553D02*
X1156543Y525511D01*
G01X1158442Y508965D02*
X1158446Y509117D01*
G01X1158438Y508867D02*
X1158442Y508965D01*
G01X1158433Y508825D02*
X1158438Y508867D01*
G01X1152594Y526353D02*
X1152588Y526147D01*
G01X1152600Y526485D02*
X1152594Y526353D01*
G01X1152606Y526538D02*
X1152600Y526485D01*
G01X1150571Y508025D02*
X1150577Y508231D01*
G01X1150565Y507893D02*
X1150571Y508025D01*
G01X1150559Y507840D02*
X1150565Y507893D01*
G01X1156536Y526353D02*
X1156530Y526147D01*
G01X1156542Y526485D02*
X1156536Y526353D01*
G01X1156548Y526538D02*
X1156542Y526485D01*
G01X1154504Y508025D02*
X1154509Y508231D01*
G01X1154498Y507893D02*
X1154504Y508025D01*
G01X1154491Y507840D02*
X1154498Y507893D01*
G01X1158445Y508025D02*
X1158451Y508231D01*
G01X1158439Y507893D02*
X1158445Y508025D01*
G01X1158433Y507840D02*
X1158439Y507893D01*
G01X1154765Y524209D02*
X1154764Y523807D01*
G01X1154767Y524537D02*
X1154765Y524209D01*
G01X1154772Y524733D02*
X1154767Y524537D01*
G01X1154776Y524763D02*
X1154772Y524733D01*
G01X1156275Y510169D02*
X1156276Y510571D01*
G01X1156272Y509841D02*
X1156275Y510169D01*
G01X1156268Y509645D02*
X1156272Y509841D01*
G01X1156263Y509615D02*
X1156268Y509645D01*
G01X1152331Y525754D02*
Y525751D01*
G01X1152332Y525756D02*
X1152331Y525754D01*
G01X1152332Y525757D02*
Y525756D01*
G01X1150834Y508624D02*
X1150835Y508627D01*
G01X1150834Y508622D02*
Y508624D01*
G01X1150833Y508621D02*
X1150834Y508622D01*
G01X1158708Y508624D02*
X1158709Y508627D01*
G01X1158708Y508622D02*
Y508624D01*
G01X1158707Y508621D02*
X1158708Y508622D01*
G01X1158697Y510197D02*
X1158696Y510571D01*
G01X1158699Y509887D02*
X1158697Y510197D01*
G01X1158703Y509680D02*
X1158699Y509887D01*
G01X1158707Y509606D02*
X1158703Y509680D01*
G01X1148744Y520142D02*
X1149122Y520314D01*
G01X1148376Y519965D02*
X1148744Y520142D01*
G01X1148020Y519783D02*
X1148376Y519965D01*
G01X1152332Y508622D02*
Y508621D01*
G01X1152331Y508624D02*
X1152332Y508622D01*
G01X1152331Y508627D02*
Y508624D01*
G01X1150834Y525756D02*
X1150833Y525757D01*
G01X1150834Y525754D02*
Y525756D01*
G01X1150835Y525751D02*
X1150834Y525754D01*
G01X1158708Y525756D02*
X1158707Y525757D01*
G01X1158708Y525754D02*
Y525756D01*
G01X1158709Y525751D02*
X1158708Y525754D01*
G01X1152331Y509610D02*
Y509617D01*
G01X1152332Y509607D02*
X1152331Y509610D01*
G01X1152332Y509606D02*
Y509607D01*
G01X1150834Y524768D02*
X1150835Y524761D01*
G01X1150833Y524771D02*
X1150834Y524768D01*
G01X1150833Y524772D02*
Y524771D01*
G01X1158708Y524768D02*
X1158709Y524761D01*
G01X1158707Y524771D02*
X1158708Y524768D01*
G01X1158707Y524772D02*
Y524771D01*
G01X1148744Y514236D02*
X1149122Y514064D01*
G01X1148376Y514412D02*
X1148744Y514236D01*
G01X1148020Y514595D02*
X1148376Y514412D01*
G01X1152621Y507839D02*
X1152606Y507840D01*
G01X1152636Y507839D02*
X1152621D01*
G01X1152651D02*
X1152636D01*
G01X1156554D02*
X1156539Y507840D01*
G01X1156569Y507839D02*
X1156554D01*
G01X1156584D02*
X1156569D01*
G01X1152621Y508824D02*
X1152606Y508825D01*
G01X1152636Y508823D02*
X1152621Y508824D01*
G01X1152651Y508823D02*
X1152636D01*
G01X1156569D02*
X1156584D01*
G01X1156554Y508824D02*
X1156569Y508823D01*
G01X1156539Y508825D02*
X1156554Y508824D01*
G01X1158403Y508823D02*
X1158388D01*
G01X1158418Y508824D02*
X1158403Y508823D01*
G01X1158433Y508825D02*
X1158418Y508824D01*
G01X1150529Y508823D02*
X1150514D01*
G01X1150544Y508824D02*
X1150529Y508823D01*
G01X1150559Y508825D02*
X1150544Y508824D01*
G01X1156578Y525555D02*
X1156593D01*
G01X1156563Y525554D02*
X1156578Y525555D01*
G01X1156548Y525553D02*
X1156563Y525554D01*
G01X1152636Y525555D02*
X1152651D01*
G01X1152621Y525554D02*
X1152636Y525555D01*
G01X1152606Y525553D02*
X1152621Y525554D01*
G01X1154461Y507839D02*
X1154446D01*
G01X1154476D02*
X1154461D01*
G01X1154491Y507840D02*
X1154476Y507839D01*
G01X1156578Y526539D02*
X1156593D01*
G01X1156563D02*
X1156578D01*
G01X1156548Y526538D02*
X1156563Y526539D01*
G01X1150544D02*
X1150559Y526538D01*
G01X1150529Y526539D02*
X1150544D01*
G01X1150514D02*
X1150529D01*
G01X1154486D02*
X1154501Y526538D01*
G01X1154471Y526539D02*
X1154486D01*
G01X1154456D02*
X1154471D01*
G01X1158418D02*
X1158433Y526538D01*
G01X1158403Y526539D02*
X1158418D01*
G01X1158388D02*
X1158403D01*
G01X1150544Y525554D02*
X1150559Y525553D01*
G01X1150529Y525555D02*
X1150544Y525554D01*
G01X1150514Y525555D02*
X1150529D01*
G01X1154486Y525554D02*
X1154501Y525553D01*
G01X1154471Y525555D02*
X1154486Y525554D01*
G01X1154456Y525555D02*
X1154471D01*
G01X1158418Y525554D02*
X1158433Y525553D01*
G01X1158403Y525555D02*
X1158418Y525554D01*
G01X1158388Y525555D02*
X1158403D01*
G01X1152764Y530476D02*
X1150402D01*
G01X1156701D02*
X1154339D01*
G01X1160638D02*
X1158276D01*
G01X1152252Y529492D02*
X1150913D01*
G01X1160126D02*
X1158787D01*
G01X1158630Y529394D02*
X1160283D01*
G01X1150756D02*
X1152409D01*
G01X1152764Y529295D02*
X1150402D01*
G01X1156701D02*
X1154339D01*
G01X1160638D02*
X1158276D01*
G01X1152409Y528902D02*
X1150756D01*
G01X1160283D02*
X1158630D01*
G01X1153000Y528035D02*
X1150165D01*
G01X1156937D02*
X1154102D01*
G01X1160874D02*
X1158039D01*
G01X1152409Y527130D02*
X1150756D01*
G01X1160283D02*
X1158630D01*
G01Y526638D02*
X1160283D01*
G01X1150756D02*
X1152409D01*
G01X1153000Y526539D02*
X1150165D01*
G01X1156937D02*
X1154102D01*
G01X1160874D02*
X1158039D01*
G01Y526382D02*
X1158630D01*
G01X1156346D02*
X1156937D01*
G01X1154102D02*
X1154693D01*
G01X1152409D02*
X1153000D01*
G01X1150165D02*
X1150756D01*
G01X1158451Y526147D02*
X1160462D01*
G01X1154519D02*
X1156530D01*
G01X1150577D02*
X1152588D01*
G01X1152332Y525757D02*
X1150833D01*
G01X1156274D02*
X1154775D01*
G01X1160206D02*
X1158707D01*
G01X1158720Y525738D02*
X1160193D01*
G01X1154788D02*
X1156261D01*
G01X1150846D02*
X1152319D01*
G01X1150756Y525713D02*
X1150165D01*
G01X1153000D02*
X1152409D01*
G01X1154693D02*
X1154102D01*
G01X1156937D02*
X1156346D01*
G01X1158630D02*
X1158039D01*
G01Y525555D02*
X1160874D01*
G01X1154102D02*
X1156937D01*
G01X1150165D02*
X1153000D01*
G01X1156346Y525457D02*
X1154693D01*
G01X1152065Y525368D02*
X1151100D01*
G01X1156007D02*
X1155042D01*
G01X1159939D02*
X1158974D01*
G01X1154102Y525358D02*
X1154417D01*
G01X1150480D02*
X1150165D01*
G01X1153000D02*
X1152685D01*
G01X1156937D02*
X1156622D01*
G01X1158354D02*
X1158039D01*
G01X1152593Y525261D02*
X1150572D01*
G01X1156535D02*
X1154514D01*
G01X1160467D02*
X1158446D01*
G01X1154693Y524965D02*
X1156346D01*
G01X1152332Y524772D02*
X1150833D01*
G01X1156274D02*
X1154775D01*
G01X1160206D02*
X1158707D01*
G01X1152331Y524763D02*
X1150834D01*
G01X1156273D02*
X1154776D01*
G01X1160205D02*
X1158708D01*
G01X1158928Y524441D02*
X1159985D01*
G01X1154996D02*
X1156053D01*
G01X1151054D02*
X1152111D01*
G01X1158276Y524394D02*
X1160638D01*
G01X1154339D02*
X1156701D01*
G01X1150402D02*
X1152764D01*
G01X1158039Y523862D02*
X1158354D01*
G01X1156622D02*
X1156937D01*
G01X1152685D02*
X1153000D01*
G01X1154102D02*
X1154417D01*
G01X1150165D02*
X1150480D01*
G01X1158685Y523826D02*
X1160228D01*
G01X1154753D02*
X1156296D01*
G01X1150811D02*
X1152354D01*
G01X1158696Y523807D02*
X1160217D01*
G01X1154764D02*
X1156285D01*
G01X1150822D02*
X1152343D01*
G01X1154693Y523193D02*
X1156346D01*
G01Y522701D02*
X1154693D01*
G01X1156189Y522602D02*
X1154850D01*
G01Y521618D02*
X1156189D01*
G01X1152380Y520999D02*
X1150785D01*
G01X1156322D02*
X1154727D01*
G01X1160254D02*
X1158659D01*
G01X1152685Y520890D02*
X1150480D01*
G01X1156622D02*
X1154417D01*
G01X1160559D02*
X1158354D01*
G01X1432617Y520732D02*
X1148422D01*
G01X1152452Y520239D02*
X1150713D01*
G01X1156394D02*
X1154655D01*
G01X1160326D02*
X1158587D01*
G01X1158661Y520037D02*
X1160252D01*
G01X1154729D02*
X1156320D01*
G01X1150787D02*
X1152378D01*
G01X1158609Y520013D02*
X1160305D01*
G01X1154676D02*
X1156372D01*
G01X1150735D02*
X1152431D01*
G01X1152438Y519945D02*
X1150728D01*
G01X1156379D02*
X1154669D01*
G01X1160312D02*
X1158602D01*
G01X1158583Y519353D02*
X1160331D01*
G01X1154650D02*
X1156399D01*
G01X1150708D02*
X1152457D01*
G01X1152428Y519051D02*
X1150737D01*
G01X1156370D02*
X1154679D01*
G01X1160302D02*
X1158611D01*
G01X1152438Y518961D02*
X1150728D01*
G01X1156379D02*
X1154669D01*
G01X1160312D02*
X1158602D01*
G01X1158354Y518635D02*
X1160559D01*
G01X1154417D02*
X1156622D01*
G01X1150480D02*
X1152685D01*
G01X1158354Y518468D02*
X1160559D01*
G01X1154417D02*
X1156622D01*
G01X1150480D02*
X1152685D01*
G01Y515910D02*
X1150480D01*
G01X1156622D02*
X1154417D01*
G01X1160559D02*
X1158354D01*
G01X1152685Y515743D02*
X1150480D01*
G01X1156622D02*
X1154417D01*
G01X1160559D02*
X1158354D01*
G01X1158602Y515417D02*
X1160312D01*
G01X1154660D02*
X1156370D01*
G01X1150728D02*
X1152438D01*
G01X1158611Y515327D02*
X1160302D01*
G01X1154669D02*
X1156361D01*
G01X1150737D02*
X1152428D01*
G01X1152457Y515025D02*
X1150708D01*
G01X1156389D02*
X1154641D01*
G01X1160331D02*
X1158583D01*
G01X1158602Y514433D02*
X1160312D01*
G01X1154660D02*
X1156370D01*
G01X1150728D02*
X1152438D01*
G01X1152431Y514365D02*
X1150735D01*
G01X1156363D02*
X1154667D01*
G01X1160305D02*
X1158609D01*
G01X1152378Y514341D02*
X1150787D01*
G01X1156310D02*
X1154720D01*
G01X1160252D02*
X1158661D01*
G01X1158587Y514139D02*
X1160326D01*
G01X1154646D02*
X1156384D01*
G01X1150713D02*
X1152452D01*
G01X1148422Y513646D02*
X1432617D01*
G01X1158354Y513488D02*
X1160559D01*
G01X1154417D02*
X1156622D01*
G01X1150480D02*
X1152685D01*
G01X1158659Y513379D02*
X1160254D01*
G01X1154717D02*
X1156313D01*
G01X1150785D02*
X1152380D01*
G01X1156189Y512760D02*
X1154850D01*
G01X1156189Y511776D02*
X1154850D01*
G01X1154693Y511677D02*
X1156346D01*
G01Y511185D02*
X1154693D01*
G01X1152343Y510571D02*
X1150822D01*
G01X1156276D02*
X1154754D01*
G01X1160217D02*
X1158696D01*
G01X1152354Y510552D02*
X1150811D01*
G01X1156287D02*
X1154743D01*
G01X1160228D02*
X1158685D01*
G01X1150480Y510516D02*
X1150165D01*
G01X1153000D02*
X1152685D01*
G01X1154417D02*
X1154102D01*
G01X1156937D02*
X1156622D01*
G01X1158354D02*
X1158039D01*
G01X1152764Y509984D02*
X1150402D01*
G01X1156701D02*
X1154339D01*
G01X1160638D02*
X1158276D01*
G01X1152111Y509937D02*
X1151054D01*
G01X1156043D02*
X1154987D01*
G01X1159985D02*
X1158928D01*
G01X1158708Y509615D02*
X1160205D01*
G01X1154767D02*
X1156263D01*
G01X1150834D02*
X1152331D01*
G01X1158707Y509606D02*
X1160206D01*
G01X1154765D02*
X1156265D01*
G01X1150833D02*
X1152332D01*
G01X1156346Y509413D02*
X1154693D01*
G01X1158446Y509117D02*
X1160467D01*
G01X1154505D02*
X1156525D01*
G01X1150572D02*
X1152593D01*
G01X1156622Y509020D02*
X1156937D01*
G01X1150480D02*
X1150165D01*
G01X1154417D02*
X1154102D01*
G01X1153000D02*
X1152685D01*
G01X1158354D02*
X1158039D01*
G01X1158974Y509010D02*
X1159939D01*
G01X1155032D02*
X1155998D01*
G01X1151100D02*
X1152065D01*
G01X1154693Y508921D02*
X1156346D01*
G01X1158039Y508823D02*
X1160874D01*
G01X1154102D02*
X1156937D01*
G01X1150165D02*
X1153000D01*
G01X1158039Y508665D02*
X1158630D01*
G01X1156346D02*
X1156937D01*
G01X1154102D02*
X1154693D01*
G01X1152409D02*
X1153000D01*
G01X1150165D02*
X1150756D01*
G01X1152319Y508640D02*
X1150846D01*
G01X1156252D02*
X1154779D01*
G01X1160193D02*
X1158720D01*
G01X1158707Y508621D02*
X1160206D01*
G01X1154765D02*
X1156265D01*
G01X1150833D02*
X1152332D01*
G01X1152588Y508231D02*
X1150577D01*
G01X1156521D02*
X1154509D01*
G01X1160462D02*
X1158451D01*
G01X1150756Y507996D02*
X1150165D01*
G01X1153000D02*
X1152409D01*
G01X1154693D02*
X1154102D01*
G01X1156937D02*
X1156346D01*
G01X1158630D02*
X1158039D01*
G01X1153000Y507839D02*
X1150165D01*
G01X1156937D02*
X1154102D01*
G01X1160874D02*
X1158039D01*
G01X1152409Y507740D02*
X1150756D01*
G01X1160283D02*
X1158630D01*
G01Y507248D02*
X1160283D01*
G01X1150756D02*
X1152409D01*
G01X1158039Y506343D02*
X1160874D01*
G01X1154102D02*
X1156937D01*
G01X1150165D02*
X1153000D01*
G01X1158630Y505476D02*
X1160283D01*
G01X1150756D02*
X1152409D01*
G01X1158276Y505083D02*
X1160638D01*
G01X1150402D02*
X1152764D01*
G01X1156701D02*
X1154339D01*
G01X1152409Y504984D02*
X1150756D01*
G01X1160283D02*
X1158630D01*
G01X1152252Y504886D02*
X1150913D01*
G01X1160126D02*
X1158787D01*
G01X1158276Y503902D02*
X1160638D01*
G01X1154339D02*
X1156701D01*
G01X1150402D02*
X1152764D01*
G01X1158974Y525368D02*
X1158720Y525738D01*
G01X1158709Y524760D02*
X1158928Y524441D01*
G01X1155042Y525368D02*
X1154788Y525738D01*
G01X1154996Y524441D02*
X1154775Y524763D01*
G01X1151100Y525368D02*
X1150846Y525738D01*
G01X1150835Y524760D02*
X1151054Y524441D01*
G01X1156043Y509937D02*
X1156265Y509615D01*
G01X1155998Y509010D02*
X1156252Y508640D01*
G01X1152331Y509618D02*
X1152111Y509937D01*
G01X1152065Y509010D02*
X1152319Y508640D01*
G01X1158938Y524394D02*
X1158928Y524441D01*
G01X1154996D02*
X1155006Y524394D01*
G01X1156043Y509937D02*
X1156034Y509984D01*
G01X1151064Y524394D02*
X1151054Y524441D01*
G01X1152101Y509984D02*
X1152111Y509937D01*
G01X1158720Y508640D02*
X1158974Y509010D01*
G01X1158928Y509937D02*
X1158709Y509618D01*
G01X1154779Y508640D02*
X1155032Y509010D01*
G01X1154765Y509615D02*
X1154987Y509937D01*
G01X1150846Y508640D02*
X1151100Y509010D01*
G01X1151054Y509937D02*
X1150835Y509618D01*
G01X1156274Y524763D02*
X1156053Y524441D01*
G01X1156261Y525738D02*
X1156007Y525368D01*
G01X1152111Y524441D02*
X1152331Y524760D01*
G01X1152319Y525738D02*
X1152065Y525368D01*
G01X1158928Y509937D02*
X1158938Y509984D01*
G01X1154996D02*
X1154987Y509937D01*
G01X1156043Y524394D02*
X1156053Y524441D01*
G01X1151054Y509937D02*
X1151064Y509984D01*
G01X1152111Y524441D02*
X1152101Y524394D01*
G01X1158611Y519051D02*
X1158661Y520037D01*
G01X1158659Y520999D02*
X1158609Y520013D01*
G01X1156313Y513379D02*
X1156363Y514365D01*
G01X1156361Y515327D02*
X1156310Y514341D01*
G01X1154679Y519051D02*
X1154729Y520037D01*
G01X1154727Y520999D02*
X1154676Y520013D01*
G01X1152380Y513379D02*
X1152431Y514365D01*
G01X1152428Y515327D02*
X1152378Y514341D01*
G01X1150737Y519051D02*
X1150787Y520037D01*
G01X1150785Y520999D02*
X1150735Y520013D01*
G01X1158451Y508231D02*
X1158587Y514139D01*
G01X1158583Y515025D02*
X1158446Y509117D01*
G01X1156399Y519353D02*
X1156535Y525261D01*
G01X1156530Y526147D02*
X1156394Y520239D01*
G01X1154509Y508231D02*
X1154646Y514139D01*
G01X1154641Y515025D02*
X1154505Y509117D01*
G01X1152457Y519353D02*
X1152593Y525261D01*
G01X1152588Y526147D02*
X1152452Y520239D01*
G01X1150577Y508231D02*
X1150713Y514139D01*
G01X1150708Y515025D02*
X1150572Y509117D01*
G01X1158961Y524394D02*
X1158974Y525368D01*
G01X1156011Y509984D02*
X1155998Y509010D01*
G01X1155029Y524394D02*
X1155042Y525368D01*
G01X1152078Y509984D02*
X1152065Y509010D01*
G01X1151087Y524394D02*
X1151100Y525368D01*
G01X1158787Y504965D02*
Y503902D01*
G01Y530476D02*
Y529413D01*
G01X1158709Y509618D02*
Y508627D01*
G01Y525751D02*
Y524760D01*
G01X1158630Y525555D02*
Y530396D01*
G01Y503982D02*
Y508823D01*
G01X1158433Y507840D02*
Y508825D01*
G01Y525553D02*
Y526538D01*
G01X1158354Y526539D02*
Y507839D01*
G01X1158276Y509984D02*
Y503902D01*
G01Y530476D02*
Y524394D01*
G01X1158079Y508823D02*
Y507839D01*
G01Y526539D02*
Y525555D01*
G01X1158074Y526539D02*
Y525555D01*
G01X1158039Y510516D02*
Y506343D01*
G01Y528035D02*
Y523862D01*
G01X1156937D02*
Y528035D01*
G01Y506343D02*
Y510516D01*
G01X1156902Y526539D02*
Y525555D01*
G01X1156898Y508823D02*
Y507839D01*
G01X1156893Y508823D02*
Y507839D01*
G01X1156701Y509984D02*
Y503902D01*
G01Y530476D02*
Y524394D01*
G01X1156622Y507839D02*
Y526539D01*
G01X1156548Y526538D02*
Y525553D01*
G01X1156539Y508825D02*
Y507840D01*
G01X1156346Y521698D02*
Y526539D01*
G01Y507839D02*
Y512680D01*
G01X1156272Y524760D02*
Y525751D01*
G01X1156263Y508627D02*
Y509618D01*
G01X1156189Y512760D02*
Y511696D01*
G01Y522681D02*
Y521618D01*
G01X1155913D02*
Y522602D01*
G01Y512760D02*
Y511776D01*
G01X1155126Y521618D02*
Y522602D01*
G01Y512760D02*
Y511776D01*
G01X1154850Y512760D02*
Y511696D01*
G01Y522682D02*
Y521618D01*
G01X1154776Y525751D02*
Y524760D01*
G01X1154767Y509618D02*
Y508627D01*
G01X1154693Y521698D02*
Y526539D01*
G01Y507839D02*
Y512680D01*
G01X1154501Y525553D02*
Y526538D01*
G01X1154491Y507840D02*
Y508825D01*
G01X1154417Y526539D02*
Y507839D01*
G01X1154339Y509984D02*
Y503902D01*
G01Y530476D02*
Y524394D01*
G01X1154146Y526539D02*
Y525555D01*
G01X1154142Y526539D02*
Y525555D01*
G01X1154137Y508823D02*
Y507839D01*
G01X1154102Y510516D02*
Y506343D01*
G01Y528035D02*
Y523862D01*
G01X1153000D02*
Y528035D01*
G01Y506343D02*
Y510516D01*
G01X1152965Y508823D02*
Y507839D01*
G01X1152961Y508823D02*
Y507839D01*
G01Y526539D02*
Y525555D01*
G01X1152764Y509984D02*
Y503902D01*
G01Y530476D02*
Y524394D01*
G01X1152685Y507839D02*
Y526539D01*
G01X1152606Y508825D02*
Y507840D01*
G01Y526538D02*
Y525553D01*
G01X1152409Y525555D02*
Y530396D01*
G01Y503982D02*
Y508823D01*
G01X1152331Y524760D02*
Y525751D01*
G01Y508627D02*
Y509618D01*
G01X1152252Y504965D02*
Y503902D01*
G01Y530476D02*
Y529413D01*
G01X1151976Y503902D02*
Y504886D01*
G01Y530476D02*
Y529492D01*
G01X1151189Y504886D02*
Y503902D01*
G01Y530476D02*
Y529492D01*
G01X1150913Y504965D02*
Y503902D01*
G01Y530476D02*
Y529413D01*
G01X1150835Y509618D02*
Y508627D01*
G01Y525751D02*
Y524760D01*
G01X1150756Y525555D02*
Y530396D01*
G01Y503982D02*
Y508823D01*
G01X1150559Y525553D02*
Y526538D01*
G01Y507840D02*
Y508825D01*
G01X1150480Y526539D02*
Y507839D01*
G01X1150402Y509984D02*
Y503902D01*
G01Y530476D02*
Y524394D01*
G01X1150205Y508823D02*
Y507839D01*
G01Y526539D02*
Y525555D01*
G01X1150200Y526539D02*
Y525555D01*
G01X1150165Y510516D02*
Y506343D01*
G01Y528035D02*
Y523862D01*
G01X1149122Y514064D02*
Y520314D01*
G01X1149083Y520732D02*
Y513646D01*
G01X1148727Y520732D02*
Y513646D01*
G01X1148177Y524768D02*
Y529492D01*
G01Y504886D02*
Y509610D01*
G01X1148020Y514595D02*
Y519783D01*
G01X1158974Y509010D02*
X1158961Y509984D01*
G01X1156007Y525368D02*
X1156020Y524394D01*
G01X1155032Y509010D02*
X1155019Y509984D01*
G01X1152065Y525368D02*
X1152078Y524394D01*
G01X1151100Y509010D02*
X1151087Y509984D01*
G01X1158587Y520239D02*
X1158451Y526147D01*
G01X1158446Y525261D02*
X1158583Y519353D01*
G01X1156525Y509117D02*
X1156389Y515025D01*
G01X1156384Y514139D02*
X1156521Y508231D01*
G01X1154655Y520239D02*
X1154519Y526147D01*
G01X1154514Y525261D02*
X1154650Y519353D01*
G01X1152593Y509117D02*
X1152457Y515025D01*
G01X1152452Y514139D02*
X1152588Y508231D01*
G01X1150713Y520239D02*
X1150577Y526147D01*
G01X1150572Y525261D02*
X1150708Y519353D01*
G01X1158661Y514341D02*
X1158611Y515327D01*
G01X1158609Y514365D02*
X1158659Y513379D01*
G01X1156372Y520013D02*
X1156322Y520999D01*
G01X1156320Y520037D02*
X1156370Y519051D01*
G01X1154720Y514341D02*
X1154669Y515327D01*
G01X1154667Y514365D02*
X1154717Y513379D01*
G01X1152431Y520013D02*
X1152380Y520999D01*
G01X1152378Y520037D02*
X1152428Y519051D01*
G01X1150787Y514341D02*
X1150737Y515327D01*
G01X1150735Y514365D02*
X1150785Y513379D01*
G01X1155520Y582524D02*
Y577012D01*
G01X1152370Y582524D02*
Y577012D01*
G01X1160215Y525608D02*
X1160206Y525757D01*
G01X1160222Y525193D02*
X1160215Y525608D01*
G01X1160227Y524573D02*
X1160222Y525193D01*
G01X1160228Y523826D02*
X1160227Y524573D01*
G01X1160211Y509680D02*
X1160206Y509606D01*
G01X1160214Y509887D02*
X1160211Y509680D01*
G01X1160216Y510197D02*
X1160214Y509887D01*
G01X1160217Y510571D02*
X1160216Y510197D01*
G01X1160227Y509804D02*
X1160228Y510552D01*
G01X1160222Y509184D02*
X1160227Y509804D01*
G01X1160215Y508770D02*
X1160222Y509184D01*
G01X1160206Y508621D02*
X1160215Y508770D01*
G01X1160206Y524771D02*
Y524772D01*
G01X1160205Y524768D02*
X1160206Y524771D01*
G01X1160205Y524761D02*
Y524768D01*
G01X1160471Y525413D02*
X1160467Y525261D01*
G01X1160476Y525511D02*
X1160471Y525413D01*
G01X1160480Y525553D02*
X1160476Y525511D01*
G01X1162374Y508965D02*
X1162379Y509117D01*
G01X1162370Y508867D02*
X1162374Y508965D01*
G01X1162365Y508825D02*
X1162370Y508867D01*
G01X1164413Y525413D02*
X1164409Y525261D01*
G01X1164417Y525511D02*
X1164413Y525413D01*
G01X1164422Y525553D02*
X1164417Y525511D01*
G01X1166316Y508965D02*
X1166320Y509117D01*
G01X1166312Y508867D02*
X1166316Y508965D01*
G01X1166307Y508825D02*
X1166312Y508867D01*
G01X1160468Y526353D02*
X1160462Y526147D01*
G01X1160474Y526485D02*
X1160468Y526353D01*
G01X1160480Y526538D02*
X1160474Y526485D01*
G01X1164410Y526353D02*
X1164404Y526147D01*
G01X1164416Y526485D02*
X1164410Y526353D01*
G01X1164422Y526538D02*
X1164416Y526485D01*
G01X1162378Y508025D02*
X1162383Y508231D01*
G01X1162372Y507893D02*
X1162378Y508025D01*
G01X1162365Y507840D02*
X1162372Y507893D01*
G01X1168342Y526353D02*
X1168336Y526147D01*
G01X1168348Y526485D02*
X1168342Y526353D01*
G01X1168354Y526538D02*
X1168348Y526485D01*
G01X1166319Y508025D02*
X1166325Y508231D01*
G01X1166313Y507893D02*
X1166319Y508025D01*
G01X1166307Y507840D02*
X1166313Y507893D01*
G01X1162639Y524209D02*
X1162638Y523807D01*
G01X1162642Y524537D02*
X1162639Y524209D01*
G01X1162646Y524733D02*
X1162642Y524537D01*
G01X1162650Y524763D02*
X1162646Y524733D01*
G01X1164149Y510169D02*
X1164150Y510571D01*
G01X1164146Y509841D02*
X1164149Y510169D01*
G01X1164142Y509645D02*
X1164146Y509841D01*
G01X1164137Y509615D02*
X1164142Y509645D01*
G01X1175953Y524768D02*
Y524763D01*
G01X1175954Y524771D02*
X1175953Y524768D01*
G01X1175954Y524772D02*
Y524771D01*
G01X1160205Y525754D02*
Y525751D01*
G01X1160206Y525756D02*
X1160205Y525754D01*
G01X1160206Y525757D02*
Y525756D01*
G01X1168079Y525754D02*
Y525751D01*
G01X1168080Y525756D02*
X1168079Y525754D01*
G01X1168080Y525757D02*
Y525756D01*
G01X1174455Y524771D02*
Y524772D01*
G01X1174456Y524768D02*
X1174455Y524771D01*
G01X1174456Y524763D02*
Y524768D01*
G01X1175954Y509607D02*
Y509606D01*
G01X1175953Y509610D02*
X1175954Y509607D01*
G01X1175953Y509615D02*
Y509610D01*
G01X1160216Y524181D02*
X1160217Y523807D01*
G01X1160214Y524491D02*
X1160216Y524181D01*
G01X1160211Y524698D02*
X1160214Y524491D01*
G01X1160206Y524772D02*
X1160211Y524698D01*
G01X1166571Y510197D02*
X1166570Y510571D01*
G01X1166573Y509887D02*
X1166571Y510197D01*
G01X1166577Y509680D02*
X1166573Y509887D01*
G01X1166581Y509606D02*
X1166577Y509680D01*
G01X1168091Y524181D02*
Y523807D01*
G01X1168088Y524491D02*
X1168091Y524181D01*
G01X1168085Y524698D02*
X1168088Y524491D01*
G01X1168080Y524772D02*
X1168085Y524698D01*
G01X1160474Y507893D02*
X1160480Y507840D01*
G01X1160468Y508025D02*
X1160474Y507893D01*
G01X1160462Y508231D02*
X1160468Y508025D01*
G01X1162381Y526485D02*
X1162375Y526538D01*
G01X1162387Y526353D02*
X1162381Y526485D01*
G01X1162393Y526147D02*
X1162387Y526353D01*
G01X1164406Y507893D02*
X1164413Y507840D01*
G01X1164400Y508025D02*
X1164406Y507893D01*
G01X1164395Y508231D02*
X1164400Y508025D01*
G01X1166313Y526485D02*
X1166307Y526538D01*
G01X1166319Y526353D02*
X1166313Y526485D01*
G01X1166325Y526147D02*
X1166319Y526353D01*
G01X1168348Y507893D02*
X1168354Y507840D01*
G01X1168342Y508025D02*
X1168348Y507893D01*
G01X1168336Y508231D02*
X1168342Y508025D01*
G01X1170255Y526485D02*
X1170249Y526538D01*
G01X1170261Y526353D02*
X1170255Y526485D01*
G01X1170267Y526147D02*
X1170261Y526353D01*
G01X1172280Y507893D02*
X1172287Y507840D01*
G01X1172274Y508025D02*
X1172280Y507893D01*
G01X1172269Y508231D02*
X1172274Y508025D01*
G01X1174187Y526485D02*
X1174181Y526538D01*
G01X1174193Y526353D02*
X1174187Y526485D01*
G01X1174199Y526147D02*
X1174193Y526353D01*
G01X1176222Y507893D02*
X1176228Y507840D01*
G01X1176216Y508025D02*
X1176222Y507893D01*
G01X1176210Y508231D02*
X1176216Y508025D01*
G01X1178129Y526485D02*
X1178123Y526538D01*
G01X1178135Y526353D02*
X1178129Y526485D01*
G01X1178141Y526147D02*
X1178135Y526353D01*
G01X1180154Y507893D02*
X1180161Y507840D01*
G01X1180148Y508025D02*
X1180154Y507893D01*
G01X1180143Y508231D02*
X1180148Y508025D01*
G01X1182061Y526485D02*
X1182055Y526538D01*
G01X1182067Y526353D02*
X1182061Y526485D01*
G01X1182073Y526147D02*
X1182067Y526353D01*
G01X1160476Y508867D02*
X1160480Y508825D01*
G01X1160471Y508965D02*
X1160476Y508867D01*
G01X1160467Y509117D02*
X1160471Y508965D01*
G01X1162379Y525511D02*
X1162375Y525553D01*
G01X1162384Y525413D02*
X1162379Y525511D01*
G01X1162388Y525261D02*
X1162384Y525413D01*
G01X1164408Y508867D02*
X1164413Y508825D01*
G01X1164404Y508965D02*
X1164408Y508867D01*
G01X1164399Y509117D02*
X1164404Y508965D01*
G01X1166312Y525511D02*
X1166307Y525553D01*
G01X1166316Y525413D02*
X1166312Y525511D01*
G01X1166320Y525261D02*
X1166316Y525413D01*
G01X1168350Y508867D02*
X1168354Y508825D01*
G01X1168345Y508965D02*
X1168350Y508867D01*
G01X1168341Y509117D02*
X1168345Y508965D01*
G01X1170253Y525511D02*
X1170249Y525553D01*
G01X1170258Y525413D02*
X1170253Y525511D01*
G01X1170262Y525261D02*
X1170258Y525413D01*
G01X1172282Y508867D02*
X1172287Y508825D01*
G01X1172278Y508965D02*
X1172282Y508867D01*
G01X1172273Y509117D02*
X1172278Y508965D01*
G01X1174186Y525511D02*
X1174181Y525553D01*
G01X1174190Y525413D02*
X1174186Y525511D01*
G01X1174194Y525261D02*
X1174190Y525413D01*
G01X1176224Y508867D02*
X1176228Y508825D01*
G01X1176219Y508965D02*
X1176224Y508867D01*
G01X1176215Y509117D02*
X1176219Y508965D01*
G01X1178127Y525511D02*
X1178123Y525553D01*
G01X1178132Y525413D02*
X1178127Y525511D01*
G01X1178136Y525261D02*
X1178132Y525413D01*
G01X1180156Y508867D02*
X1180161Y508825D01*
G01X1180152Y508965D02*
X1180156Y508867D01*
G01X1180147Y509117D02*
X1180152Y508965D01*
G01X1182060Y525511D02*
X1182055Y525553D01*
G01X1182064Y525413D02*
X1182060Y525511D01*
G01X1182068Y525261D02*
X1182064Y525413D01*
G01X1162636Y509645D02*
X1162641Y509615D01*
G01X1162632Y509841D02*
X1162636Y509645D01*
G01X1162629Y510169D02*
X1162632Y509841D01*
G01X1162628Y510571D02*
X1162629Y510169D01*
G01X1164151Y524733D02*
X1164147Y524763D01*
G01X1164155Y524537D02*
X1164151Y524733D01*
G01X1164158Y524209D02*
X1164155Y524537D01*
G01X1164159Y523807D02*
X1164158Y524209D01*
G01X1170510Y509645D02*
X1170515Y509615D01*
G01X1170506Y509841D02*
X1170510Y509645D01*
G01X1170503Y510169D02*
X1170506Y509841D01*
G01X1170502Y510571D02*
X1170503Y510169D01*
G01X1172025Y524733D02*
X1172021Y524763D01*
G01X1172029Y524537D02*
X1172025Y524733D01*
G01X1172032Y524209D02*
X1172029Y524537D01*
G01X1172033Y523807D02*
X1172032Y524209D01*
G01X1178384Y509645D02*
X1178389Y509615D01*
G01X1178380Y509841D02*
X1178384Y509645D01*
G01X1178377Y510169D02*
X1178380Y509841D01*
G01X1178376Y510571D02*
X1178377Y510169D01*
G01X1179899Y524733D02*
X1179895Y524763D01*
G01X1179903Y524537D02*
X1179899Y524733D01*
G01X1179906Y524209D02*
X1179903Y524537D01*
G01X1179907Y523807D02*
X1179906Y524209D01*
G01X1166573Y508770D02*
X1166581Y508621D01*
G01X1166566Y509184D02*
X1166573Y508770D01*
G01X1166561Y509804D02*
X1166566Y509184D01*
G01X1166559Y510552D02*
X1166561Y509804D01*
G01X1168089Y525608D02*
X1168080Y525757D01*
G01X1168096Y525193D02*
X1168089Y525608D01*
G01X1168101Y524573D02*
X1168096Y525193D01*
G01X1168102Y523826D02*
X1168101Y524573D01*
G01X1174447Y508770D02*
X1174455Y508621D01*
G01X1174440Y509184D02*
X1174447Y508770D01*
G01X1174435Y509804D02*
X1174440Y509184D01*
G01X1174433Y510552D02*
X1174435Y509804D01*
G01X1174451Y509679D02*
X1174455Y509606D01*
G01X1174447Y509887D02*
X1174451Y509679D01*
G01X1174445Y510200D02*
X1174447Y509887D01*
G01X1174444Y510571D02*
X1174445Y510200D01*
G01X1175959Y524699D02*
X1175954Y524772D01*
G01X1175962Y524491D02*
X1175959Y524699D01*
G01X1175965Y524178D02*
X1175962Y524491D01*
G01X1175965Y523807D02*
Y524178D01*
G01X1175963Y525608D02*
X1175954Y525757D01*
G01X1175970Y525193D02*
X1175963Y525608D01*
G01X1175975Y524573D02*
X1175970Y525193D01*
G01X1175976Y523826D02*
X1175975Y524573D01*
G01X1182321Y508770D02*
X1182329Y508621D01*
G01X1182314Y509184D02*
X1182321Y508770D01*
G01X1182309Y509804D02*
X1182314Y509184D01*
G01X1182307Y510552D02*
X1182309Y509804D01*
G01X1182325Y509679D02*
X1182329Y509606D01*
G01X1182321Y509887D02*
X1182325Y509679D01*
G01X1182319Y510200D02*
X1182321Y509887D01*
G01X1182318Y510571D02*
X1182319Y510200D01*
G01X1166577Y524698D02*
X1166581Y524772D01*
G01X1166573Y524491D02*
X1166577Y524698D01*
G01X1166571Y524181D02*
X1166573Y524491D01*
G01X1166570Y523807D02*
X1166571Y524181D01*
G01X1168085Y509680D02*
X1168080Y509606D01*
G01X1168088Y509887D02*
X1168085Y509680D01*
G01X1168091Y510197D02*
X1168088Y509887D01*
G01X1168091Y510571D02*
Y510197D01*
G01X1166561Y524573D02*
X1166559Y523826D01*
G01X1166566Y525193D02*
X1166561Y524573D01*
G01X1166573Y525608D02*
X1166566Y525193D01*
G01X1166581Y525757D02*
X1166573Y525608D01*
G01X1168101Y509804D02*
X1168102Y510552D01*
G01X1168096Y509184D02*
X1168101Y509804D01*
G01X1168089Y508770D02*
X1168096Y509184D01*
G01X1168080Y508621D02*
X1168089Y508770D01*
G01X1174435Y524573D02*
X1174433Y523826D01*
G01X1174440Y525193D02*
X1174435Y524573D01*
G01X1174447Y525608D02*
X1174440Y525193D01*
G01X1174455Y525757D02*
X1174447Y525608D01*
G01X1175975Y509804D02*
X1175976Y510552D01*
G01X1175970Y509184D02*
X1175975Y509804D01*
G01X1175963Y508770D02*
X1175970Y509184D01*
G01X1175954Y508621D02*
X1175963Y508770D01*
G01X1182309Y524573D02*
X1182307Y523826D01*
G01X1182314Y525193D02*
X1182309Y524573D01*
G01X1182321Y525608D02*
X1182314Y525193D01*
G01X1182329Y525757D02*
X1182321Y525608D01*
G01X1174445Y524178D02*
X1174444Y523807D01*
G01X1174447Y524491D02*
X1174445Y524178D01*
G01X1174451Y524699D02*
X1174447Y524491D01*
G01X1174455Y524772D02*
X1174451Y524699D01*
G01X1175965Y510200D02*
Y510571D01*
G01X1175962Y509887D02*
X1175965Y510200D01*
G01X1175959Y509679D02*
X1175962Y509887D01*
G01X1175954Y509606D02*
X1175959Y509679D01*
G01X1182319Y524178D02*
X1182318Y523807D01*
G01X1182321Y524491D02*
X1182319Y524178D01*
G01X1182325Y524699D02*
X1182321Y524491D01*
G01X1182329Y524772D02*
X1182325Y524699D01*
G01X1166581Y509607D02*
Y509606D01*
G01X1166582Y509610D02*
X1166581Y509607D01*
G01X1166583Y509617D02*
X1166582Y509610D01*
G01X1168080Y524771D02*
Y524772D01*
G01X1168079Y524768D02*
X1168080Y524771D01*
G01X1168079Y524761D02*
Y524768D01*
G01X1168345Y525413D02*
X1168341Y525261D01*
G01X1168350Y525511D02*
X1168345Y525413D01*
G01X1168354Y525553D02*
X1168350Y525511D01*
G01X1170248Y508965D02*
X1170253Y509117D01*
G01X1170244Y508867D02*
X1170248Y508965D01*
G01X1170239Y508825D02*
X1170244Y508867D01*
G01X1172287Y525413D02*
X1172283Y525261D01*
G01X1172291Y525511D02*
X1172287Y525413D01*
G01X1172296Y525553D02*
X1172291Y525511D01*
G01X1174190Y508965D02*
X1174194Y509117D01*
G01X1174186Y508867D02*
X1174190Y508965D01*
G01X1174181Y508825D02*
X1174186Y508867D01*
G01X1176219Y525413D02*
X1176215Y525261D01*
G01X1176224Y525511D02*
X1176219Y525413D01*
G01X1176228Y525553D02*
X1176224Y525511D01*
G01X1178122Y508965D02*
X1178127Y509117D01*
G01X1178118Y508867D02*
X1178122Y508965D01*
G01X1178113Y508825D02*
X1178118Y508867D01*
G01X1180161Y525413D02*
X1180157Y525261D01*
G01X1180165Y525511D02*
X1180161Y525413D01*
G01X1180170Y525553D02*
X1180165Y525511D01*
G01X1182064Y508965D02*
X1182068Y509117D01*
G01X1182060Y508867D02*
X1182064Y508965D01*
G01X1182055Y508825D02*
X1182060Y508867D01*
G01X1172284Y526353D02*
X1172278Y526147D01*
G01X1172290Y526485D02*
X1172284Y526353D01*
G01X1172296Y526538D02*
X1172290Y526485D01*
G01X1170252Y508025D02*
X1170257Y508231D01*
G01X1170246Y507893D02*
X1170252Y508025D01*
G01X1170239Y507840D02*
X1170246Y507893D01*
G01X1176216Y526353D02*
X1176210Y526147D01*
G01X1176222Y526485D02*
X1176216Y526353D01*
G01X1176228Y526538D02*
X1176222Y526485D01*
G01X1174193Y508025D02*
X1174199Y508231D01*
G01X1174187Y507893D02*
X1174193Y508025D01*
G01X1174181Y507840D02*
X1174187Y507893D01*
G01X1180158Y526353D02*
X1180152Y526147D01*
G01X1180164Y526485D02*
X1180158Y526353D01*
G01X1180170Y526538D02*
X1180164Y526485D01*
G01X1178126Y508025D02*
X1178131Y508231D01*
G01X1178120Y507893D02*
X1178126Y508025D01*
G01X1178113Y507840D02*
X1178120Y507893D01*
G01X1182067Y508025D02*
X1182073Y508231D01*
G01X1182061Y507893D02*
X1182067Y508025D01*
G01X1182055Y507840D02*
X1182061Y507893D01*
G01X1170513Y524209D02*
X1170512Y523807D01*
G01X1170516Y524537D02*
X1170513Y524209D01*
G01X1170520Y524733D02*
X1170516Y524537D01*
G01X1170524Y524763D02*
X1170520Y524733D01*
G01X1172023Y510169D02*
X1172024Y510571D01*
G01X1172020Y509841D02*
X1172023Y510169D01*
G01X1172016Y509645D02*
X1172020Y509841D01*
G01X1172011Y509615D02*
X1172016Y509645D01*
G01X1178387Y524209D02*
X1178386Y523807D01*
G01X1178390Y524537D02*
X1178387Y524209D01*
G01X1178394Y524733D02*
X1178390Y524537D01*
G01X1178398Y524763D02*
X1178394Y524733D01*
G01X1179897Y510169D02*
X1179898Y510571D01*
G01X1179894Y509841D02*
X1179897Y510169D01*
G01X1179890Y509645D02*
X1179894Y509841D01*
G01X1179885Y509615D02*
X1179890Y509645D01*
G01X1174456Y509610D02*
Y509615D01*
G01X1174455Y509607D02*
X1174456Y509610D01*
G01X1174455Y509606D02*
Y509607D01*
G01X1182330Y509610D02*
X1182331Y509615D01*
G01X1182330Y509607D02*
Y509610D01*
G01X1182329Y509606D02*
X1182330Y509607D01*
G01X1175953Y525754D02*
Y525751D01*
G01X1175954Y525756D02*
X1175953Y525754D01*
G01X1175954Y525757D02*
Y525756D01*
G01X1166582Y508624D02*
X1166583Y508627D01*
G01X1166582Y508622D02*
Y508624D01*
G01X1166581Y508621D02*
X1166582Y508622D01*
G01X1174456Y508624D02*
X1174457Y508627D01*
G01X1174456Y508622D02*
Y508624D01*
G01X1174455Y508621D02*
X1174456Y508622D01*
G01X1182330Y508624D02*
X1182331Y508627D01*
G01X1182330Y508622D02*
Y508624D01*
G01X1182329Y508621D02*
X1182330Y508622D01*
G01X1160206D02*
Y508621D01*
G01X1160205Y508624D02*
X1160206Y508622D01*
G01X1160205Y508627D02*
Y508624D01*
G01X1168080Y508622D02*
Y508621D01*
G01X1168079Y508624D02*
X1168080Y508622D01*
G01X1168079Y508627D02*
Y508624D01*
G01X1166582Y525756D02*
X1166581Y525757D01*
G01X1166582Y525754D02*
Y525756D01*
G01X1166583Y525751D02*
X1166582Y525754D01*
G01X1175954Y508622D02*
Y508621D01*
G01X1175953Y508624D02*
X1175954Y508622D01*
G01X1175953Y508627D02*
Y508624D01*
G01X1182330Y524771D02*
X1182329Y524772D01*
G01X1182330Y524768D02*
Y524771D01*
G01X1182331Y524763D02*
X1182330Y524768D01*
G01X1160205Y509610D02*
Y509617D01*
G01X1160206Y509607D02*
X1160205Y509610D01*
G01X1160206Y509606D02*
Y509607D01*
G01X1168079Y509610D02*
Y509617D01*
G01X1168080Y509607D02*
X1168079Y509610D01*
G01X1168080Y509606D02*
Y509607D01*
G01X1166582Y524768D02*
X1166583Y524761D01*
G01X1166581Y524771D02*
X1166582Y524768D01*
G01X1166581Y524772D02*
Y524771D01*
G01X1174456Y525756D02*
X1174455Y525757D01*
G01X1174456Y525754D02*
Y525756D01*
G01X1174457Y525751D02*
X1174456Y525754D01*
G01X1182330Y525756D02*
X1182329Y525757D01*
G01X1182330Y525754D02*
Y525756D01*
G01X1182331Y525751D02*
X1182330Y525754D01*
G01X1160495Y507839D02*
X1160480Y507840D01*
G01X1160510Y507839D02*
X1160495D01*
G01X1160525D02*
X1160510D01*
G01X1164428D02*
X1164413Y507840D01*
G01X1164443Y507839D02*
X1164428D01*
G01X1164458D02*
X1164443D01*
G01X1168369D02*
X1168354Y507840D01*
G01X1168384Y507839D02*
X1168369D01*
G01X1168399D02*
X1168384D01*
G01X1172302D02*
X1172287Y507840D01*
G01X1172317Y507839D02*
X1172302D01*
G01X1172332D02*
X1172317D01*
G01X1176243D02*
X1176228Y507840D01*
G01X1176258Y507839D02*
X1176243D01*
G01X1176273D02*
X1176258D01*
G01X1180176D02*
X1180161Y507840D01*
G01X1180191Y507839D02*
X1180176D01*
G01X1180206D02*
X1180191D01*
G01X1160495Y508824D02*
X1160480Y508825D01*
G01X1160510Y508823D02*
X1160495Y508824D01*
G01X1160525Y508823D02*
X1160510D01*
G01X1168369Y508824D02*
X1168354Y508825D01*
G01X1168384Y508823D02*
X1168369Y508824D01*
G01X1168399Y508823D02*
X1168384D01*
G01X1172302Y508824D02*
X1172287Y508825D01*
G01X1172317Y508823D02*
X1172302Y508824D01*
G01X1172332Y508823D02*
X1172317D01*
G01X1176243Y508824D02*
X1176228Y508825D01*
G01X1176258Y508823D02*
X1176243Y508824D01*
G01X1176273Y508823D02*
X1176258D01*
G01X1180176Y508824D02*
X1180161Y508825D01*
G01X1180191Y508823D02*
X1180176Y508824D01*
G01X1180206Y508823D02*
X1180191D01*
G01X1164443D02*
X1164458D01*
G01X1164428Y508824D02*
X1164443Y508823D01*
G01X1164413Y508825D02*
X1164428Y508824D01*
G01X1182025Y508823D02*
X1182010D01*
G01X1182040Y508824D02*
X1182025Y508823D01*
G01X1182055Y508825D02*
X1182040Y508824D01*
G01X1178083Y508823D02*
X1178068D01*
G01X1178098Y508824D02*
X1178083Y508823D01*
G01X1178113Y508825D02*
X1178098Y508824D01*
G01X1174151Y508823D02*
X1174136D01*
G01X1174166Y508824D02*
X1174151Y508823D01*
G01X1174181Y508825D02*
X1174166Y508824D01*
G01X1170209Y508823D02*
X1170194D01*
G01X1170224Y508824D02*
X1170209Y508823D01*
G01X1170239Y508825D02*
X1170224Y508824D01*
G01X1166277Y508823D02*
X1166262D01*
G01X1166292Y508824D02*
X1166277Y508823D01*
G01X1166307Y508825D02*
X1166292Y508824D01*
G01X1176258Y525555D02*
X1176273D01*
G01X1176243Y525554D02*
X1176258Y525555D01*
G01X1176228Y525553D02*
X1176243Y525554D01*
G01X1168384Y525555D02*
X1168399D01*
G01X1168369Y525554D02*
X1168384Y525555D01*
G01X1168354Y525553D02*
X1168369Y525554D01*
G01X1164452Y525555D02*
X1164467D01*
G01X1164437Y525554D02*
X1164452Y525555D01*
G01X1164422Y525553D02*
X1164437Y525554D01*
G01X1160510Y525555D02*
X1160525D01*
G01X1160495Y525554D02*
X1160510Y525555D01*
G01X1160480Y525553D02*
X1160495Y525554D01*
G01X1182025Y507839D02*
X1182010D01*
G01X1182040D02*
X1182025D01*
G01X1182055Y507840D02*
X1182040Y507839D01*
G01X1178083D02*
X1178068D01*
G01X1178098D02*
X1178083D01*
G01X1178113Y507840D02*
X1178098Y507839D01*
G01X1174151D02*
X1174136D01*
G01X1174166D02*
X1174151D01*
G01X1174181Y507840D02*
X1174166Y507839D01*
G01X1170209D02*
X1170194D01*
G01X1170224D02*
X1170209D01*
G01X1170239Y507840D02*
X1170224Y507839D01*
G01X1162335D02*
X1162320D01*
G01X1162350D02*
X1162335D01*
G01X1162365Y507840D02*
X1162350Y507839D01*
G01X1180200Y526539D02*
X1180215D01*
G01X1180185D02*
X1180200D01*
G01X1180170Y526538D02*
X1180185Y526539D01*
G01X1176258D02*
X1176273D01*
G01X1176243D02*
X1176258D01*
G01X1176228Y526538D02*
X1176243Y526539D01*
G01X1172326D02*
X1172341D01*
G01X1172311D02*
X1172326D01*
G01X1172296Y526538D02*
X1172311Y526539D01*
G01X1162360D02*
X1162375Y526538D01*
G01X1162345Y526539D02*
X1162360D01*
G01X1162330D02*
X1162345D01*
G01X1166292D02*
X1166307Y526538D01*
G01X1166277Y526539D02*
X1166292D01*
G01X1166262D02*
X1166277D01*
G01X1170234D02*
X1170249Y526538D01*
G01X1170219Y526539D02*
X1170234D01*
G01X1170204D02*
X1170219D01*
G01X1174166D02*
X1174181Y526538D01*
G01X1174151Y526539D02*
X1174166D01*
G01X1174136D02*
X1174151D01*
G01X1178108D02*
X1178123Y526538D01*
G01X1178093Y526539D02*
X1178108D01*
G01X1178078D02*
X1178093D01*
G01X1182040D02*
X1182055Y526538D01*
G01X1182025Y526539D02*
X1182040D01*
G01X1182010D02*
X1182025D01*
G01X1162360Y525554D02*
X1162375Y525553D01*
G01X1162345Y525555D02*
X1162360Y525554D01*
G01X1162330Y525555D02*
X1162345D01*
G01X1166292Y525554D02*
X1166307Y525553D01*
G01X1166277Y525555D02*
X1166292Y525554D01*
G01X1166262Y525555D02*
X1166277D01*
G01X1170234Y525554D02*
X1170249Y525553D01*
G01X1170219Y525555D02*
X1170234Y525554D01*
G01X1170204Y525555D02*
X1170219D01*
G01X1174166Y525554D02*
X1174181Y525553D01*
G01X1174151Y525555D02*
X1174166Y525554D01*
G01X1174136Y525555D02*
X1174151D01*
G01X1178108Y525554D02*
X1178123Y525553D01*
G01X1178093Y525555D02*
X1178108Y525554D01*
G01X1178078Y525555D02*
X1178093D01*
G01X1182040Y525554D02*
X1182055Y525553D01*
G01X1182025Y525555D02*
X1182040Y525554D01*
G01X1182010Y525555D02*
X1182025D01*
G01X1164575Y530476D02*
X1162213D01*
G01X1168512D02*
X1166150D01*
G01X1172449D02*
X1170087D01*
G01X1176386D02*
X1174024D01*
G01X1180323D02*
X1177961D01*
G01X1184260D02*
X1181898D01*
G01X1168000Y529492D02*
X1166661D01*
G01X1175874D02*
X1174535D01*
G01X1182252Y529394D02*
X1183906D01*
G01X1174378D02*
X1176031D01*
G01X1166504D02*
X1168157D01*
G01X1164575Y529295D02*
X1162213D01*
G01X1168512D02*
X1166150D01*
G01X1172449D02*
X1170087D01*
G01X1176386D02*
X1174024D01*
G01X1180323D02*
X1177961D01*
G01X1184260D02*
X1181898D01*
G01X1168157Y528902D02*
X1166504D01*
G01X1176031D02*
X1174378D01*
G01X1183906D02*
X1182252D01*
G01X1164811Y528035D02*
X1161976D01*
G01X1168748D02*
X1165913D01*
G01X1172685D02*
X1169850D01*
G01X1176622D02*
X1173787D01*
G01X1180559D02*
X1177724D01*
G01X1184496D02*
X1181661D01*
G01X1168157Y527130D02*
X1166504D01*
G01X1176031D02*
X1174378D01*
G01X1183906D02*
X1182252D01*
G01Y526638D02*
X1183906D01*
G01X1174378D02*
X1176031D01*
G01X1166504D02*
X1168157D01*
G01X1164811Y526539D02*
X1161976D01*
G01X1168748D02*
X1165913D01*
G01X1172685D02*
X1169850D01*
G01X1176622D02*
X1173787D01*
G01X1180559D02*
X1177724D01*
G01X1184496D02*
X1181661D01*
G01Y526382D02*
X1182252D01*
G01X1179968D02*
X1180559D01*
G01X1177724D02*
X1178315D01*
G01X1176031D02*
X1176622D01*
G01X1173787D02*
X1174378D01*
G01X1172094D02*
X1172685D01*
G01X1169850D02*
X1170441D01*
G01X1168157D02*
X1168748D01*
G01X1165913D02*
X1166504D01*
G01X1164220D02*
X1164811D01*
G01X1161976D02*
X1162567D01*
G01X1160283D02*
X1160874D01*
G01X1182073Y526147D02*
X1184084D01*
G01X1178141D02*
X1180152D01*
G01X1174199D02*
X1176210D01*
G01X1170267D02*
X1172278D01*
G01X1166325D02*
X1168336D01*
G01X1162393D02*
X1164404D01*
G01X1164148Y525757D02*
X1162649D01*
G01X1168080D02*
X1166581D01*
G01X1172022D02*
X1170523D01*
G01X1175954D02*
X1174455D01*
G01X1179896D02*
X1178397D01*
G01X1183828D02*
X1182329D01*
G01X1182342Y525738D02*
X1183815D01*
G01X1178410D02*
X1179883D01*
G01X1174468D02*
X1175941D01*
G01X1170536D02*
X1172009D01*
G01X1166594D02*
X1168067D01*
G01X1162662D02*
X1164135D01*
G01X1160874Y525713D02*
X1160283D01*
G01X1162567D02*
X1161976D01*
G01X1164811D02*
X1164220D01*
G01X1166504D02*
X1165913D01*
G01X1168748D02*
X1168157D01*
G01X1170441D02*
X1169850D01*
G01X1172685D02*
X1172094D01*
G01X1174378D02*
X1173787D01*
G01X1176622D02*
X1176031D01*
G01X1178315D02*
X1177724D01*
G01X1180559D02*
X1179968D01*
G01X1182252D02*
X1181661D01*
G01Y525555D02*
X1184496D01*
G01X1177724D02*
X1180559D01*
G01X1173787D02*
X1176622D01*
G01X1169850D02*
X1172685D01*
G01X1165913D02*
X1168748D01*
G01X1161976D02*
X1164811D01*
G01X1164220Y525457D02*
X1162567D01*
G01X1172094D02*
X1170441D01*
G01X1179968D02*
X1178315D01*
G01X1163881Y525368D02*
X1162916D01*
G01X1167813D02*
X1166848D01*
G01X1171755D02*
X1170790D01*
G01X1175687D02*
X1174722D01*
G01X1179629D02*
X1178664D01*
G01X1181661Y525358D02*
X1181976D01*
G01X1177724D02*
X1178039D01*
G01X1173787D02*
X1174102D01*
G01X1169850D02*
X1170165D01*
G01X1161976D02*
X1162291D01*
G01X1160874D02*
X1160559D01*
G01X1164811D02*
X1164496D01*
G01X1166228D02*
X1165913D01*
G01X1168748D02*
X1168433D01*
G01X1172685D02*
X1172370D01*
G01X1176622D02*
X1176307D01*
G01X1180559D02*
X1180244D01*
G01X1164409Y525261D02*
X1162388D01*
G01X1168341D02*
X1166320D01*
G01X1172283D02*
X1170262D01*
G01X1176215D02*
X1174194D01*
G01X1180157D02*
X1178136D01*
G01X1184089D02*
X1182068D01*
G01X1178315Y524965D02*
X1179968D01*
G01X1170441D02*
X1172094D01*
G01X1162567D02*
X1164220D01*
G01X1164148Y524772D02*
X1162649D01*
G01X1168080D02*
X1166581D01*
G01X1172022D02*
X1170523D01*
G01X1175954D02*
X1174455D01*
G01X1179896D02*
X1178397D01*
G01X1183828D02*
X1182329D01*
G01X1164147Y524763D02*
X1162650D01*
G01X1168079D02*
X1166582D01*
G01X1172021D02*
X1170524D01*
G01X1175953D02*
X1174456D01*
G01X1179895D02*
X1178398D01*
G01X1183827D02*
X1182331D01*
G01X1178618Y524441D02*
X1179675D01*
G01X1174676D02*
X1175733D01*
G01X1170744D02*
X1171801D01*
G01X1166802D02*
X1167859D01*
G01X1162870D02*
X1163927D01*
G01X1166150Y524394D02*
X1168512D01*
G01X1162213D02*
X1164575D01*
G01X1172449D02*
X1170087D01*
G01X1176386D02*
X1174024D01*
G01X1180323D02*
X1177961D01*
G01X1184260D02*
X1181898D01*
G01X1181661Y523862D02*
X1181976D01*
G01X1180244D02*
X1180559D01*
G01X1177724D02*
X1178039D01*
G01X1176307D02*
X1176622D01*
G01X1172370D02*
X1172685D01*
G01X1173787D02*
X1174102D01*
G01X1169850D02*
X1170165D01*
G01X1168433D02*
X1168748D01*
G01X1165913D02*
X1166228D01*
G01X1164496D02*
X1164811D01*
G01X1161976D02*
X1162291D01*
G01X1160559D02*
X1160874D01*
G01X1182307Y523826D02*
X1183850D01*
G01X1178375D02*
X1179918D01*
G01X1174433D02*
X1175976D01*
G01X1170501D02*
X1172044D01*
G01X1166559D02*
X1168102D01*
G01X1162627D02*
X1164170D01*
G01X1182318Y523807D02*
X1183839D01*
G01X1178386D02*
X1179907D01*
G01X1174444D02*
X1175965D01*
G01X1170512D02*
X1172033D01*
G01X1166570D02*
X1168091D01*
G01X1162638D02*
X1164159D01*
G01X1178315Y523193D02*
X1179968D01*
G01X1170441D02*
X1172094D01*
G01X1162567D02*
X1164220D01*
G01Y522701D02*
X1162567D01*
G01X1172094D02*
X1170441D01*
G01X1179968D02*
X1178315D01*
G01X1164063Y522602D02*
X1162724D01*
G01X1171937D02*
X1170598D01*
G01X1179811D02*
X1178472D01*
G01Y521618D02*
X1179811D01*
G01X1170598D02*
X1171937D01*
G01X1162724D02*
X1164063D01*
G01X1164196Y520999D02*
X1162601D01*
G01X1168128D02*
X1166533D01*
G01X1172070D02*
X1170475D01*
G01X1176002D02*
X1174407D01*
G01X1179944D02*
X1178349D01*
G01X1183876D02*
X1182281D01*
G01X1164496Y520890D02*
X1162291D01*
G01X1168433D02*
X1166228D01*
G01X1172370D02*
X1170165D01*
G01X1176307D02*
X1174102D01*
G01X1180244D02*
X1178039D01*
G01X1184181D02*
X1181976D01*
G01X1164268Y520239D02*
X1162529D01*
G01X1168200D02*
X1166461D01*
G01X1172142D02*
X1170403D01*
G01X1176074D02*
X1174335D01*
G01X1180016D02*
X1178277D01*
G01X1183948D02*
X1182209D01*
G01X1182283Y520037D02*
X1183874D01*
G01X1178351D02*
X1179942D01*
G01X1174409D02*
X1176000D01*
G01X1170477D02*
X1172068D01*
G01X1166535D02*
X1168126D01*
G01X1162603D02*
X1164194D01*
G01X1182231Y520013D02*
X1183927D01*
G01X1178298D02*
X1179994D01*
G01X1174357D02*
X1176053D01*
G01X1170424D02*
X1172120D01*
G01X1166483D02*
X1168179D01*
G01X1162550D02*
X1164246D01*
G01X1164253Y519945D02*
X1162543D01*
G01X1168186D02*
X1166476D01*
G01X1172127D02*
X1170417D01*
G01X1176060D02*
X1174350D01*
G01X1180001D02*
X1178291D01*
G01X1183934D02*
X1182224D01*
G01X1182205Y519353D02*
X1183953D01*
G01X1178272D02*
X1180021D01*
G01X1174331D02*
X1176079D01*
G01X1170398D02*
X1172147D01*
G01X1166457D02*
X1168205D01*
G01X1162524D02*
X1164273D01*
G01X1164244Y519051D02*
X1162553D01*
G01X1168176D02*
X1166485D01*
G01X1172118D02*
X1170427D01*
G01X1176050D02*
X1174359D01*
G01X1179992D02*
X1178301D01*
G01X1183924D02*
X1182233D01*
G01X1164253Y518961D02*
X1162543D01*
G01X1168186D02*
X1166476D01*
G01X1172127D02*
X1170417D01*
G01X1176060D02*
X1174350D01*
G01X1180001D02*
X1178291D01*
G01X1183934D02*
X1182224D01*
G01X1181976Y518635D02*
X1184181D01*
G01X1178039D02*
X1180244D01*
G01X1174102D02*
X1176307D01*
G01X1170165D02*
X1172370D01*
G01X1166228D02*
X1168433D01*
G01X1162291D02*
X1164496D01*
G01X1181976Y518468D02*
X1184181D01*
G01X1178039D02*
X1180244D01*
G01X1174102D02*
X1176307D01*
G01X1170165D02*
X1172370D01*
G01X1166228D02*
X1168433D01*
G01X1162291D02*
X1164496D01*
G01Y515910D02*
X1162291D01*
G01X1168433D02*
X1166228D01*
G01X1172370D02*
X1170165D01*
G01X1176307D02*
X1174102D01*
G01X1180244D02*
X1178039D01*
G01X1184181D02*
X1181976D01*
G01X1164496Y515743D02*
X1162291D01*
G01X1168433D02*
X1166228D01*
G01X1172370D02*
X1170165D01*
G01X1176307D02*
X1174102D01*
G01X1180244D02*
X1178039D01*
G01X1184181D02*
X1181976D01*
G01X1182224Y515417D02*
X1183934D01*
G01X1178282D02*
X1179992D01*
G01X1174350D02*
X1176060D01*
G01X1170408D02*
X1172118D01*
G01X1166476D02*
X1168186D01*
G01X1162534D02*
X1164244D01*
G01X1182233Y515327D02*
X1183924D01*
G01X1178291D02*
X1179983D01*
G01X1174359D02*
X1176050D01*
G01X1170417D02*
X1172109D01*
G01X1166485D02*
X1168176D01*
G01X1162543D02*
X1164235D01*
G01X1164263Y515025D02*
X1162515D01*
G01X1168205D02*
X1166457D01*
G01X1172137D02*
X1170389D01*
G01X1176079D02*
X1174331D01*
G01X1180011D02*
X1178263D01*
G01X1183953D02*
X1182205D01*
G01X1182224Y514433D02*
X1183934D01*
G01X1178282D02*
X1179992D01*
G01X1174350D02*
X1176060D01*
G01X1170408D02*
X1172118D01*
G01X1166476D02*
X1168186D01*
G01X1162534D02*
X1164244D01*
G01X1164237Y514365D02*
X1162541D01*
G01X1168179D02*
X1166483D01*
G01X1172111D02*
X1170415D01*
G01X1176053D02*
X1174357D01*
G01X1179985D02*
X1178289D01*
G01X1183927D02*
X1182231D01*
G01X1164184Y514341D02*
X1162594D01*
G01X1168126D02*
X1166535D01*
G01X1172058D02*
X1170468D01*
G01X1176000D02*
X1174409D01*
G01X1179932D02*
X1178342D01*
G01X1183874D02*
X1182283D01*
G01X1182209Y514139D02*
X1183948D01*
G01X1178268D02*
X1180006D01*
G01X1174335D02*
X1176074D01*
G01X1170394D02*
X1172132D01*
G01X1166461D02*
X1168200D01*
G01X1162520D02*
X1164258D01*
G01X1181976Y513488D02*
X1184181D01*
G01X1178039D02*
X1180244D01*
G01X1174102D02*
X1176307D01*
G01X1170165D02*
X1172370D01*
G01X1166228D02*
X1168433D01*
G01X1162291D02*
X1164496D01*
G01X1182281Y513379D02*
X1183876D01*
G01X1178339D02*
X1179935D01*
G01X1174407D02*
X1176002D01*
G01X1170465D02*
X1172061D01*
G01X1166533D02*
X1168128D01*
G01X1162591D02*
X1164187D01*
G01X1164063Y512760D02*
X1162724D01*
G01X1171937D02*
X1170598D01*
G01X1179811D02*
X1178472D01*
G01X1164063Y511776D02*
X1162724D01*
G01X1171937D02*
X1170598D01*
G01X1179811D02*
X1178472D01*
G01X1178315Y511677D02*
X1179968D01*
G01X1170441D02*
X1172094D01*
G01X1162567D02*
X1164220D01*
G01Y511185D02*
X1162567D01*
G01X1172094D02*
X1170441D01*
G01X1179968D02*
X1178315D01*
G01X1164150Y510571D02*
X1162628D01*
G01X1168091D02*
X1166570D01*
G01X1172024D02*
X1170502D01*
G01X1175965D02*
X1174444D01*
G01X1179898D02*
X1178376D01*
G01X1183839D02*
X1182318D01*
G01X1164161Y510552D02*
X1162617D01*
G01X1168102D02*
X1166559D01*
G01X1172035D02*
X1170491D01*
G01X1175976D02*
X1174433D01*
G01X1179909D02*
X1178365D01*
G01X1183850D02*
X1182307D01*
G01X1160874Y510516D02*
X1160559D01*
G01X1162291D02*
X1161976D01*
G01X1164811D02*
X1164496D01*
G01X1166228D02*
X1165913D01*
G01X1168748D02*
X1168433D01*
G01X1170165D02*
X1169850D01*
G01X1172685D02*
X1172370D01*
G01X1174102D02*
X1173787D01*
G01X1176622D02*
X1176307D01*
G01X1178039D02*
X1177724D01*
G01X1180559D02*
X1180244D01*
G01X1181976D02*
X1181661D01*
G01X1164575Y509984D02*
X1162213D01*
G01X1168512D02*
X1166150D01*
G01X1172449D02*
X1170087D01*
G01X1176386D02*
X1174024D01*
G01X1180323D02*
X1177961D01*
G01X1184260D02*
X1181898D01*
G01X1163917Y509937D02*
X1162861D01*
G01X1167859D02*
X1166802D01*
G01X1171791D02*
X1170735D01*
G01X1175733D02*
X1174676D01*
G01X1179665D02*
X1178609D01*
G01X1182331Y509615D02*
X1183827D01*
G01X1178389D02*
X1179885D01*
G01X1174456D02*
X1175953D01*
G01X1170515D02*
X1172011D01*
G01X1166582D02*
X1168079D01*
G01X1162641D02*
X1164137D01*
G01X1182329Y509606D02*
X1183828D01*
G01X1178387D02*
X1179887D01*
G01X1174455D02*
X1175954D01*
G01X1170513D02*
X1172013D01*
G01X1166581D02*
X1168080D01*
G01X1162639D02*
X1164139D01*
G01X1164220Y509413D02*
X1162567D01*
G01X1172094D02*
X1170441D01*
G01X1179968D02*
X1178315D01*
G01X1182068Y509117D02*
X1184089D01*
G01X1178127D02*
X1180147D01*
G01X1174194D02*
X1176215D01*
G01X1170253D02*
X1172273D01*
G01X1166320D02*
X1168341D01*
G01X1162379D02*
X1164399D01*
G01X1180244Y509020D02*
X1180559D01*
G01X1176307D02*
X1176622D01*
G01X1172370D02*
X1172685D01*
G01X1164496D02*
X1164811D01*
G01X1160874D02*
X1160559D01*
G01X1162291D02*
X1161976D01*
G01X1166228D02*
X1165913D01*
G01X1168748D02*
X1168433D01*
G01X1170165D02*
X1169850D01*
G01X1174102D02*
X1173787D01*
G01X1178039D02*
X1177724D01*
G01X1181976D02*
X1181661D01*
G01X1178654Y509010D02*
X1179620D01*
G01X1174722D02*
X1175687D01*
G01X1170780D02*
X1171746D01*
G01X1166848D02*
X1167813D01*
G01X1162906D02*
X1163872D01*
G01X1178315Y508921D02*
X1179968D01*
G01X1170441D02*
X1172094D01*
G01X1162567D02*
X1164220D01*
G01X1181661Y508823D02*
X1184496D01*
G01X1177724D02*
X1180559D01*
G01X1173787D02*
X1176622D01*
G01X1169850D02*
X1172685D01*
G01X1165913D02*
X1168748D01*
G01X1161976D02*
X1164811D01*
G01X1181661Y508665D02*
X1182252D01*
G01X1179968D02*
X1180559D01*
G01X1177724D02*
X1178315D01*
G01X1176031D02*
X1176622D01*
G01X1173787D02*
X1174378D01*
G01X1172094D02*
X1172685D01*
G01X1169850D02*
X1170441D01*
G01X1168157D02*
X1168748D01*
G01X1165913D02*
X1166504D01*
G01X1164220D02*
X1164811D01*
G01X1161976D02*
X1162567D01*
G01X1160283D02*
X1160874D01*
G01X1164126Y508640D02*
X1162653D01*
G01X1168067D02*
X1166594D01*
G01X1172000D02*
X1170527D01*
G01X1175941D02*
X1174468D01*
G01X1179874D02*
X1178401D01*
G01X1183815D02*
X1182342D01*
G01X1182329Y508621D02*
X1183828D01*
G01X1178387D02*
X1179887D01*
G01X1174455D02*
X1175954D01*
G01X1170513D02*
X1172013D01*
G01X1166581D02*
X1168080D01*
G01X1162639D02*
X1164139D01*
G01X1164395Y508231D02*
X1162383D01*
G01X1168336D02*
X1166325D01*
G01X1172269D02*
X1170257D01*
G01X1176210D02*
X1174199D01*
G01X1180143D02*
X1178131D01*
G01X1184084D02*
X1182073D01*
G01X1160874Y507996D02*
X1160283D01*
G01X1162567D02*
X1161976D01*
G01X1164811D02*
X1164220D01*
G01X1166504D02*
X1165913D01*
G01X1168748D02*
X1168157D01*
G01X1170441D02*
X1169850D01*
G01X1172685D02*
X1172094D01*
G01X1174378D02*
X1173787D01*
G01X1176622D02*
X1176031D01*
G01X1178315D02*
X1177724D01*
G01X1180559D02*
X1179968D01*
G01X1182252D02*
X1181661D01*
G01X1164811Y507839D02*
X1161976D01*
G01X1168748D02*
X1165913D01*
G01X1172685D02*
X1169850D01*
G01X1176622D02*
X1173787D01*
G01X1180559D02*
X1177724D01*
G01X1184496D02*
X1181661D01*
G01X1168157Y507740D02*
X1166504D01*
G01X1176031D02*
X1174378D01*
G01X1183906D02*
X1182252D01*
G01Y507248D02*
X1183906D01*
G01X1174378D02*
X1176031D01*
G01X1166504D02*
X1168157D01*
G01X1181661Y506343D02*
X1184496D01*
G01X1177724D02*
X1180559D01*
G01X1173787D02*
X1176622D01*
G01X1169850D02*
X1172685D01*
G01X1165913D02*
X1168748D01*
G01X1161976D02*
X1164811D01*
G01X1182252Y505476D02*
X1183906D01*
G01X1174378D02*
X1176031D01*
G01X1166504D02*
X1168157D01*
G01X1166150Y505083D02*
X1168512D01*
G01X1162213D02*
X1164575D01*
G01X1172449D02*
X1170087D01*
G01X1176386D02*
X1174024D01*
G01X1180323D02*
X1177961D01*
G01X1184260D02*
X1181898D01*
G01X1168157Y504984D02*
X1166504D01*
G01X1176031D02*
X1174378D01*
G01X1183906D02*
X1182252D01*
G01X1168000Y504886D02*
X1166661D01*
G01X1175874D02*
X1174535D01*
G01X1181898Y503902D02*
X1184260D01*
G01X1177961D02*
X1180323D01*
G01X1174024D02*
X1176386D01*
G01X1170087D02*
X1172449D01*
G01X1166150D02*
X1168512D01*
G01X1162213D02*
X1164575D01*
G01X1182342Y525738D02*
X1182596Y525368D01*
G01X1182550Y524441D02*
X1182329Y524763D01*
G01X1178410Y525738D02*
X1178664Y525368D01*
G01X1178618Y524441D02*
X1178397Y524763D01*
G01X1174468Y525738D02*
X1174722Y525368D01*
G01X1174676Y524441D02*
X1174455Y524763D01*
G01X1170536Y525738D02*
X1170790Y525368D01*
G01X1170744Y524441D02*
X1170523Y524763D01*
G01X1179665Y509937D02*
X1179887Y509615D01*
G01X1179874Y508640D02*
X1179620Y509010D01*
G01X1166848Y525368D02*
X1166594Y525738D01*
G01X1166583Y524760D02*
X1166802Y524441D01*
G01X1175733Y509937D02*
X1175954Y509615D01*
G01X1175941Y508640D02*
X1175687Y509010D01*
G01X1162916Y525368D02*
X1162662Y525738D01*
G01X1162870Y524441D02*
X1162649Y524763D01*
G01X1171791Y509937D02*
X1172013Y509615D01*
G01X1172000Y508640D02*
X1171746Y509010D01*
G01X1168079Y509618D02*
X1167859Y509937D01*
G01X1167813Y509010D02*
X1168067Y508640D01*
G01X1163917Y509937D02*
X1164139Y509615D01*
G01X1163872Y509010D02*
X1164126Y508640D01*
G01X1160205Y509618D02*
X1159985Y509937D01*
G01X1159939Y509010D02*
X1160193Y508640D01*
G01X1178618Y524441D02*
X1178628Y524394D01*
G01X1179665Y509937D02*
X1179656Y509984D01*
G01X1174676Y524441D02*
X1174686Y524394D01*
G01X1175733Y509937D02*
X1175723Y509984D01*
G01X1170744Y524441D02*
X1170754Y524394D01*
G01X1171791Y509937D02*
X1171782Y509984D01*
G01X1166812Y524394D02*
X1166802Y524441D01*
G01X1167849Y509984D02*
X1167859Y509937D01*
G01X1162870Y524441D02*
X1162880Y524394D01*
G01X1163917Y509937D02*
X1163908Y509984D01*
G01X1159975D02*
X1159985Y509937D01*
G01X1182342Y508640D02*
X1182596Y509010D01*
G01X1182329Y509615D02*
X1182550Y509937D01*
G01X1178401Y508640D02*
X1178654Y509010D01*
G01X1178387Y509615D02*
X1178609Y509937D01*
G01X1174468Y508640D02*
X1174722Y509010D01*
G01X1174455Y509615D02*
X1174676Y509937D01*
G01X1170527Y508640D02*
X1170780Y509010D01*
G01X1170513Y509615D02*
X1170735Y509937D01*
G01X1179896Y524763D02*
X1179675Y524441D01*
G01X1179883Y525738D02*
X1179629Y525368D01*
G01X1166594Y508640D02*
X1166848Y509010D01*
G01X1166802Y509937D02*
X1166583Y509618D01*
G01X1178618Y509984D02*
X1178609Y509937D01*
G01X1179665Y524394D02*
X1179675Y524441D01*
G01X1174686Y509984D02*
X1174676Y509937D01*
G01X1175723Y524394D02*
X1175733Y524441D01*
G01X1170744Y509984D02*
X1170735Y509937D01*
G01X1182233Y519051D02*
X1182283Y520037D01*
G01X1182281Y520999D02*
X1182231Y520013D01*
G01X1179935Y513379D02*
X1179985Y514365D01*
G01X1179983Y515327D02*
X1179932Y514341D01*
G01X1178301Y519051D02*
X1178351Y520037D01*
G01X1178349Y520999D02*
X1178298Y520013D01*
G01X1176002Y513379D02*
X1176053Y514365D01*
G01X1176050Y515327D02*
X1176000Y514341D01*
G01X1174359Y519051D02*
X1174409Y520037D01*
G01X1174407Y520999D02*
X1174357Y520013D01*
G01X1172061Y513379D02*
X1172111Y514365D01*
G01X1172109Y515327D02*
X1172058Y514341D01*
G01X1170427Y519051D02*
X1170477Y520037D01*
G01X1170475Y520999D02*
X1170424Y520013D01*
G01X1168128Y513379D02*
X1168179Y514365D01*
G01X1168176Y515327D02*
X1168126Y514341D01*
G01X1166485Y519051D02*
X1166535Y520037D01*
G01X1166533Y520999D02*
X1166483Y520013D01*
G01X1182073Y508231D02*
X1182209Y514139D01*
G01X1182205Y515025D02*
X1182068Y509117D01*
G01X1180021Y519353D02*
X1180157Y525261D01*
G01X1180152Y526147D02*
X1180016Y520239D01*
G01X1178131Y508231D02*
X1178268Y514139D01*
G01X1178263Y515025D02*
X1178127Y509117D01*
G01X1176079Y519353D02*
X1176215Y525261D01*
G01X1176210Y526147D02*
X1176074Y520239D01*
G01X1174199Y508231D02*
X1174335Y514139D01*
G01X1174331Y515025D02*
X1174194Y509117D01*
G01X1172147Y519353D02*
X1172283Y525261D01*
G01X1172278Y526147D02*
X1172142Y520239D01*
G01X1170257Y508231D02*
X1170394Y514139D01*
G01X1170389Y515025D02*
X1170253Y509117D01*
G01X1168205Y519353D02*
X1168341Y525261D01*
G01X1168336Y526147D02*
X1168200Y520239D01*
G01X1166325Y508231D02*
X1166461Y514139D01*
G01X1166457Y515025D02*
X1166320Y509117D01*
G01X1164273Y519353D02*
X1164409Y525261D01*
G01X1164404Y526147D02*
X1164268Y520239D01*
G01X1179633Y509984D02*
X1179620Y509010D01*
G01X1178651Y524394D02*
X1178664Y525368D01*
G01X1175701Y509984D02*
X1175687Y509010D01*
G01X1174709Y524394D02*
X1174722Y525368D01*
G01X1171759Y509984D02*
X1171746Y509010D01*
G01X1170777Y524394D02*
X1170790Y525368D01*
G01X1167827Y509984D02*
X1167813Y509010D01*
G01X1166835Y524394D02*
X1166848Y525368D01*
G01X1163885Y509984D02*
X1163872Y509010D01*
G01X1162903Y524394D02*
X1162916Y525368D01*
G01X1182331Y509618D02*
Y508627D01*
G01Y525751D02*
Y524760D01*
G01X1182252Y525555D02*
Y530396D01*
G01Y503982D02*
Y508823D01*
G01X1182055Y507840D02*
Y508825D01*
G01Y525553D02*
Y526538D01*
G01X1181976Y526539D02*
Y507839D01*
G01X1181898Y509984D02*
Y503902D01*
G01Y530476D02*
Y524394D01*
G01X1181701Y508823D02*
Y507839D01*
G01Y526539D02*
Y525555D01*
G01X1181696Y526539D02*
Y525555D01*
G01X1181661Y510516D02*
Y506343D01*
G01Y528035D02*
Y523862D01*
G01X1180559D02*
Y528035D01*
G01Y506343D02*
Y510516D01*
G01X1180524Y526539D02*
Y525555D01*
G01X1180520Y508823D02*
Y507839D01*
G01X1180515Y508823D02*
Y507839D01*
G01X1180323Y509984D02*
Y503902D01*
G01Y530476D02*
Y524394D01*
G01X1180244Y507839D02*
Y526539D01*
G01X1180170Y526538D02*
Y525553D01*
G01X1180161Y508825D02*
Y507840D01*
G01X1179968Y521698D02*
Y526539D01*
G01Y507839D02*
Y512680D01*
G01X1179894Y524760D02*
Y525751D01*
G01X1179885Y508627D02*
Y509618D01*
G01X1179811Y512760D02*
Y511696D01*
G01Y522681D02*
Y521618D01*
G01X1179535D02*
Y522602D01*
G01Y512760D02*
Y511776D01*
G01X1178748Y521618D02*
Y522602D01*
G01Y511776D02*
Y512760D01*
G01X1178472D02*
Y511696D01*
G01Y522682D02*
Y521618D01*
G01X1178398Y525751D02*
Y524760D01*
G01X1178389Y509618D02*
Y508627D01*
G01X1178315Y521698D02*
Y526539D01*
G01Y507839D02*
Y512680D01*
G01X1178123Y525553D02*
Y526538D01*
G01X1178113Y507840D02*
Y508825D01*
G01X1178039Y526539D02*
Y507839D01*
G01X1177961Y509984D02*
Y503902D01*
G01Y530476D02*
Y524394D01*
G01X1177768Y526539D02*
Y525555D01*
G01X1177764Y526539D02*
Y525555D01*
G01X1177759Y508823D02*
Y507839D01*
G01X1177724Y510516D02*
Y506343D01*
G01Y528035D02*
Y523862D01*
G01X1176622D02*
Y528035D01*
G01Y506343D02*
Y510516D01*
G01X1176587Y508823D02*
Y507839D01*
G01X1176583Y508823D02*
Y507839D01*
G01Y526539D02*
Y525555D01*
G01X1176386Y509984D02*
Y503902D01*
G01Y530476D02*
Y524394D01*
G01X1176307Y507839D02*
Y526539D01*
G01X1176228Y508825D02*
Y507840D01*
G01Y526538D02*
Y525553D01*
G01X1176031Y525555D02*
Y530396D01*
G01Y503982D02*
Y508823D01*
G01X1175953Y524760D02*
Y525751D01*
G01Y508627D02*
Y509618D01*
G01X1175874Y504965D02*
Y503902D01*
G01Y530476D02*
Y529413D01*
G01X1175598Y504886D02*
Y503902D01*
G01Y530476D02*
Y529492D01*
G01X1174811D02*
Y530476D01*
G01Y504886D02*
Y503902D01*
G01X1174535Y504965D02*
Y503902D01*
G01Y530476D02*
Y529413D01*
G01X1174457Y509618D02*
Y508627D01*
G01Y525751D02*
Y524760D01*
G01X1174378Y525555D02*
Y530396D01*
G01Y503982D02*
Y508823D01*
G01X1174181Y525553D02*
Y526538D01*
G01Y507840D02*
Y508825D01*
G01X1174102Y526539D02*
Y507839D01*
G01X1174024Y509984D02*
Y503902D01*
G01Y530476D02*
Y524394D01*
G01X1173827Y508823D02*
Y507839D01*
G01Y526539D02*
Y525555D01*
G01X1173822Y526539D02*
Y525555D01*
G01X1173787Y510516D02*
Y506343D01*
G01Y528035D02*
Y523862D01*
G01X1172685D02*
Y528035D01*
G01Y506343D02*
Y510516D01*
G01X1172650Y526539D02*
Y525555D01*
G01X1172646Y508823D02*
Y507839D01*
G01X1172641Y508823D02*
Y507839D01*
G01X1172449Y509984D02*
Y503902D01*
G01Y530476D02*
Y524394D01*
G01X1172370Y507839D02*
Y526539D01*
G01X1172296Y526538D02*
Y525553D01*
G01X1172287Y508825D02*
Y507840D01*
G01X1172094Y521698D02*
Y526539D01*
G01Y507839D02*
Y512680D01*
G01X1172020Y524760D02*
Y525751D01*
G01X1172011Y508627D02*
Y509618D01*
G01X1171937Y512760D02*
Y511696D01*
G01Y522681D02*
Y521618D01*
G01X1171661D02*
Y522602D01*
G01Y512760D02*
Y511776D01*
G01X1170874Y521618D02*
Y522602D01*
G01Y511776D02*
Y512760D01*
G01X1170598D02*
Y511696D01*
G01Y522682D02*
Y521618D01*
G01X1170524Y525751D02*
Y524760D01*
G01X1170515Y509618D02*
Y508627D01*
G01X1170441Y521698D02*
Y526539D01*
G01Y507839D02*
Y512680D01*
G01X1170249Y525553D02*
Y526538D01*
G01X1170239Y507840D02*
Y508825D01*
G01X1170165Y526539D02*
Y507839D01*
G01X1170087Y509984D02*
Y503902D01*
G01Y530476D02*
Y524394D01*
G01X1169894Y526539D02*
Y525555D01*
G01X1169890Y526539D02*
Y525555D01*
G01X1169885Y508823D02*
Y507839D01*
G01X1169850Y510516D02*
Y506343D01*
G01Y528035D02*
Y523862D01*
G01X1168748D02*
Y528035D01*
G01Y506343D02*
Y510516D01*
G01X1168713Y508823D02*
Y507839D01*
G01X1168709Y508823D02*
Y507839D01*
G01Y526539D02*
Y525555D01*
G01X1168512Y509984D02*
Y503902D01*
G01Y530476D02*
Y524394D01*
G01X1168433Y507839D02*
Y526539D01*
G01X1168354Y508825D02*
Y507840D01*
G01Y526538D02*
Y525553D01*
G01X1168157Y525555D02*
Y530396D01*
G01Y503982D02*
Y508823D01*
G01X1168079Y524760D02*
Y525751D01*
G01Y508627D02*
Y509618D01*
G01X1168000Y504965D02*
Y503902D01*
G01Y530476D02*
Y529413D01*
G01X1167724Y503902D02*
Y504886D01*
G01Y530476D02*
Y529492D01*
G01X1166937Y504886D02*
Y503902D01*
G01Y530476D02*
Y529492D01*
G01X1166661Y504965D02*
Y503902D01*
G01Y530476D02*
Y529413D01*
G01X1166583Y509618D02*
Y508627D01*
G01Y525751D02*
Y524760D01*
G01X1166504Y525555D02*
Y530396D01*
G01Y503982D02*
Y508823D01*
G01X1166307Y525553D02*
Y526538D01*
G01Y507840D02*
Y508825D01*
G01X1166228Y526539D02*
Y507839D01*
G01X1166150Y509984D02*
Y503902D01*
G01Y530476D02*
Y524394D01*
G01X1165953Y508823D02*
Y507839D01*
G01Y526539D02*
Y525555D01*
G01X1165948Y526539D02*
Y525555D01*
G01X1165913Y510516D02*
Y506343D01*
G01Y528035D02*
Y523862D01*
G01X1164811D02*
Y528035D01*
G01Y506343D02*
Y510516D01*
G01X1164776Y526539D02*
Y525555D01*
G01X1164772Y508823D02*
Y507839D01*
G01X1164767Y508823D02*
Y507839D01*
G01X1164575Y509984D02*
Y503902D01*
G01Y530476D02*
Y524394D01*
G01X1164496Y507839D02*
Y526539D01*
G01X1164422Y526538D02*
Y525553D01*
G01X1164413Y508825D02*
Y507840D01*
G01X1164220Y521698D02*
Y526539D01*
G01Y507839D02*
Y512680D01*
G01X1164146Y524760D02*
Y525751D01*
G01X1164137Y508627D02*
Y509618D01*
G01X1164063Y512760D02*
Y511696D01*
G01Y522681D02*
Y521618D01*
G01X1163787D02*
Y522602D01*
G01Y512760D02*
Y511776D01*
G01X1163000Y521618D02*
Y522602D01*
G01Y512760D02*
Y511776D01*
G01X1162724Y512760D02*
Y511696D01*
G01Y522682D02*
Y521618D01*
G01X1162650Y525751D02*
Y524760D01*
G01X1162641Y509618D02*
Y508627D01*
G01X1162567Y521698D02*
Y526539D01*
G01Y507839D02*
Y512680D01*
G01X1162375Y525553D02*
Y526538D01*
G01X1162365Y507840D02*
Y508825D01*
G01X1162291Y526539D02*
Y507839D01*
G01X1162213Y509984D02*
Y503902D01*
G01Y530476D02*
Y524394D01*
G01X1162020Y526539D02*
Y525555D01*
G01X1162016Y526539D02*
Y525555D01*
G01X1162011Y508823D02*
Y507839D01*
G01X1161976Y510516D02*
Y506343D01*
G01Y528035D02*
Y523862D01*
G01X1179629Y525368D02*
X1179642Y524394D01*
G01X1178654Y509010D02*
X1178641Y509984D01*
G01X1175687Y525368D02*
X1175701Y524394D01*
G01X1174722Y509010D02*
X1174709Y509984D01*
G01X1171755Y525368D02*
X1171768Y524394D01*
G01X1170780Y509010D02*
X1170767Y509984D01*
G01X1167813Y525368D02*
X1167827Y524394D01*
G01X1166848Y509010D02*
X1166835Y509984D01*
G01X1163881Y525368D02*
X1163894Y524394D01*
G01X1162906Y509010D02*
X1162893Y509984D01*
G01X1182209Y520239D02*
X1182073Y526147D01*
G01X1182068Y525261D02*
X1182205Y519353D01*
G01X1180147Y509117D02*
X1180011Y515025D01*
G01X1180006Y514139D02*
X1180143Y508231D01*
G01X1178277Y520239D02*
X1178141Y526147D01*
G01X1178136Y525261D02*
X1178272Y519353D01*
G01X1176215Y509117D02*
X1176079Y515025D01*
G01X1176074Y514139D02*
X1176210Y508231D01*
G01X1174335Y520239D02*
X1174199Y526147D01*
G01X1174194Y525261D02*
X1174331Y519353D01*
G01X1172273Y509117D02*
X1172137Y515025D01*
G01X1172132Y514139D02*
X1172269Y508231D01*
G01X1170403Y520239D02*
X1170267Y526147D01*
G01X1170262Y525261D02*
X1170398Y519353D01*
G01X1168341Y509117D02*
X1168205Y515025D01*
G01X1168200Y514139D02*
X1168336Y508231D01*
G01X1166461Y520239D02*
X1166325Y526147D01*
G01X1166320Y525261D02*
X1166457Y519353D01*
G01X1164399Y509117D02*
X1164263Y515025D01*
G01X1164258Y514139D02*
X1164395Y508231D01*
G01X1162529Y520239D02*
X1162393Y526147D01*
G01X1162388Y525261D02*
X1162524Y519353D01*
G01X1182283Y514341D02*
X1182233Y515327D01*
G01X1182231Y514365D02*
X1182281Y513379D01*
G01X1179994Y520013D02*
X1179944Y520999D01*
G01X1179942Y520037D02*
X1179992Y519051D01*
G01X1178342Y514341D02*
X1178291Y515327D01*
G01X1178289Y514365D02*
X1178339Y513379D01*
G01X1176053Y520013D02*
X1176002Y520999D01*
G01X1176000Y520037D02*
X1176050Y519051D01*
G01X1174409Y514341D02*
X1174359Y515327D01*
G01X1174357Y514365D02*
X1174407Y513379D01*
G01X1172120Y520013D02*
X1172070Y520999D01*
G01X1172068Y520037D02*
X1172118Y519051D01*
G01X1170468Y514341D02*
X1170417Y515327D01*
G01X1170415Y514365D02*
X1170465Y513379D01*
G01X1168179Y520013D02*
X1168128Y520999D01*
G01X1168126Y520037D02*
X1168176Y519051D01*
G01X1166535Y514341D02*
X1166485Y515327D01*
G01X1166483Y514365D02*
X1166533Y513379D01*
G01X1164246Y520013D02*
X1164196Y520999D01*
G01X1164194Y520037D02*
X1164244Y519051D01*
G01X1162594Y514341D02*
X1162543Y515327D01*
G01X1162541Y514365D02*
X1162591Y513379D01*
G01X1160305Y520013D02*
X1160254Y520999D01*
G01X1160252Y520037D02*
X1160302Y519051D01*
G01X1175954Y524763D02*
X1175733Y524441D01*
G01X1175941Y525738D02*
X1175687Y525368D01*
G01X1162653Y508640D02*
X1162906Y509010D01*
G01X1162639Y509615D02*
X1162861Y509937D01*
G01X1172022Y524763D02*
X1171801Y524441D01*
G01X1172009Y525738D02*
X1171755Y525368D01*
G01X1167859Y524441D02*
X1168079Y524760D01*
G01X1168067Y525738D02*
X1167813Y525368D01*
G01X1164148Y524763D02*
X1163927Y524441D01*
G01X1164135Y525738D02*
X1163881Y525368D01*
G01X1159985Y524441D02*
X1160205Y524760D01*
G01X1160193Y525738D02*
X1159939Y525368D01*
G01X1171791Y524394D02*
X1171801Y524441D01*
G01X1166802Y509937D02*
X1166812Y509984D01*
G01X1167859Y524441D02*
X1167849Y524394D01*
G01X1162870Y509984D02*
X1162861Y509937D01*
G01X1163917Y524394D02*
X1163927Y524441D01*
G01X1159985D02*
X1159975Y524394D01*
G01X1164187Y513379D02*
X1164237Y514365D01*
G01X1164235Y515327D02*
X1164184Y514341D01*
G01X1162553Y519051D02*
X1162603Y520037D01*
G01X1162601Y520999D02*
X1162550Y520013D01*
G01X1160254Y513379D02*
X1160305Y514365D01*
G01X1160302Y515327D02*
X1160252Y514341D01*
G01X1162383Y508231D02*
X1162520Y514139D01*
G01X1162515Y515025D02*
X1162379Y509117D01*
G01X1160331Y519353D02*
X1160467Y525261D01*
G01X1160462Y526147D02*
X1160326Y520239D01*
G01X1159952Y509984D02*
X1159939Y509010D01*
G01X1160874Y523862D02*
Y528035D01*
G01Y506343D02*
Y510516D01*
G01X1160839Y508823D02*
Y507839D01*
G01X1160835Y508823D02*
Y507839D01*
G01Y526539D02*
Y525555D01*
G01X1160638Y509984D02*
Y503902D01*
G01Y530476D02*
Y524394D01*
G01X1160559Y507839D02*
Y526539D01*
G01X1160480Y508825D02*
Y507840D01*
G01Y526538D02*
Y525553D01*
G01X1160283Y525555D02*
Y530396D01*
G01Y503982D02*
Y508823D01*
G01X1160205Y524760D02*
Y525751D01*
G01Y508627D02*
Y509618D01*
G01X1160126Y504965D02*
Y503902D01*
G01Y530476D02*
Y529413D01*
G01X1159850Y503902D02*
Y504886D01*
G01Y530476D02*
Y529492D01*
G01X1159063Y504886D02*
Y503902D01*
G01Y530476D02*
Y529492D01*
G01X1159939Y525368D02*
X1159952Y524394D01*
G01X1160467Y509117D02*
X1160331Y515025D01*
G01X1160326Y514139D02*
X1160462Y508231D01*
G01X1159457Y577012D02*
X1179142D01*
G01Y582524D02*
Y577012D01*
G01X1175992Y582524D02*
Y577012D01*
G01X1162606Y582524D02*
Y577012D01*
G01X1159457Y582524D02*
Y577012D01*
G01X1206701D02*
X1226386D01*
G01X1183079D02*
X1202764D01*
G01X1226386Y582524D02*
Y577012D01*
G01X1223236Y582524D02*
Y577012D01*
G01X1209850Y582524D02*
Y577012D01*
G01X1206701Y582524D02*
Y577012D01*
G01X1202764Y582524D02*
Y577012D01*
G01X1199614Y582524D02*
Y577012D01*
G01X1186228Y582524D02*
Y577012D01*
G01X1183079Y582524D02*
Y577012D01*
G01X1184096Y507893D02*
X1184102Y507840D01*
G01X1184090Y508025D02*
X1184096Y507893D01*
G01X1184084Y508231D02*
X1184090Y508025D01*
G01X1184098Y508867D02*
X1184102Y508825D01*
G01X1184093Y508965D02*
X1184098Y508867D01*
G01X1184089Y509117D02*
X1184093Y508965D01*
G01X1183833Y524699D02*
X1183828Y524772D01*
G01X1183836Y524491D02*
X1183833Y524699D01*
G01X1183839Y524178D02*
X1183836Y524491D01*
G01X1183839Y523807D02*
Y524178D01*
G01X1183837Y525608D02*
X1183828Y525757D01*
G01X1183844Y525193D02*
X1183837Y525608D01*
G01X1183849Y524573D02*
X1183844Y525193D01*
G01X1183850Y523826D02*
X1183849Y524573D01*
G01Y509804D02*
X1183850Y510552D01*
G01X1183844Y509184D02*
X1183849Y509804D01*
G01X1183837Y508770D02*
X1183844Y509184D01*
G01X1183828Y508621D02*
X1183837Y508770D01*
G01X1183839Y510200D02*
Y510571D01*
G01X1183836Y509887D02*
X1183839Y510200D01*
G01X1183833Y509679D02*
X1183836Y509887D01*
G01X1183828Y509606D02*
X1183833Y509679D01*
G01X1184093Y525413D02*
X1184089Y525261D01*
G01X1184098Y525511D02*
X1184093Y525413D01*
G01X1184102Y525553D02*
X1184098Y525511D01*
G01X1185996Y508965D02*
X1186001Y509117D01*
G01X1185992Y508867D02*
X1185996Y508965D01*
G01X1185987Y508825D02*
X1185992Y508867D01*
G01X1188035Y525413D02*
X1188031Y525261D01*
G01X1188040Y525511D02*
X1188035Y525413D01*
G01X1188044Y525553D02*
X1188040Y525511D01*
G01X1189938Y508965D02*
X1189942Y509117D01*
G01X1189934Y508867D02*
X1189938Y508965D01*
G01X1189929Y508825D02*
X1189934Y508867D01*
G01X1191967Y525413D02*
X1191963Y525261D01*
G01X1191972Y525511D02*
X1191967Y525413D01*
G01X1191976Y525553D02*
X1191972Y525511D01*
G01X1184090Y526353D02*
X1184084Y526147D01*
G01X1184096Y526485D02*
X1184090Y526353D01*
G01X1184102Y526538D02*
X1184096Y526485D01*
G01X1188032Y526353D02*
X1188026Y526147D01*
G01X1188038Y526485D02*
X1188032Y526353D01*
G01X1188044Y526538D02*
X1188038Y526485D01*
G01X1186000Y508025D02*
X1186005Y508231D01*
G01X1185994Y507893D02*
X1186000Y508025D01*
G01X1185987Y507840D02*
X1185994Y507893D01*
G01X1191964Y526353D02*
X1191958Y526147D01*
G01X1191970Y526485D02*
X1191964Y526353D01*
G01X1191976Y526538D02*
X1191970Y526485D01*
G01X1189941Y508025D02*
X1189947Y508231D01*
G01X1189935Y507893D02*
X1189941Y508025D01*
G01X1189929Y507840D02*
X1189935Y507893D01*
G01X1186261Y524209D02*
X1186260Y523807D01*
G01X1186264Y524537D02*
X1186261Y524209D01*
G01X1186268Y524733D02*
X1186264Y524537D01*
G01X1186272Y524763D02*
X1186268Y524733D01*
G01X1187771Y510169D02*
X1187772Y510571D01*
G01X1187768Y509841D02*
X1187771Y510169D01*
G01X1187764Y509645D02*
X1187768Y509841D01*
G01X1187759Y509615D02*
X1187764Y509645D01*
G01X1194135Y524209D02*
X1194134Y523807D01*
G01X1194138Y524537D02*
X1194135Y524209D01*
G01X1194142Y524733D02*
X1194138Y524537D01*
G01X1194146Y524763D02*
X1194142Y524733D01*
G01X1183827Y524768D02*
Y524763D01*
G01X1183828Y524771D02*
X1183827Y524768D01*
G01X1183828Y524772D02*
Y524771D01*
G01X1191701Y524768D02*
Y524763D01*
G01X1191702Y524771D02*
X1191701Y524768D01*
G01X1191702Y524772D02*
Y524771D01*
G01X1190204Y509610D02*
X1190205Y509615D01*
G01X1190204Y509607D02*
Y509610D01*
G01X1190203Y509606D02*
X1190204Y509607D01*
G01X1199575Y524768D02*
Y524763D01*
G01X1199576Y524771D02*
X1199575Y524768D01*
G01X1199577Y524772D02*
X1199576Y524771D01*
G01X1183827Y525754D02*
Y525751D01*
G01X1183828Y525756D02*
X1183827Y525754D01*
G01X1183828Y525757D02*
Y525756D01*
G01X1191701Y525754D02*
Y525751D01*
G01X1191702Y525756D02*
X1191701Y525754D01*
G01X1191702Y525757D02*
Y525756D01*
G01X1199575Y525754D02*
Y525751D01*
G01X1199576Y525756D02*
X1199575Y525754D01*
G01X1199577Y525757D02*
X1199576Y525756D01*
G01X1190204Y508624D02*
X1190205Y508627D01*
G01X1190204Y508622D02*
Y508624D01*
G01X1190203Y508621D02*
X1190204Y508622D01*
G01X1183828Y509607D02*
Y509606D01*
G01X1183827Y509610D02*
X1183828Y509607D01*
G01X1183827Y509615D02*
Y509610D01*
G01X1190204Y524771D02*
X1190203Y524772D01*
G01X1190204Y524768D02*
Y524771D01*
G01X1190205Y524763D02*
X1190204Y524768D01*
G01X1191702Y509607D02*
Y509606D01*
G01X1191701Y509610D02*
X1191702Y509607D01*
G01X1191701Y509615D02*
Y509610D01*
G01X1198078Y524771D02*
X1198077Y524772D01*
G01X1198078Y524768D02*
Y524771D01*
G01X1198079Y524763D02*
X1198078Y524768D01*
G01X1199576Y509607D02*
X1199577Y509606D01*
G01X1199575Y509610D02*
X1199576Y509607D01*
G01X1199575Y509615D02*
Y509610D01*
G01X1186003Y526485D02*
X1185997Y526538D01*
G01X1186009Y526353D02*
X1186003Y526485D01*
G01X1186015Y526147D02*
X1186009Y526353D01*
G01X1188029Y507893D02*
X1188035Y507840D01*
G01X1188022Y508025D02*
X1188029Y507893D01*
G01X1188017Y508231D02*
X1188022Y508025D01*
G01X1189935Y526485D02*
X1189929Y526538D01*
G01X1189941Y526353D02*
X1189935Y526485D01*
G01X1189947Y526147D02*
X1189941Y526353D01*
G01X1191970Y507893D02*
X1191976Y507840D01*
G01X1191964Y508025D02*
X1191970Y507893D01*
G01X1191958Y508231D02*
X1191964Y508025D01*
G01X1193877Y526485D02*
X1193871Y526538D01*
G01X1193883Y526353D02*
X1193877Y526485D01*
G01X1193889Y526147D02*
X1193883Y526353D01*
G01X1195903Y507893D02*
X1195909Y507840D01*
G01X1195896Y508025D02*
X1195903Y507893D01*
G01X1195891Y508231D02*
X1195896Y508025D01*
G01X1197809Y526485D02*
X1197803Y526538D01*
G01X1197815Y526353D02*
X1197809Y526485D01*
G01X1197821Y526147D02*
X1197815Y526353D01*
G01X1199844Y507893D02*
X1199850Y507840D01*
G01X1199838Y508025D02*
X1199844Y507893D01*
G01X1199832Y508231D02*
X1199838Y508025D01*
G01X1201751Y526485D02*
X1201745Y526538D01*
G01X1201757Y526353D02*
X1201751Y526485D01*
G01X1201763Y526147D02*
X1201757Y526353D01*
G01X1203777Y507893D02*
X1203783Y507840D01*
G01X1203771Y508025D02*
X1203777Y507893D01*
G01X1203765Y508231D02*
X1203771Y508025D01*
G01X1205683Y526485D02*
X1205677Y526538D01*
G01X1205689Y526353D02*
X1205683Y526485D01*
G01X1205695Y526147D02*
X1205689Y526353D01*
G01X1207718Y507893D02*
X1207724Y507840D01*
G01X1207712Y508025D02*
X1207718Y507893D01*
G01X1207706Y508231D02*
X1207712Y508025D01*
G01X1186001Y525511D02*
X1185997Y525553D01*
G01X1186006Y525413D02*
X1186001Y525511D01*
G01X1186010Y525261D02*
X1186006Y525413D01*
G01X1188030Y508867D02*
X1188035Y508825D01*
G01X1188026Y508965D02*
X1188030Y508867D01*
G01X1188021Y509117D02*
X1188026Y508965D01*
G01X1189934Y525511D02*
X1189929Y525553D01*
G01X1189938Y525413D02*
X1189934Y525511D01*
G01X1189942Y525261D02*
X1189938Y525413D01*
G01X1191972Y508867D02*
X1191976Y508825D01*
G01X1191967Y508965D02*
X1191972Y508867D01*
G01X1191963Y509117D02*
X1191967Y508965D01*
G01X1193875Y525511D02*
X1193871Y525553D01*
G01X1193880Y525413D02*
X1193875Y525511D01*
G01X1193884Y525261D02*
X1193880Y525413D01*
G01X1195904Y508867D02*
X1195909Y508825D01*
G01X1195900Y508965D02*
X1195904Y508867D01*
G01X1195896Y509117D02*
X1195900Y508965D01*
G01X1197808Y525511D02*
X1197803Y525553D01*
G01X1197812Y525413D02*
X1197808Y525511D01*
G01X1197816Y525261D02*
X1197812Y525413D01*
G01X1199846Y508867D02*
X1199850Y508825D01*
G01X1199841Y508965D02*
X1199846Y508867D01*
G01X1199837Y509117D02*
X1199841Y508965D01*
G01X1201749Y525511D02*
X1201745Y525553D01*
G01X1201754Y525413D02*
X1201749Y525511D01*
G01X1201758Y525261D02*
X1201754Y525413D01*
G01X1203778Y508867D02*
X1203783Y508825D01*
G01X1203774Y508965D02*
X1203778Y508867D01*
G01X1203770Y509117D02*
X1203774Y508965D01*
G01X1205682Y525511D02*
X1205677Y525553D01*
G01X1205686Y525413D02*
X1205682Y525511D01*
G01X1205690Y525261D02*
X1205686Y525413D01*
G01X1207720Y508867D02*
X1207724Y508825D01*
G01X1207715Y508965D02*
X1207720Y508867D01*
G01X1207711Y509117D02*
X1207715Y508965D01*
G01X1186258Y509645D02*
X1186263Y509615D01*
G01X1186254Y509841D02*
X1186258Y509645D01*
G01X1186251Y510169D02*
X1186254Y509841D01*
G01X1186250Y510571D02*
X1186251Y510169D01*
G01X1187773Y524733D02*
X1187769Y524763D01*
G01X1187777Y524537D02*
X1187773Y524733D01*
G01X1187780Y524209D02*
X1187777Y524537D01*
G01X1187781Y523807D02*
X1187780Y524209D01*
G01X1194132Y509645D02*
X1194137Y509615D01*
G01X1194128Y509841D02*
X1194132Y509645D01*
G01X1194125Y510169D02*
X1194128Y509841D01*
G01X1194124Y510571D02*
X1194125Y510169D01*
G01X1195647Y524733D02*
X1195643Y524763D01*
G01X1195651Y524537D02*
X1195647Y524733D01*
G01X1195654Y524209D02*
X1195651Y524537D01*
G01X1195655Y523807D02*
X1195654Y524209D01*
G01X1202006Y509645D02*
X1202011Y509615D01*
G01X1202002Y509841D02*
X1202006Y509645D01*
G01X1201999Y510169D02*
X1202002Y509841D01*
G01X1201998Y510571D02*
X1201999Y510169D01*
G01X1203521Y524733D02*
X1203517Y524763D01*
G01X1203525Y524537D02*
X1203521Y524733D01*
G01X1203528Y524209D02*
X1203525Y524537D01*
G01X1203529Y523807D02*
X1203528Y524209D01*
G01X1209880Y509645D02*
X1209885Y509615D01*
G01X1209876Y509841D02*
X1209880Y509645D01*
G01X1209873Y510169D02*
X1209876Y509841D01*
G01X1209872Y510571D02*
X1209873Y510169D01*
G01X1190195Y508770D02*
X1190203Y508621D01*
G01X1190188Y509184D02*
X1190195Y508770D01*
G01X1190183Y509804D02*
X1190188Y509184D01*
G01X1190181Y510552D02*
X1190183Y509804D01*
G01X1190199Y509679D02*
X1190203Y509606D01*
G01X1190195Y509887D02*
X1190199Y509679D01*
G01X1190193Y510200D02*
X1190195Y509887D01*
G01X1190192Y510571D02*
X1190193Y510200D01*
G01X1191707Y524699D02*
X1191702Y524772D01*
G01X1191710Y524491D02*
X1191707Y524699D01*
G01X1191713Y524178D02*
X1191710Y524491D01*
G01X1191713Y523807D02*
Y524178D01*
G01X1191711Y525608D02*
X1191702Y525757D01*
G01X1191718Y525193D02*
X1191711Y525608D01*
G01X1191723Y524573D02*
X1191718Y525193D01*
G01X1191724Y523826D02*
X1191723Y524573D01*
G01X1198069Y508770D02*
X1198077Y508621D01*
G01X1198062Y509184D02*
X1198069Y508770D01*
G01X1198057Y509804D02*
X1198062Y509184D01*
G01X1198055Y510552D02*
X1198057Y509804D01*
G01X1198073Y509679D02*
X1198077Y509606D01*
G01X1198069Y509887D02*
X1198073Y509679D01*
G01X1198067Y510200D02*
X1198069Y509887D01*
G01X1198066Y510571D02*
X1198067Y510200D01*
G01X1199581Y524699D02*
X1199577Y524772D01*
G01X1199584Y524491D02*
X1199581Y524699D01*
G01X1199587Y524178D02*
X1199584Y524491D01*
G01X1199587Y523807D02*
Y524178D01*
G01X1199585Y525608D02*
X1199577Y525757D01*
G01X1199592Y525193D02*
X1199585Y525608D01*
G01X1199597Y524573D02*
X1199592Y525193D01*
G01X1199598Y523826D02*
X1199597Y524573D01*
G01X1205943Y508770D02*
X1205951Y508621D01*
G01X1205936Y509184D02*
X1205943Y508770D01*
G01X1205931Y509804D02*
X1205936Y509184D01*
G01X1205929Y510552D02*
X1205931Y509804D01*
G01X1205947Y509679D02*
X1205951Y509606D01*
G01X1205943Y509887D02*
X1205947Y509679D01*
G01X1205941Y510200D02*
X1205943Y509887D01*
G01X1205940Y510571D02*
X1205941Y510200D01*
G01X1207455Y524699D02*
X1207451Y524772D01*
G01X1207458Y524491D02*
X1207455Y524699D01*
G01X1207461Y524178D02*
X1207458Y524491D01*
G01X1207461Y523807D02*
Y524178D01*
G01X1207459Y525608D02*
X1207451Y525757D01*
G01X1207466Y525193D02*
X1207459Y525608D01*
G01X1207471Y524573D02*
X1207466Y525193D01*
G01X1207472Y523826D02*
X1207471Y524573D01*
G01X1190183D02*
X1190181Y523826D01*
G01X1190188Y525193D02*
X1190183Y524573D01*
G01X1190195Y525608D02*
X1190188Y525193D01*
G01X1190203Y525757D02*
X1190195Y525608D01*
G01X1191723Y509804D02*
X1191724Y510552D01*
G01X1191718Y509184D02*
X1191723Y509804D01*
G01X1191711Y508770D02*
X1191718Y509184D01*
G01X1191702Y508621D02*
X1191711Y508770D01*
G01X1198057Y524573D02*
X1198055Y523826D01*
G01X1198062Y525193D02*
X1198057Y524573D01*
G01X1198069Y525608D02*
X1198062Y525193D01*
G01X1198077Y525757D02*
X1198069Y525608D01*
G01X1199597Y509804D02*
X1199598Y510552D01*
G01X1199592Y509184D02*
X1199597Y509804D01*
G01X1199585Y508770D02*
X1199592Y509184D01*
G01X1199577Y508621D02*
X1199585Y508770D01*
G01X1205931Y524573D02*
X1205929Y523826D01*
G01X1205936Y525193D02*
X1205931Y524573D01*
G01X1205943Y525608D02*
X1205936Y525193D01*
G01X1205951Y525757D02*
X1205943Y525608D01*
G01X1207471Y509804D02*
X1207472Y510552D01*
G01X1207466Y509184D02*
X1207471Y509804D01*
G01X1207459Y508770D02*
X1207466Y509184D01*
G01X1207451Y508621D02*
X1207459Y508770D01*
G01X1213805Y524573D02*
X1213803Y523826D01*
G01X1213810Y525193D02*
X1213805Y524573D01*
G01X1213817Y525608D02*
X1213810Y525193D01*
G01X1213825Y525757D02*
X1213817Y525608D01*
G01X1190193Y524178D02*
X1190192Y523807D01*
G01X1190195Y524491D02*
X1190193Y524178D01*
G01X1190199Y524699D02*
X1190195Y524491D01*
G01X1190203Y524772D02*
X1190199Y524699D01*
G01X1191713Y510200D02*
Y510571D01*
G01X1191710Y509887D02*
X1191713Y510200D01*
G01X1191707Y509679D02*
X1191710Y509887D01*
G01X1191702Y509606D02*
X1191707Y509679D01*
G01X1198067Y524178D02*
X1198066Y523807D01*
G01X1198069Y524491D02*
X1198067Y524178D01*
G01X1198073Y524699D02*
X1198069Y524491D01*
G01X1198077Y524772D02*
X1198073Y524699D01*
G01X1199587Y510200D02*
Y510571D01*
G01X1199584Y509887D02*
X1199587Y510200D01*
G01X1199581Y509679D02*
X1199584Y509887D01*
G01X1199577Y509606D02*
X1199581Y509679D01*
G01X1205941Y524178D02*
X1205940Y523807D01*
G01X1205943Y524491D02*
X1205941Y524178D01*
G01X1205947Y524699D02*
X1205943Y524491D01*
G01X1205951Y524772D02*
X1205947Y524699D01*
G01X1207461Y510200D02*
Y510571D01*
G01X1207458Y509887D02*
X1207461Y510200D01*
G01X1207455Y509679D02*
X1207458Y509887D01*
G01X1207451Y509606D02*
X1207455Y509679D01*
G01X1213815Y524178D02*
X1213814Y523807D01*
G01X1213817Y524491D02*
X1213815Y524178D01*
G01X1213821Y524699D02*
X1213817Y524491D01*
G01X1213825Y524772D02*
X1213821Y524699D01*
G01X1193870Y508965D02*
X1193875Y509117D01*
G01X1193866Y508867D02*
X1193870Y508965D01*
G01X1193861Y508825D02*
X1193866Y508867D01*
G01X1195909Y525413D02*
X1195905Y525261D01*
G01X1195914Y525511D02*
X1195909Y525413D01*
G01X1195918Y525553D02*
X1195914Y525511D01*
G01X1197812Y508965D02*
X1197816Y509117D01*
G01X1197808Y508867D02*
X1197812Y508965D01*
G01X1197803Y508825D02*
X1197808Y508867D01*
G01X1199841Y525413D02*
X1199837Y525261D01*
G01X1199846Y525511D02*
X1199841Y525413D01*
G01X1199850Y525553D02*
X1199846Y525511D01*
G01X1201744Y508965D02*
X1201749Y509117D01*
G01X1201740Y508867D02*
X1201744Y508965D01*
G01X1201735Y508825D02*
X1201740Y508867D01*
G01X1203783Y525413D02*
X1203779Y525261D01*
G01X1203788Y525511D02*
X1203783Y525413D01*
G01X1203792Y525553D02*
X1203788Y525511D01*
G01X1205686Y508965D02*
X1205690Y509117D01*
G01X1205682Y508867D02*
X1205686Y508965D01*
G01X1205677Y508825D02*
X1205682Y508867D01*
G01X1207715Y525413D02*
X1207711Y525261D01*
G01X1207720Y525511D02*
X1207715Y525413D01*
G01X1207724Y525553D02*
X1207720Y525511D01*
G01X1209618Y508965D02*
X1209623Y509117D01*
G01X1209614Y508867D02*
X1209618Y508965D01*
G01X1209610Y508825D02*
X1209614Y508867D01*
G01X1211657Y525413D02*
X1211653Y525261D01*
G01X1211662Y525511D02*
X1211657Y525413D01*
G01X1211666Y525553D02*
X1211662Y525511D01*
G01X1213560Y508965D02*
X1213564Y509117D01*
G01X1213556Y508867D02*
X1213560Y508965D01*
G01X1213551Y508825D02*
X1213556Y508867D01*
G01X1215589Y525413D02*
X1215585Y525261D01*
G01X1215594Y525511D02*
X1215589Y525413D01*
G01X1215598Y525553D02*
X1215594Y525511D01*
G01X1195906Y526353D02*
X1195900Y526147D01*
G01X1195912Y526485D02*
X1195906Y526353D01*
G01X1195918Y526538D02*
X1195912Y526485D01*
G01X1193874Y508025D02*
X1193879Y508231D01*
G01X1193868Y507893D02*
X1193874Y508025D01*
G01X1193861Y507840D02*
X1193868Y507893D01*
G01X1199838Y526353D02*
X1199832Y526147D01*
G01X1199844Y526485D02*
X1199838Y526353D01*
G01X1199850Y526538D02*
X1199844Y526485D01*
G01X1197815Y508025D02*
X1197821Y508231D01*
G01X1197809Y507893D02*
X1197815Y508025D01*
G01X1197803Y507840D02*
X1197809Y507893D01*
G01X1203780Y526353D02*
X1203774Y526147D01*
G01X1203786Y526485D02*
X1203780Y526353D01*
G01X1203792Y526538D02*
X1203786Y526485D01*
G01X1201748Y508025D02*
X1201753Y508231D01*
G01X1201742Y507893D02*
X1201748Y508025D01*
G01X1201735Y507840D02*
X1201742Y507893D01*
G01X1207712Y526353D02*
X1207706Y526147D01*
G01X1207718Y526485D02*
X1207712Y526353D01*
G01X1207724Y526538D02*
X1207718Y526485D01*
G01X1205689Y508025D02*
X1205695Y508231D01*
G01X1205683Y507893D02*
X1205689Y508025D01*
G01X1205677Y507840D02*
X1205683Y507893D01*
G01X1211654Y526353D02*
X1211648Y526147D01*
G01X1211660Y526485D02*
X1211654Y526353D01*
G01X1211666Y526538D02*
X1211660Y526485D01*
G01X1209622Y508025D02*
X1209627Y508231D01*
G01X1209616Y507893D02*
X1209622Y508025D01*
G01X1209610Y507840D02*
X1209616Y507893D01*
G01X1215586Y526353D02*
X1215580Y526147D01*
G01X1215592Y526485D02*
X1215586Y526353D01*
G01X1215598Y526538D02*
X1215592Y526485D01*
G01X1213563Y508025D02*
X1213569Y508231D01*
G01X1213557Y507893D02*
X1213563Y508025D01*
G01X1213551Y507840D02*
X1213557Y507893D01*
G01X1195645Y510169D02*
X1195646Y510571D01*
G01X1195642Y509841D02*
X1195645Y510169D01*
G01X1195638Y509645D02*
X1195642Y509841D01*
G01X1195633Y509615D02*
X1195638Y509645D01*
G01X1202009Y524209D02*
X1202008Y523807D01*
G01X1202012Y524537D02*
X1202009Y524209D01*
G01X1202016Y524733D02*
X1202012Y524537D01*
G01X1202020Y524763D02*
X1202016Y524733D01*
G01X1203519Y510169D02*
X1203520Y510571D01*
G01X1203516Y509841D02*
X1203519Y510169D01*
G01X1203512Y509645D02*
X1203516Y509841D01*
G01X1203507Y509615D02*
X1203512Y509645D01*
G01X1209883Y524209D02*
X1209882Y523807D01*
G01X1209886Y524537D02*
X1209883Y524209D01*
G01X1209890Y524733D02*
X1209886Y524537D01*
G01X1209894Y524763D02*
X1209890Y524733D01*
G01X1211393Y510169D02*
X1211394Y510571D01*
G01X1211390Y509841D02*
X1211393Y510169D01*
G01X1211386Y509645D02*
X1211390Y509841D01*
G01X1211381Y509615D02*
X1211386Y509645D01*
G01X1217757Y524209D02*
X1217756Y523807D01*
G01X1217760Y524537D02*
X1217757Y524209D01*
G01X1217764Y524733D02*
X1217760Y524537D01*
G01X1217768Y524763D02*
X1217764Y524733D01*
G01X1198078Y509610D02*
X1198079Y509615D01*
G01X1198078Y509607D02*
Y509610D01*
G01X1198077Y509606D02*
X1198078Y509607D01*
G01X1207450Y524768D02*
X1207449Y524763D01*
G01X1207450Y524771D02*
Y524768D01*
G01X1207451Y524772D02*
X1207450Y524771D01*
G01X1205952Y509610D02*
X1205953Y509615D01*
G01X1205952Y509607D02*
Y509610D01*
G01X1205951Y509606D02*
X1205952Y509607D01*
G01X1215324Y524768D02*
X1215323Y524763D01*
G01X1215324Y524771D02*
Y524768D01*
G01X1215325Y524772D02*
X1215324Y524771D01*
G01X1213826Y509610D02*
X1213827Y509615D01*
G01X1213826Y509607D02*
Y509610D01*
G01X1213825Y509606D02*
X1213826Y509607D01*
G01X1223198Y524768D02*
X1223197Y524763D01*
G01X1223198Y524771D02*
Y524768D01*
G01X1223199Y524772D02*
X1223198Y524771D01*
G01X1221700Y509610D02*
X1221701Y509615D01*
G01X1221700Y509607D02*
Y509610D01*
G01X1221699Y509606D02*
X1221700Y509607D01*
G01X1207449Y525754D02*
Y525751D01*
G01X1207450Y525756D02*
X1207449Y525754D01*
G01X1207451Y525757D02*
X1207450Y525756D01*
G01X1198078Y508624D02*
X1198079Y508627D01*
G01X1198078Y508622D02*
Y508624D01*
G01X1198077Y508621D02*
X1198078Y508622D01*
G01X1215323Y525754D02*
Y525751D01*
G01X1215324Y525756D02*
X1215323Y525754D01*
G01X1215325Y525757D02*
X1215324Y525756D01*
G01X1205952Y508624D02*
X1205953Y508627D01*
G01X1205952Y508622D02*
Y508624D01*
G01X1205951Y508621D02*
X1205952Y508622D01*
G01X1223197Y525754D02*
Y525751D01*
G01X1223198Y525756D02*
X1223197Y525754D01*
G01X1223199Y525757D02*
X1223198Y525756D01*
G01X1213826Y508624D02*
X1213827Y508627D01*
G01X1213826Y508622D02*
Y508624D01*
G01X1213825Y508621D02*
X1213826Y508622D01*
G01X1221700Y508624D02*
X1221701Y508627D01*
G01X1221700Y508622D02*
Y508624D01*
G01X1221699Y508621D02*
X1221700Y508622D01*
G01X1183828D02*
Y508621D01*
G01X1183827Y508624D02*
X1183828Y508622D01*
G01X1183827Y508627D02*
Y508624D01*
G01X1191702Y508622D02*
Y508621D01*
G01X1191701Y508624D02*
X1191702Y508622D01*
G01X1191701Y508627D02*
Y508624D01*
G01X1190204Y525756D02*
X1190203Y525757D01*
G01X1190204Y525754D02*
Y525756D01*
G01X1190205Y525751D02*
X1190204Y525754D01*
G01X1199576Y508622D02*
X1199577Y508621D01*
G01X1199575Y508624D02*
X1199576Y508622D01*
G01X1199575Y508627D02*
Y508624D01*
G01X1205952Y524771D02*
X1205951Y524772D01*
G01X1205952Y524768D02*
Y524771D01*
G01X1205953Y524763D02*
X1205952Y524768D01*
G01X1207450Y509607D02*
X1207451Y509606D01*
G01X1207450Y509610D02*
Y509607D01*
G01X1207449Y509615D02*
X1207450Y509610D01*
G01X1213826Y524771D02*
X1213825Y524772D01*
G01X1213826Y524768D02*
Y524771D01*
G01X1213827Y524763D02*
X1213826Y524768D01*
G01X1215324Y509607D02*
X1215325Y509606D01*
G01X1215324Y509610D02*
Y509607D01*
G01X1215323Y509615D02*
X1215324Y509610D01*
G01X1221700Y524771D02*
X1221699Y524772D01*
G01X1221700Y524768D02*
Y524771D01*
G01X1221701Y524763D02*
X1221700Y524768D01*
G01X1223198Y509607D02*
X1223199Y509606D01*
G01X1223198Y509610D02*
Y509607D01*
G01X1223197Y509615D02*
X1223198Y509610D01*
G01X1209625Y526485D02*
X1209619Y526538D01*
G01X1209631Y526353D02*
X1209625Y526485D01*
G01X1209637Y526147D02*
X1209631Y526353D01*
G01X1211651Y507893D02*
X1211657Y507840D01*
G01X1211645Y508025D02*
X1211651Y507893D01*
G01X1211639Y508231D02*
X1211645Y508025D01*
G01X1213557Y526485D02*
X1213551Y526538D01*
G01X1213563Y526353D02*
X1213557Y526485D01*
G01X1213569Y526147D02*
X1213563Y526353D01*
G01X1215592Y507893D02*
X1215598Y507840D01*
G01X1215586Y508025D02*
X1215592Y507893D01*
G01X1215580Y508231D02*
X1215586Y508025D01*
G01X1217499Y526485D02*
X1217493Y526538D01*
G01X1217505Y526353D02*
X1217499Y526485D01*
G01X1217511Y526147D02*
X1217505Y526353D01*
G01X1219525Y507893D02*
X1219531Y507840D01*
G01X1219519Y508025D02*
X1219525Y507893D01*
G01X1219513Y508231D02*
X1219519Y508025D01*
G01X1221431Y526485D02*
X1221425Y526538D01*
G01X1221437Y526353D02*
X1221431Y526485D01*
G01X1221443Y526147D02*
X1221437Y526353D01*
G01X1223466Y507893D02*
X1223472Y507840D01*
G01X1223460Y508025D02*
X1223466Y507893D01*
G01X1223454Y508231D02*
X1223460Y508025D01*
G01X1225373Y526485D02*
X1225367Y526538D01*
G01X1225379Y526353D02*
X1225373Y526485D01*
G01X1225385Y526147D02*
X1225379Y526353D01*
G01X1227399Y507893D02*
X1227405Y507840D01*
G01X1227393Y508025D02*
X1227399Y507893D01*
G01X1227387Y508231D02*
X1227393Y508025D01*
G01X1209623Y525511D02*
X1209619Y525553D01*
G01X1209628Y525413D02*
X1209623Y525511D01*
G01X1209632Y525261D02*
X1209628Y525413D01*
G01X1211652Y508867D02*
X1211657Y508825D01*
G01X1211648Y508965D02*
X1211652Y508867D01*
G01X1211644Y509117D02*
X1211648Y508965D01*
G01X1213556Y525511D02*
X1213551Y525553D01*
G01X1213560Y525413D02*
X1213556Y525511D01*
G01X1213564Y525261D02*
X1213560Y525413D01*
G01X1215594Y508867D02*
X1215598Y508825D01*
G01X1215589Y508965D02*
X1215594Y508867D01*
G01X1215585Y509117D02*
X1215589Y508965D01*
G01X1217497Y525511D02*
X1217493Y525553D01*
G01X1217502Y525413D02*
X1217497Y525511D01*
G01X1217506Y525261D02*
X1217502Y525413D01*
G01X1219526Y508867D02*
X1219531Y508825D01*
G01X1219522Y508965D02*
X1219526Y508867D01*
G01X1219518Y509117D02*
X1219522Y508965D01*
G01X1221430Y525511D02*
X1221425Y525553D01*
G01X1221434Y525413D02*
X1221430Y525511D01*
G01X1221438Y525261D02*
X1221434Y525413D01*
G01X1223468Y508867D02*
X1223472Y508825D01*
G01X1223463Y508965D02*
X1223468Y508867D01*
G01X1223459Y509117D02*
X1223463Y508965D01*
G01X1225371Y525511D02*
X1225367Y525553D01*
G01X1225376Y525413D02*
X1225371Y525511D01*
G01X1225380Y525261D02*
X1225376Y525413D01*
G01X1227400Y508867D02*
X1227405Y508825D01*
G01X1227396Y508965D02*
X1227400Y508867D01*
G01X1227392Y509117D02*
X1227396Y508965D01*
G01X1211395Y524733D02*
X1211391Y524763D01*
G01X1211399Y524537D02*
X1211395Y524733D01*
G01X1211402Y524209D02*
X1211399Y524537D01*
G01X1211403Y523807D02*
X1211402Y524209D01*
G01X1217754Y509645D02*
X1217759Y509615D01*
G01X1217750Y509841D02*
X1217754Y509645D01*
G01X1217747Y510169D02*
X1217750Y509841D01*
G01X1217746Y510571D02*
X1217747Y510169D01*
G01X1219269Y524733D02*
X1219265Y524763D01*
G01X1219273Y524537D02*
X1219269Y524733D01*
G01X1219276Y524209D02*
X1219273Y524537D01*
G01X1219277Y523807D02*
X1219276Y524209D01*
G01X1225628Y509645D02*
X1225633Y509615D01*
G01X1225624Y509841D02*
X1225628Y509645D01*
G01X1225621Y510169D02*
X1225624Y509841D01*
G01X1225620Y510571D02*
X1225621Y510169D01*
G01X1227143Y524733D02*
X1227139Y524763D01*
G01X1227147Y524537D02*
X1227143Y524733D01*
G01X1227150Y524209D02*
X1227147Y524537D01*
G01X1227151Y523807D02*
X1227150Y524209D01*
G01X1213817Y508770D02*
X1213825Y508621D01*
G01X1213810Y509184D02*
X1213817Y508770D01*
G01X1213805Y509804D02*
X1213810Y509184D01*
G01X1213803Y510552D02*
X1213805Y509804D01*
G01X1213821Y509679D02*
X1213825Y509606D01*
G01X1213817Y509887D02*
X1213821Y509679D01*
G01X1213815Y510200D02*
X1213817Y509887D01*
G01X1213814Y510571D02*
X1213815Y510200D01*
G01X1215329Y524699D02*
X1215325Y524772D01*
G01X1215332Y524491D02*
X1215329Y524699D01*
G01X1215335Y524178D02*
X1215332Y524491D01*
G01X1215336Y523807D02*
X1215335Y524178D01*
G01X1215333Y525608D02*
X1215325Y525757D01*
G01X1215340Y525193D02*
X1215333Y525608D01*
G01X1215345Y524573D02*
X1215340Y525193D01*
G01X1215346Y523826D02*
X1215345Y524573D01*
G01X1221691Y508770D02*
X1221699Y508621D01*
G01X1221684Y509184D02*
X1221691Y508770D01*
G01X1221679Y509804D02*
X1221684Y509184D01*
G01X1221677Y510552D02*
X1221679Y509804D01*
G01X1221695Y509679D02*
X1221699Y509606D01*
G01X1221691Y509887D02*
X1221695Y509679D01*
G01X1221689Y510200D02*
X1221691Y509887D01*
G01X1221688Y510571D02*
X1221689Y510200D01*
G01X1223203Y524699D02*
X1223199Y524772D01*
G01X1223206Y524491D02*
X1223203Y524699D01*
G01X1223209Y524178D02*
X1223206Y524491D01*
G01X1223210Y523807D02*
X1223209Y524178D01*
G01X1223207Y525608D02*
X1223199Y525757D01*
G01X1223214Y525193D02*
X1223207Y525608D01*
G01X1223219Y524573D02*
X1223214Y525193D01*
G01X1223220Y523826D02*
X1223219Y524573D01*
G01X1215345Y509804D02*
X1215346Y510552D01*
G01X1215340Y509184D02*
X1215345Y509804D01*
G01X1215333Y508770D02*
X1215340Y509184D01*
G01X1215325Y508621D02*
X1215333Y508770D01*
G01X1221679Y524573D02*
X1221677Y523826D01*
G01X1221684Y525193D02*
X1221679Y524573D01*
G01X1221691Y525608D02*
X1221684Y525193D01*
G01X1221699Y525757D02*
X1221691Y525608D01*
G01X1223219Y509804D02*
X1223220Y510552D01*
G01X1223214Y509184D02*
X1223219Y509804D01*
G01X1223207Y508770D02*
X1223214Y509184D01*
G01X1223199Y508621D02*
X1223207Y508770D01*
G01X1215335Y510200D02*
X1215336Y510571D01*
G01X1215332Y509887D02*
X1215335Y510200D01*
G01X1215329Y509679D02*
X1215332Y509887D01*
G01X1215325Y509606D02*
X1215329Y509679D01*
G01X1221689Y524178D02*
X1221688Y523807D01*
G01X1221691Y524491D02*
X1221689Y524178D01*
G01X1221695Y524699D02*
X1221691Y524491D01*
G01X1221699Y524772D02*
X1221695Y524699D01*
G01X1223209Y510200D02*
X1223210Y510571D01*
G01X1223206Y509887D02*
X1223209Y510200D01*
G01X1223203Y509679D02*
X1223206Y509887D01*
G01X1223199Y509606D02*
X1223203Y509679D01*
G01X1217492Y508965D02*
X1217497Y509117D01*
G01X1217488Y508867D02*
X1217492Y508965D01*
G01X1217484Y508825D02*
X1217488Y508867D01*
G01X1219531Y525413D02*
X1219527Y525261D01*
G01X1219536Y525511D02*
X1219531Y525413D01*
G01X1219540Y525553D02*
X1219536Y525511D01*
G01X1221434Y508965D02*
X1221438Y509117D01*
G01X1221430Y508867D02*
X1221434Y508965D01*
G01X1221425Y508825D02*
X1221430Y508867D01*
G01X1223463Y525413D02*
X1223459Y525261D01*
G01X1223468Y525511D02*
X1223463Y525413D01*
G01X1223472Y525553D02*
X1223468Y525511D01*
G01X1225366Y508965D02*
X1225371Y509117D01*
G01X1225362Y508867D02*
X1225366Y508965D01*
G01X1225358Y508825D02*
X1225362Y508867D01*
G01X1227405Y525413D02*
X1227401Y525261D01*
G01X1227410Y525511D02*
X1227405Y525413D01*
G01X1227414Y525553D02*
X1227410Y525511D01*
G01X1219528Y526353D02*
X1219522Y526147D01*
G01X1219534Y526485D02*
X1219528Y526353D01*
G01X1219540Y526538D02*
X1219534Y526485D01*
G01X1217496Y508025D02*
X1217502Y508231D01*
G01X1217490Y507893D02*
X1217496Y508025D01*
G01X1217484Y507840D02*
X1217490Y507893D01*
G01X1223460Y526353D02*
X1223454Y526147D01*
G01X1223466Y526485D02*
X1223460Y526353D01*
G01X1223472Y526538D02*
X1223466Y526485D01*
G01X1221437Y508025D02*
X1221443Y508231D01*
G01X1221431Y507893D02*
X1221437Y508025D01*
G01X1221425Y507840D02*
X1221431Y507893D01*
G01X1227402Y526353D02*
X1227396Y526147D01*
G01X1227408Y526485D02*
X1227402Y526353D01*
G01X1227414Y526538D02*
X1227408Y526485D01*
G01X1225370Y508025D02*
X1225376Y508231D01*
G01X1225364Y507893D02*
X1225370Y508025D01*
G01X1225358Y507840D02*
X1225364Y507893D01*
G01X1219267Y510169D02*
X1219268Y510571D01*
G01X1219264Y509841D02*
X1219267Y510169D01*
G01X1219260Y509645D02*
X1219264Y509841D01*
G01X1219255Y509615D02*
X1219260Y509645D01*
G01X1225631Y524209D02*
X1225630Y523807D01*
G01X1225634Y524537D02*
X1225631Y524209D01*
G01X1225638Y524733D02*
X1225634Y524537D01*
G01X1225642Y524763D02*
X1225638Y524733D01*
G01X1227141Y510169D02*
X1227142Y510571D01*
G01X1227138Y509841D02*
X1227141Y510169D01*
G01X1227134Y509645D02*
X1227138Y509841D01*
G01X1227129Y509615D02*
X1227134Y509645D01*
G01X1198078Y525756D02*
X1198077Y525757D01*
G01X1198078Y525754D02*
Y525756D01*
G01X1198079Y525751D02*
X1198078Y525754D01*
G01X1207450Y508622D02*
X1207451Y508621D01*
G01X1207449Y508624D02*
X1207450Y508622D01*
G01X1207449Y508627D02*
Y508624D01*
G01X1205952Y525756D02*
X1205951Y525757D01*
G01X1205952Y525754D02*
Y525756D01*
G01X1205953Y525751D02*
X1205952Y525754D01*
G01X1215324Y508622D02*
X1215325Y508621D01*
G01X1215323Y508624D02*
X1215324Y508622D01*
G01X1215323Y508627D02*
Y508624D01*
G01X1213826Y525756D02*
X1213825Y525757D01*
G01X1213826Y525754D02*
Y525756D01*
G01X1213827Y525751D02*
X1213826Y525754D01*
G01X1223198Y508622D02*
X1223199Y508621D01*
G01X1223197Y508624D02*
X1223198Y508622D01*
G01X1223197Y508627D02*
Y508624D01*
G01X1221700Y525756D02*
X1221699Y525757D01*
G01X1221700Y525754D02*
Y525756D01*
G01X1221701Y525751D02*
X1221700Y525754D01*
G01X1184117Y507839D02*
X1184102Y507840D01*
G01X1184132Y507839D02*
X1184117D01*
G01X1184147D02*
X1184132D01*
G01X1188050D02*
X1188035Y507840D01*
G01X1188065Y507839D02*
X1188050D01*
G01X1188080D02*
X1188065D01*
G01X1191991D02*
X1191976Y507840D01*
G01X1192006Y507839D02*
X1191991D01*
G01X1192021D02*
X1192006D01*
G01X1195924D02*
X1195909Y507840D01*
G01X1195939Y507839D02*
X1195924D01*
G01X1195954D02*
X1195939D01*
G01X1199865D02*
X1199850Y507840D01*
G01X1199880Y507839D02*
X1199865D01*
G01X1199895D02*
X1199880D01*
G01X1203798D02*
X1203783Y507840D01*
G01X1203813Y507839D02*
X1203798D01*
G01X1203828D02*
X1203813D01*
G01X1207739D02*
X1207724Y507840D01*
G01X1207754Y507839D02*
X1207739D01*
G01X1207769D02*
X1207754D01*
G01X1211672D02*
X1211657Y507840D01*
G01X1211687Y507839D02*
X1211672D01*
G01X1211702D02*
X1211687D01*
G01X1215613D02*
X1215598Y507840D01*
G01X1215628Y507839D02*
X1215613D01*
G01X1215643D02*
X1215628D01*
G01X1219546D02*
X1219531Y507840D01*
G01X1219561Y507839D02*
X1219546D01*
G01X1219576D02*
X1219561D01*
G01X1223487D02*
X1223472Y507840D01*
G01X1223502Y507839D02*
X1223487D01*
G01X1223517D02*
X1223502D01*
G01X1227420D02*
X1227405Y507840D01*
G01X1227435Y507839D02*
X1227420D01*
G01X1227450D02*
X1227435D01*
G01X1184117Y508824D02*
X1184102Y508825D01*
G01X1184132Y508823D02*
X1184117Y508824D01*
G01X1184147Y508823D02*
X1184132D01*
G01X1188050Y508824D02*
X1188035Y508825D01*
G01X1188065Y508823D02*
X1188050Y508824D01*
G01X1188080Y508823D02*
X1188065D01*
G01X1191991Y508824D02*
X1191976Y508825D01*
G01X1192006Y508823D02*
X1191991Y508824D01*
G01X1192021Y508823D02*
X1192006D01*
G01X1195924Y508824D02*
X1195909Y508825D01*
G01X1195939Y508823D02*
X1195924Y508824D01*
G01X1195954Y508823D02*
X1195939D01*
G01X1199865Y508824D02*
X1199850Y508825D01*
G01X1199880Y508823D02*
X1199865Y508824D01*
G01X1199895Y508823D02*
X1199880D01*
G01X1203798Y508824D02*
X1203783Y508825D01*
G01X1203813Y508823D02*
X1203798Y508824D01*
G01X1203828Y508823D02*
X1203813D01*
G01X1207739Y508824D02*
X1207724Y508825D01*
G01X1207754Y508823D02*
X1207739Y508824D01*
G01X1207769Y508823D02*
X1207754D01*
G01X1211672Y508824D02*
X1211657Y508825D01*
G01X1211687Y508823D02*
X1211672Y508824D01*
G01X1211702Y508823D02*
X1211687D01*
G01X1215613Y508824D02*
X1215598Y508825D01*
G01X1215628Y508823D02*
X1215613Y508824D01*
G01X1215643Y508823D02*
X1215628D01*
G01X1219546Y508824D02*
X1219531Y508825D01*
G01X1219561Y508823D02*
X1219546Y508824D01*
G01X1219576Y508823D02*
X1219561D01*
G01X1223487Y508824D02*
X1223472Y508825D01*
G01X1223502Y508823D02*
X1223487Y508824D01*
G01X1223517Y508823D02*
X1223502D01*
G01X1227435D02*
X1227450D01*
G01X1227420Y508824D02*
X1227435Y508823D01*
G01X1227405Y508825D02*
X1227420Y508824D01*
G01X1221395Y508823D02*
X1221380D01*
G01X1221410Y508824D02*
X1221395Y508823D01*
G01X1221425Y508825D02*
X1221410Y508824D01*
G01X1217454Y508823D02*
X1217438D01*
G01X1217469Y508824D02*
X1217454Y508823D01*
G01X1217484Y508825D02*
X1217469Y508824D01*
G01X1213521Y508823D02*
X1213506D01*
G01X1213536Y508824D02*
X1213521Y508823D01*
G01X1213551Y508825D02*
X1213536Y508824D01*
G01X1209579Y508823D02*
X1209564D01*
G01X1209594Y508824D02*
X1209579Y508823D01*
G01X1209610Y508825D02*
X1209594Y508824D01*
G01X1205647Y508823D02*
X1205632D01*
G01X1205662Y508824D02*
X1205647Y508823D01*
G01X1205677Y508825D02*
X1205662Y508824D01*
G01X1201705Y508823D02*
X1201690D01*
G01X1201720Y508824D02*
X1201705Y508823D01*
G01X1201735Y508825D02*
X1201720Y508824D01*
G01X1197773Y508823D02*
X1197758D01*
G01X1197788Y508824D02*
X1197773Y508823D01*
G01X1197803Y508825D02*
X1197788Y508824D01*
G01X1193831Y508823D02*
X1193816D01*
G01X1193846Y508824D02*
X1193831Y508823D01*
G01X1193861Y508825D02*
X1193846Y508824D01*
G01X1189899Y508823D02*
X1189884D01*
G01X1189914Y508824D02*
X1189899Y508823D01*
G01X1189929Y508825D02*
X1189914Y508824D01*
G01X1185957Y508823D02*
X1185942D01*
G01X1185972Y508824D02*
X1185957Y508823D01*
G01X1185987Y508825D02*
X1185972Y508824D01*
G01X1227444Y525555D02*
X1227459D01*
G01X1227429Y525554D02*
X1227444Y525555D01*
G01X1227414Y525553D02*
X1227429Y525554D01*
G01X1223502Y525555D02*
X1223517D01*
G01X1223487Y525554D02*
X1223502Y525555D01*
G01X1223472Y525553D02*
X1223487Y525554D01*
G01X1219570Y525555D02*
X1219585D01*
G01X1219555Y525554D02*
X1219570Y525555D01*
G01X1219540Y525553D02*
X1219555Y525554D01*
G01X1215628Y525555D02*
X1215643D01*
G01X1215613Y525554D02*
X1215628Y525555D01*
G01X1215598Y525553D02*
X1215613Y525554D01*
G01X1207754Y525555D02*
X1207769D01*
G01X1207739Y525554D02*
X1207754Y525555D01*
G01X1207724Y525553D02*
X1207739Y525554D01*
G01X1199880Y525555D02*
X1199895D01*
G01X1199865Y525554D02*
X1199880Y525555D01*
G01X1199850Y525553D02*
X1199865Y525554D01*
G01X1195948Y525555D02*
X1195963D01*
G01X1195933Y525554D02*
X1195948Y525555D01*
G01X1195918Y525553D02*
X1195933Y525554D01*
G01X1192006Y525555D02*
X1192021D01*
G01X1191991Y525554D02*
X1192006Y525555D01*
G01X1191976Y525553D02*
X1191991Y525554D01*
G01X1188074Y525555D02*
X1188089D01*
G01X1188059Y525554D02*
X1188074Y525555D01*
G01X1188044Y525553D02*
X1188059Y525554D01*
G01X1184132Y525555D02*
X1184147D01*
G01X1184117Y525554D02*
X1184132Y525555D01*
G01X1184102Y525553D02*
X1184117Y525554D01*
G01X1225328Y507839D02*
X1225313D01*
G01X1225343D02*
X1225328D01*
G01X1225358Y507840D02*
X1225343Y507839D01*
G01X1221395D02*
X1221380D01*
G01X1221410D02*
X1221395D01*
G01X1221425Y507840D02*
X1221410Y507839D01*
G01X1217454D02*
X1217438D01*
G01X1217469D02*
X1217454D01*
G01X1217484Y507840D02*
X1217469Y507839D01*
G01X1213521D02*
X1213506D01*
G01X1213536D02*
X1213521D01*
G01X1213551Y507840D02*
X1213536Y507839D01*
G01X1209579D02*
X1209564D01*
G01X1209594D02*
X1209579D01*
G01X1209610Y507840D02*
X1209594Y507839D01*
G01X1205647D02*
X1205632D01*
G01X1205662D02*
X1205647D01*
G01X1205677Y507840D02*
X1205662Y507839D01*
G01X1201705D02*
X1201690D01*
G01X1201720D02*
X1201705D01*
G01X1201735Y507840D02*
X1201720Y507839D01*
G01X1197773D02*
X1197758D01*
G01X1197788D02*
X1197773D01*
G01X1197803Y507840D02*
X1197788Y507839D01*
G01X1193831D02*
X1193816D01*
G01X1193846D02*
X1193831D01*
G01X1193861Y507840D02*
X1193846Y507839D01*
G01X1189899D02*
X1189884D01*
G01X1189914D02*
X1189899D01*
G01X1189929Y507840D02*
X1189914Y507839D01*
G01X1185957D02*
X1185942D01*
G01X1185972D02*
X1185957D01*
G01X1185987Y507840D02*
X1185972Y507839D01*
G01X1227444Y526539D02*
X1227459D01*
G01X1227429D02*
X1227444D01*
G01X1227414Y526538D02*
X1227429Y526539D01*
G01X1223502D02*
X1223517D01*
G01X1223487D02*
X1223502D01*
G01X1223472Y526538D02*
X1223487Y526539D01*
G01X1219570D02*
X1219585D01*
G01X1219555D02*
X1219570D01*
G01X1219540Y526538D02*
X1219555Y526539D01*
G01X1215628D02*
X1215643D01*
G01X1215613D02*
X1215628D01*
G01X1215598Y526538D02*
X1215613Y526539D01*
G01X1211696D02*
X1211711D01*
G01X1211681D02*
X1211696D01*
G01X1211666Y526538D02*
X1211681Y526539D01*
G01X1207754D02*
X1207769D01*
G01X1207739D02*
X1207754D01*
G01X1207724Y526538D02*
X1207739Y526539D01*
G01X1203822D02*
X1203837D01*
G01X1203807D02*
X1203822D01*
G01X1203792Y526538D02*
X1203807Y526539D01*
G01X1199880D02*
X1199895D01*
G01X1199865D02*
X1199880D01*
G01X1199850Y526538D02*
X1199865Y526539D01*
G01X1195948D02*
X1195963D01*
G01X1195933D02*
X1195948D01*
G01X1195918Y526538D02*
X1195933Y526539D01*
G01X1192006D02*
X1192021D01*
G01X1191991D02*
X1192006D01*
G01X1191976Y526538D02*
X1191991Y526539D01*
G01X1188074D02*
X1188089D01*
G01X1188059D02*
X1188074D01*
G01X1188044Y526538D02*
X1188059Y526539D01*
G01X1184132D02*
X1184147D01*
G01X1184117D02*
X1184132D01*
G01X1184102Y526538D02*
X1184117Y526539D01*
G01X1185982D02*
X1185997Y526538D01*
G01X1185967Y526539D02*
X1185982D01*
G01X1185952D02*
X1185967D01*
G01X1189914D02*
X1189929Y526538D01*
G01X1189899Y526539D02*
X1189914D01*
G01X1189884D02*
X1189899D01*
G01X1193856D02*
X1193871Y526538D01*
G01X1193841Y526539D02*
X1193856D01*
G01X1193826D02*
X1193841D01*
G01X1197788D02*
X1197803Y526538D01*
G01X1197773Y526539D02*
X1197788D01*
G01X1197758D02*
X1197773D01*
G01X1201730D02*
X1201745Y526538D01*
G01X1201715Y526539D02*
X1201730D01*
G01X1201700D02*
X1201715D01*
G01X1205662D02*
X1205677Y526538D01*
G01X1205647Y526539D02*
X1205662D01*
G01X1205632D02*
X1205647D01*
G01X1209604D02*
X1209619Y526538D01*
G01X1209589Y526539D02*
X1209604D01*
G01X1209574D02*
X1209589D01*
G01X1213536D02*
X1213551Y526538D01*
G01X1213521Y526539D02*
X1213536D01*
G01X1213506D02*
X1213521D01*
G01X1217478D02*
X1217493Y526538D01*
G01X1217463Y526539D02*
X1217478D01*
G01X1217448D02*
X1217463D01*
G01X1221410D02*
X1221425Y526538D01*
G01X1221395Y526539D02*
X1221410D01*
G01X1221380D02*
X1221395D01*
G01X1225352D02*
X1225367Y526538D01*
G01X1225337Y526539D02*
X1225352D01*
G01X1225322D02*
X1225337D01*
G01X1189914Y525554D02*
X1189929Y525553D01*
G01X1189899Y525555D02*
X1189914Y525554D01*
G01X1189884Y525555D02*
X1189899D01*
G01X1197788Y525554D02*
X1197803Y525553D01*
G01X1197773Y525555D02*
X1197788Y525554D01*
G01X1197758Y525555D02*
X1197773D01*
G01X1201730Y525554D02*
X1201745Y525553D01*
G01X1201715Y525555D02*
X1201730Y525554D01*
G01X1201700Y525555D02*
X1201715D01*
G01X1205662Y525554D02*
X1205677Y525553D01*
G01X1205647Y525555D02*
X1205662Y525554D01*
G01X1205632Y525555D02*
X1205647D01*
G01X1209604Y525554D02*
X1209619Y525553D01*
G01X1209589Y525555D02*
X1209604Y525554D01*
G01X1209574Y525555D02*
X1209589D01*
G01X1213536Y525554D02*
X1213551Y525553D01*
G01X1213521Y525555D02*
X1213536Y525554D01*
G01X1213506Y525555D02*
X1213521D01*
G01X1221410Y525554D02*
X1221425Y525553D01*
G01X1221395Y525555D02*
X1221410Y525554D01*
G01X1221380Y525555D02*
X1221395D01*
G01X1225352Y525554D02*
X1225367Y525553D01*
G01X1225337Y525555D02*
X1225352Y525554D01*
G01X1225322Y525555D02*
X1225337D01*
G01X1185967D02*
X1185952D01*
G01X1185982Y525554D02*
X1185967Y525555D01*
G01X1185997Y525553D02*
X1185982Y525554D01*
G01X1193841Y525555D02*
X1193826D01*
G01X1193856Y525554D02*
X1193841Y525555D01*
G01X1193871Y525553D02*
X1193856Y525554D01*
G01X1217463Y525555D02*
X1217448D01*
G01X1217478Y525554D02*
X1217463Y525555D01*
G01X1217493Y525553D02*
X1217478Y525554D01*
G01X1188197Y530476D02*
X1185835D01*
G01X1192134D02*
X1189772D01*
G01X1196071D02*
X1193709D01*
G01X1200008D02*
X1197646D01*
G01X1203945D02*
X1201583D01*
G01X1207882D02*
X1205520D01*
G01X1211819D02*
X1209457D01*
G01X1215756D02*
X1213394D01*
G01X1219693D02*
X1217331D01*
G01X1223630D02*
X1221268D01*
G01X1227567D02*
X1225205D01*
G01X1183748Y529492D02*
X1182409D01*
G01X1191622D02*
X1190283D01*
G01X1199496D02*
X1198157D01*
G01X1207370D02*
X1206031D01*
G01X1215244D02*
X1213906D01*
G01X1223118D02*
X1221780D01*
G01X1221622Y529394D02*
X1223276D01*
G01X1213748D02*
X1215402D01*
G01X1205874D02*
X1207528D01*
G01X1198000D02*
X1199654D01*
G01X1190126D02*
X1191780D01*
G01X1188197Y529295D02*
X1185835D01*
G01X1192134D02*
X1189772D01*
G01X1196071D02*
X1193709D01*
G01X1200008D02*
X1197646D01*
G01X1203945D02*
X1201583D01*
G01X1207882D02*
X1205520D01*
G01X1211819D02*
X1209457D01*
G01X1215756D02*
X1213394D01*
G01X1219693D02*
X1217331D01*
G01X1223630D02*
X1221268D01*
G01X1227567D02*
X1225205D01*
G01X1191780Y528902D02*
X1190126D01*
G01X1199654D02*
X1198000D01*
G01X1207528D02*
X1205874D01*
G01X1215402D02*
X1213748D01*
G01X1223276D02*
X1221622D01*
G01X1188433Y528035D02*
X1185598D01*
G01X1192370D02*
X1189535D01*
G01X1196307D02*
X1193472D01*
G01X1200244D02*
X1197409D01*
G01X1204181D02*
X1201346D01*
G01X1208118D02*
X1205283D01*
G01X1212055D02*
X1209220D01*
G01X1215992D02*
X1213157D01*
G01X1219929D02*
X1217094D01*
G01X1223866D02*
X1221031D01*
G01X1227803D02*
X1224968D01*
G01X1191780Y527130D02*
X1190126D01*
G01X1199654D02*
X1198000D01*
G01X1207528D02*
X1205874D01*
G01X1215402D02*
X1213748D01*
G01X1223276D02*
X1221622D01*
G01Y526638D02*
X1223276D01*
G01X1213748D02*
X1215402D01*
G01X1205874D02*
X1207528D01*
G01X1198000D02*
X1199654D01*
G01X1190126D02*
X1191780D01*
G01X1188433Y526539D02*
X1185598D01*
G01X1192370D02*
X1189535D01*
G01X1196307D02*
X1193472D01*
G01X1200244D02*
X1197409D01*
G01X1204181D02*
X1201346D01*
G01X1208118D02*
X1205283D01*
G01X1212055D02*
X1209220D01*
G01X1215992D02*
X1213157D01*
G01X1219929D02*
X1217094D01*
G01X1223866D02*
X1221031D01*
G01X1227803D02*
X1224968D01*
G01X1227213Y526382D02*
X1227803D01*
G01X1224968D02*
X1225559D01*
G01X1223276D02*
X1223866D01*
G01X1221031D02*
X1221622D01*
G01X1219339D02*
X1219929D01*
G01X1217094D02*
X1217685D01*
G01X1215402D02*
X1215992D01*
G01X1213157D02*
X1213748D01*
G01X1211465D02*
X1212055D01*
G01X1209220D02*
X1209811D01*
G01X1207528D02*
X1208118D01*
G01X1205283D02*
X1205874D01*
G01X1203591D02*
X1204181D01*
G01X1201346D02*
X1201937D01*
G01X1199654D02*
X1200244D01*
G01X1197409D02*
X1198000D01*
G01X1195717D02*
X1196307D01*
G01X1193472D02*
X1194063D01*
G01X1191780D02*
X1192370D01*
G01X1189535D02*
X1190126D01*
G01X1187843D02*
X1188433D01*
G01X1185598D02*
X1186189D01*
G01X1183906D02*
X1184496D01*
G01X1225385Y526147D02*
X1227396D01*
G01X1221443D02*
X1223454D01*
G01X1217511D02*
X1219522D01*
G01X1213569D02*
X1215580D01*
G01X1209637D02*
X1211648D01*
G01X1205695D02*
X1207706D01*
G01X1201763D02*
X1203774D01*
G01X1197821D02*
X1199832D01*
G01X1193889D02*
X1195900D01*
G01X1189947D02*
X1191958D01*
G01X1186015D02*
X1188026D01*
G01X1187770Y525757D02*
X1186271D01*
G01X1191702D02*
X1190203D01*
G01X1195644D02*
X1194145D01*
G01X1199577D02*
X1198077D01*
G01X1203518D02*
X1202019D01*
G01X1207451D02*
X1205951D01*
G01X1211392D02*
X1209893D01*
G01X1215325D02*
X1213825D01*
G01X1219266D02*
X1217767D01*
G01X1223199D02*
X1221699D01*
G01X1227140D02*
X1225641D01*
G01X1225654Y525738D02*
X1227127D01*
G01X1221712D02*
X1223185D01*
G01X1217780D02*
X1219253D01*
G01X1213838D02*
X1215311D01*
G01X1209906D02*
X1211379D01*
G01X1205964D02*
X1207437D01*
G01X1202032D02*
X1203505D01*
G01X1198090D02*
X1199563D01*
G01X1194158D02*
X1195631D01*
G01X1190216D02*
X1191689D01*
G01X1186284D02*
X1187757D01*
G01X1184496Y525713D02*
X1183906D01*
G01X1186189D02*
X1185598D01*
G01X1188433D02*
X1187843D01*
G01X1190126D02*
X1189535D01*
G01X1192370D02*
X1191780D01*
G01X1194063D02*
X1193472D01*
G01X1196307D02*
X1195717D01*
G01X1198000D02*
X1197409D01*
G01X1200244D02*
X1199654D01*
G01X1201937D02*
X1201346D01*
G01X1204181D02*
X1203591D01*
G01X1205874D02*
X1205283D01*
G01X1208118D02*
X1207528D01*
G01X1209811D02*
X1209220D01*
G01X1212055D02*
X1211465D01*
G01X1213748D02*
X1213157D01*
G01X1215992D02*
X1215402D01*
G01X1217685D02*
X1217094D01*
G01X1219929D02*
X1219339D01*
G01X1221622D02*
X1221031D01*
G01X1223866D02*
X1223276D01*
G01X1225559D02*
X1224968D01*
G01X1227803D02*
X1227213D01*
G01X1221031Y525555D02*
X1223866D01*
G01X1217094D02*
X1219929D01*
G01X1213157D02*
X1215992D01*
G01X1209220D02*
X1212055D01*
G01X1205283D02*
X1208118D01*
G01X1201346D02*
X1204181D01*
G01X1197409D02*
X1200244D01*
G01X1189535D02*
X1192370D01*
G01X1185598D02*
X1188433D01*
G01X1196307D02*
X1193472D01*
G01X1227803D02*
X1224968D01*
G01X1187843Y525457D02*
X1186189D01*
G01X1195717D02*
X1194063D01*
G01X1203591D02*
X1201937D01*
G01X1211465D02*
X1209811D01*
G01X1219339D02*
X1217685D01*
G01X1227213D02*
X1225559D01*
G01X1183561Y525368D02*
X1182596D01*
G01X1187503D02*
X1186538D01*
G01X1191435D02*
X1190470D01*
G01X1195377D02*
X1194412D01*
G01X1199309D02*
X1198344D01*
G01X1203251D02*
X1202286D01*
G01X1207183D02*
X1206218D01*
G01X1211125D02*
X1210160D01*
G01X1215057D02*
X1214092D01*
G01X1218999D02*
X1218034D01*
G01X1222931D02*
X1221966D01*
G01X1226873D02*
X1225908D01*
G01X1224968Y525358D02*
X1225283D01*
G01X1221031D02*
X1221346D01*
G01X1217094D02*
X1217409D01*
G01X1213157D02*
X1213472D01*
G01X1209220D02*
X1209535D01*
G01X1205283D02*
X1205598D01*
G01X1201346D02*
X1201661D01*
G01X1197409D02*
X1197724D01*
G01X1193472D02*
X1193787D01*
G01X1189535D02*
X1189850D01*
G01X1185598D02*
X1185913D01*
G01X1184496D02*
X1184181D01*
G01X1188433D02*
X1188118D01*
G01X1192370D02*
X1192055D01*
G01X1196307D02*
X1195992D01*
G01X1200244D02*
X1199929D01*
G01X1204181D02*
X1203866D01*
G01X1208118D02*
X1207803D01*
G01X1212055D02*
X1211740D01*
G01X1215992D02*
X1215677D01*
G01X1219929D02*
X1219614D01*
G01X1223866D02*
X1223551D01*
G01X1227803D02*
X1227488D01*
G01X1188031Y525261D02*
X1186010D01*
G01X1191963D02*
X1189942D01*
G01X1195905D02*
X1193884D01*
G01X1199837D02*
X1197816D01*
G01X1203779D02*
X1201758D01*
G01X1207711D02*
X1205690D01*
G01X1211653D02*
X1209632D01*
G01X1215585D02*
X1213564D01*
G01X1219527D02*
X1217506D01*
G01X1223459D02*
X1221438D01*
G01X1227401D02*
X1225380D01*
G01X1225559Y524965D02*
X1227213D01*
G01X1217685D02*
X1219339D01*
G01X1209811D02*
X1211465D01*
G01X1201937D02*
X1203591D01*
G01X1194063D02*
X1195717D01*
G01X1186189D02*
X1187843D01*
G01X1187770Y524772D02*
X1186271D01*
G01X1191702D02*
X1190203D01*
G01X1195644D02*
X1194145D01*
G01X1199577D02*
X1198077D01*
G01X1203518D02*
X1202019D01*
G01X1207451D02*
X1205951D01*
G01X1211392D02*
X1209893D01*
G01X1215325D02*
X1213825D01*
G01X1219266D02*
X1217767D01*
G01X1223199D02*
X1221699D01*
G01X1227140D02*
X1225641D01*
G01X1187769Y524763D02*
X1186272D01*
G01X1191701D02*
X1190205D01*
G01X1195643D02*
X1194146D01*
G01X1199575D02*
X1198079D01*
G01X1203517D02*
X1202020D01*
G01X1207449D02*
X1205953D01*
G01X1211391D02*
X1209894D01*
G01X1215323D02*
X1213827D01*
G01X1219265D02*
X1217768D01*
G01X1223197D02*
X1221701D01*
G01X1227139D02*
X1225642D01*
G01X1225862Y524441D02*
X1226919D01*
G01X1221921D02*
X1222977D01*
G01X1217988D02*
X1219045D01*
G01X1214047D02*
X1215103D01*
G01X1210114D02*
X1211171D01*
G01X1206172D02*
X1207229D01*
G01X1202240D02*
X1203297D01*
G01X1198298D02*
X1199355D01*
G01X1194366D02*
X1195423D01*
G01X1190424D02*
X1191481D01*
G01X1186492D02*
X1187549D01*
G01X1182550D02*
X1183607D01*
G01X1188197Y524394D02*
X1185835D01*
G01X1192134D02*
X1189772D01*
G01X1196071D02*
X1193709D01*
G01X1200008D02*
X1197646D01*
G01X1203945D02*
X1201583D01*
G01X1207882D02*
X1205520D01*
G01X1211819D02*
X1209457D01*
G01X1215756D02*
X1213394D01*
G01X1219693D02*
X1217331D01*
G01X1223630D02*
X1221268D01*
G01X1227567D02*
X1225205D01*
G01X1227488Y523862D02*
X1227803D01*
G01X1224968D02*
X1225283D01*
G01X1223551D02*
X1223866D01*
G01X1221031D02*
X1221346D01*
G01X1219614D02*
X1219929D01*
G01X1217094D02*
X1217409D01*
G01X1215677D02*
X1215992D01*
G01X1213157D02*
X1213472D01*
G01X1211740D02*
X1212055D01*
G01X1209220D02*
X1209535D01*
G01X1207803D02*
X1208118D01*
G01X1203866D02*
X1204181D01*
G01X1205283D02*
X1205598D01*
G01X1201346D02*
X1201661D01*
G01X1199929D02*
X1200244D01*
G01X1197409D02*
X1197724D01*
G01X1195992D02*
X1196307D01*
G01X1193472D02*
X1193787D01*
G01X1192055D02*
X1192370D01*
G01X1189535D02*
X1189850D01*
G01X1188118D02*
X1188433D01*
G01X1185598D02*
X1185913D01*
G01X1184181D02*
X1184496D01*
G01X1225619Y523826D02*
X1227162D01*
G01X1221677D02*
X1223220D01*
G01X1217745D02*
X1219288D01*
G01X1213803D02*
X1215346D01*
G01X1209871D02*
X1211414D01*
G01X1205929D02*
X1207472D01*
G01X1201997D02*
X1203540D01*
G01X1198055D02*
X1199598D01*
G01X1194123D02*
X1195666D01*
G01X1190181D02*
X1191724D01*
G01X1186249D02*
X1187792D01*
G01X1225630Y523807D02*
X1227151D01*
G01X1221688D02*
X1223210D01*
G01X1217756D02*
X1219277D01*
G01X1213814D02*
X1215336D01*
G01X1209882D02*
X1211403D01*
G01X1205940D02*
X1207461D01*
G01X1202008D02*
X1203529D01*
G01X1198066D02*
X1199587D01*
G01X1194134D02*
X1195655D01*
G01X1190192D02*
X1191713D01*
G01X1186260D02*
X1187781D01*
G01X1225559Y523193D02*
X1227213D01*
G01X1217685D02*
X1219339D01*
G01X1209811D02*
X1211465D01*
G01X1201937D02*
X1203591D01*
G01X1194063D02*
X1195717D01*
G01X1186189D02*
X1187843D01*
G01Y522701D02*
X1186189D01*
G01X1195717D02*
X1194063D01*
G01X1203591D02*
X1201937D01*
G01X1211465D02*
X1209811D01*
G01X1219339D02*
X1217685D01*
G01X1227213D02*
X1225559D01*
G01X1187685Y522602D02*
X1186346D01*
G01X1195559D02*
X1194220D01*
G01X1203433D02*
X1202094D01*
G01X1211307D02*
X1209968D01*
G01X1219181D02*
X1217843D01*
G01X1227055D02*
X1225717D01*
G01Y521618D02*
X1227055D01*
G01X1217843D02*
X1219181D01*
G01X1209968D02*
X1211307D01*
G01X1202094D02*
X1203433D01*
G01X1194220D02*
X1195559D01*
G01X1186346D02*
X1187685D01*
G01X1187818Y520999D02*
X1186223D01*
G01X1191750D02*
X1190155D01*
G01X1195692D02*
X1194097D01*
G01X1199624D02*
X1198029D01*
G01X1203566D02*
X1201971D01*
G01X1207498D02*
X1205903D01*
G01X1211440D02*
X1209845D01*
G01X1215372D02*
X1213777D01*
G01X1219314D02*
X1217719D01*
G01X1223246D02*
X1221651D01*
G01X1227188D02*
X1225593D01*
G01X1188118Y520890D02*
X1185913D01*
G01X1192055D02*
X1189850D01*
G01X1195992D02*
X1193787D01*
G01X1199929D02*
X1197724D01*
G01X1203866D02*
X1201661D01*
G01X1207803D02*
X1205598D01*
G01X1211740D02*
X1209535D01*
G01X1215677D02*
X1213472D01*
G01X1219614D02*
X1217409D01*
G01X1223551D02*
X1221346D01*
G01X1227488D02*
X1225283D01*
G01X1187890Y520239D02*
X1186151D01*
G01X1191822D02*
X1190083D01*
G01X1195764D02*
X1194025D01*
G01X1199696D02*
X1197957D01*
G01X1203638D02*
X1201899D01*
G01X1207570D02*
X1205831D01*
G01X1211512D02*
X1209773D01*
G01X1215444D02*
X1213705D01*
G01X1219386D02*
X1217647D01*
G01X1223318D02*
X1221579D01*
G01X1227260D02*
X1225521D01*
G01X1225595Y520037D02*
X1227186D01*
G01X1221654D02*
X1223244D01*
G01X1217721D02*
X1219312D01*
G01X1213780D02*
X1215370D01*
G01X1209847D02*
X1211438D01*
G01X1205906D02*
X1207496D01*
G01X1201973D02*
X1203564D01*
G01X1198032D02*
X1199622D01*
G01X1194099D02*
X1195690D01*
G01X1190158D02*
X1191748D01*
G01X1186225D02*
X1187816D01*
G01X1225542Y520013D02*
X1227239D01*
G01X1221601D02*
X1223297D01*
G01X1217668D02*
X1219365D01*
G01X1213727D02*
X1215423D01*
G01X1209794D02*
X1211491D01*
G01X1205853D02*
X1207549D01*
G01X1201920D02*
X1203617D01*
G01X1197979D02*
X1199675D01*
G01X1194046D02*
X1195742D01*
G01X1190105D02*
X1191801D01*
G01X1186172D02*
X1187868D01*
G01X1187876Y519945D02*
X1186165D01*
G01X1191808D02*
X1190098D01*
G01X1195750D02*
X1194039D01*
G01X1199682D02*
X1197972D01*
G01X1203624D02*
X1201913D01*
G01X1207556D02*
X1205846D01*
G01X1211498D02*
X1209787D01*
G01X1215430D02*
X1213720D01*
G01X1219372D02*
X1217661D01*
G01X1223304D02*
X1221594D01*
G01X1227246D02*
X1225535D01*
G01X1225516Y519353D02*
X1227265D01*
G01X1221575D02*
X1223323D01*
G01X1217642D02*
X1219391D01*
G01X1213701D02*
X1215449D01*
G01X1209768D02*
X1211517D01*
G01X1205827D02*
X1207575D01*
G01X1201894D02*
X1203643D01*
G01X1197953D02*
X1199701D01*
G01X1194020D02*
X1195769D01*
G01X1190079D02*
X1191827D01*
G01X1186146D02*
X1187895D01*
G01X1187866Y519051D02*
X1186175D01*
G01X1191798D02*
X1190107D01*
G01X1195740D02*
X1194049D01*
G01X1199673D02*
X1197981D01*
G01X1203614D02*
X1201923D01*
G01X1207547D02*
X1205855D01*
G01X1211488D02*
X1209797D01*
G01X1215421D02*
X1213729D01*
G01X1219362D02*
X1217671D01*
G01X1223295D02*
X1221603D01*
G01X1227236D02*
X1225545D01*
G01X1187876Y518961D02*
X1186165D01*
G01X1191808D02*
X1190098D01*
G01X1195750D02*
X1194039D01*
G01X1199682D02*
X1197972D01*
G01X1203624D02*
X1201913D01*
G01X1207556D02*
X1205846D01*
G01X1211498D02*
X1209787D01*
G01X1215430D02*
X1213720D01*
G01X1219372D02*
X1217661D01*
G01X1223304D02*
X1221594D01*
G01X1227246D02*
X1225535D01*
G01X1225283Y518635D02*
X1227488D01*
G01X1221346D02*
X1223551D01*
G01X1217409D02*
X1219614D01*
G01X1213472D02*
X1215677D01*
G01X1209535D02*
X1211740D01*
G01X1205598D02*
X1207803D01*
G01X1201661D02*
X1203866D01*
G01X1197724D02*
X1199929D01*
G01X1193787D02*
X1195992D01*
G01X1189850D02*
X1192055D01*
G01X1185913D02*
X1188118D01*
G01X1225283Y518468D02*
X1227488D01*
G01X1221346D02*
X1223551D01*
G01X1217409D02*
X1219614D01*
G01X1213472D02*
X1215677D01*
G01X1209535D02*
X1211740D01*
G01X1205598D02*
X1207803D01*
G01X1201661D02*
X1203866D01*
G01X1197724D02*
X1199929D01*
G01X1193787D02*
X1195992D01*
G01X1189850D02*
X1192055D01*
G01X1185913D02*
X1188118D01*
G01Y515910D02*
X1185913D01*
G01X1192055D02*
X1189850D01*
G01X1195992D02*
X1193787D01*
G01X1199929D02*
X1197724D01*
G01X1203866D02*
X1201661D01*
G01X1207803D02*
X1205598D01*
G01X1211740D02*
X1209535D01*
G01X1215677D02*
X1213472D01*
G01X1219614D02*
X1217409D01*
G01X1223551D02*
X1221346D01*
G01X1227488D02*
X1225283D01*
G01X1188118Y515743D02*
X1185913D01*
G01X1192055D02*
X1189850D01*
G01X1195992D02*
X1193787D01*
G01X1199929D02*
X1197724D01*
G01X1203866D02*
X1201661D01*
G01X1207803D02*
X1205598D01*
G01X1211740D02*
X1209535D01*
G01X1215677D02*
X1213472D01*
G01X1219614D02*
X1217409D01*
G01X1223551D02*
X1221346D01*
G01X1227488D02*
X1225283D01*
G01X1225526Y515417D02*
X1227236D01*
G01X1221594D02*
X1223304D01*
G01X1217652D02*
X1219362D01*
G01X1213720D02*
X1215430D01*
G01X1209778D02*
X1211488D01*
G01X1205846D02*
X1207556D01*
G01X1201904D02*
X1203614D01*
G01X1197972D02*
X1199682D01*
G01X1194030D02*
X1195740D01*
G01X1190098D02*
X1191808D01*
G01X1186156D02*
X1187866D01*
G01X1225535Y515327D02*
X1227227D01*
G01X1221603D02*
X1223295D01*
G01X1217661D02*
X1219353D01*
G01X1213729D02*
X1215421D01*
G01X1209787D02*
X1211479D01*
G01X1205855D02*
X1207547D01*
G01X1201913D02*
X1203605D01*
G01X1197981D02*
X1199673D01*
G01X1194039D02*
X1195731D01*
G01X1190107D02*
X1191798D01*
G01X1186165D02*
X1187857D01*
G01X1187885Y515025D02*
X1186137D01*
G01X1191827D02*
X1190079D01*
G01X1195759D02*
X1194011D01*
G01X1199701D02*
X1197953D01*
G01X1203633D02*
X1201885D01*
G01X1207575D02*
X1205827D01*
G01X1211507D02*
X1209759D01*
G01X1215449D02*
X1213701D01*
G01X1219381D02*
X1217633D01*
G01X1223323D02*
X1221575D01*
G01X1227255D02*
X1225507D01*
G01X1225526Y514433D02*
X1227236D01*
G01X1221594D02*
X1223304D01*
G01X1217652D02*
X1219362D01*
G01X1213720D02*
X1215430D01*
G01X1209778D02*
X1211488D01*
G01X1205846D02*
X1207556D01*
G01X1201904D02*
X1203614D01*
G01X1197972D02*
X1199682D01*
G01X1194030D02*
X1195740D01*
G01X1190098D02*
X1191808D01*
G01X1186156D02*
X1187866D01*
G01X1187859Y514365D02*
X1186163D01*
G01X1191801D02*
X1190105D01*
G01X1195733D02*
X1194037D01*
G01X1199675D02*
X1197979D01*
G01X1203607D02*
X1201911D01*
G01X1207549D02*
X1205853D01*
G01X1211481D02*
X1209785D01*
G01X1215423D02*
X1213727D01*
G01X1219355D02*
X1217659D01*
G01X1223297D02*
X1221601D01*
G01X1227229D02*
X1225533D01*
G01X1187806Y514341D02*
X1186216D01*
G01X1191748D02*
X1190158D01*
G01X1195680D02*
X1194090D01*
G01X1199622D02*
X1198032D01*
G01X1203554D02*
X1201964D01*
G01X1207496D02*
X1205906D01*
G01X1211428D02*
X1209838D01*
G01X1215370D02*
X1213780D01*
G01X1219302D02*
X1217712D01*
G01X1223244D02*
X1221654D01*
G01X1227176D02*
X1225586D01*
G01X1225512Y514139D02*
X1227251D01*
G01X1221579D02*
X1223318D01*
G01X1217638D02*
X1219377D01*
G01X1213705D02*
X1215444D01*
G01X1209764D02*
X1211503D01*
G01X1205831D02*
X1207570D01*
G01X1201890D02*
X1203629D01*
G01X1197957D02*
X1199696D01*
G01X1194016D02*
X1195754D01*
G01X1190083D02*
X1191822D01*
G01X1186142D02*
X1187880D01*
G01X1225283Y513488D02*
X1227488D01*
G01X1221346D02*
X1223551D01*
G01X1217409D02*
X1219614D01*
G01X1213472D02*
X1215677D01*
G01X1209535D02*
X1211740D01*
G01X1205598D02*
X1207803D01*
G01X1201661D02*
X1203866D01*
G01X1197724D02*
X1199929D01*
G01X1193787D02*
X1195992D01*
G01X1189850D02*
X1192055D01*
G01X1185913D02*
X1188118D01*
G01X1225584Y513379D02*
X1227179D01*
G01X1221651D02*
X1223246D01*
G01X1217710D02*
X1219305D01*
G01X1213777D02*
X1215372D01*
G01X1209836D02*
X1211431D01*
G01X1205903D02*
X1207498D01*
G01X1201962D02*
X1203557D01*
G01X1198029D02*
X1199624D01*
G01X1194088D02*
X1195683D01*
G01X1190155D02*
X1191750D01*
G01X1186213D02*
X1187809D01*
G01X1187685Y512760D02*
X1186346D01*
G01X1195559D02*
X1194220D01*
G01X1203433D02*
X1202094D01*
G01X1211307D02*
X1209968D01*
G01X1219181D02*
X1217843D01*
G01X1227055D02*
X1225717D01*
G01X1187685Y511776D02*
X1186346D01*
G01X1195559D02*
X1194220D01*
G01X1203433D02*
X1202094D01*
G01X1211307D02*
X1209968D01*
G01X1219181D02*
X1217843D01*
G01X1227055D02*
X1225717D01*
G01X1225559Y511677D02*
X1227213D01*
G01X1217685D02*
X1219339D01*
G01X1209811D02*
X1211465D01*
G01X1201937D02*
X1203591D01*
G01X1194063D02*
X1195717D01*
G01X1186189D02*
X1187843D01*
G01Y511185D02*
X1186189D01*
G01X1195717D02*
X1194063D01*
G01X1203591D02*
X1201937D01*
G01X1211465D02*
X1209811D01*
G01X1219339D02*
X1217685D01*
G01X1227213D02*
X1225559D01*
G01X1187772Y510571D02*
X1186250D01*
G01X1191713D02*
X1190192D01*
G01X1195646D02*
X1194124D01*
G01X1199587D02*
X1198066D01*
G01X1203520D02*
X1201998D01*
G01X1207461D02*
X1205940D01*
G01X1211394D02*
X1209872D01*
G01X1215336D02*
X1213814D01*
G01X1219268D02*
X1217746D01*
G01X1223210D02*
X1221688D01*
G01X1227142D02*
X1225620D01*
G01X1187783Y510552D02*
X1186239D01*
G01X1191724D02*
X1190181D01*
G01X1195657D02*
X1194113D01*
G01X1199598D02*
X1198055D01*
G01X1203531D02*
X1201987D01*
G01X1207472D02*
X1205929D01*
G01X1211405D02*
X1209861D01*
G01X1215346D02*
X1213803D01*
G01X1219279D02*
X1217735D01*
G01X1223220D02*
X1221677D01*
G01X1227153D02*
X1225609D01*
G01X1184496Y510516D02*
X1184181D01*
G01X1185913D02*
X1185598D01*
G01X1188433D02*
X1188118D01*
G01X1189850D02*
X1189535D01*
G01X1192370D02*
X1192055D01*
G01X1193787D02*
X1193472D01*
G01X1196307D02*
X1195992D01*
G01X1197724D02*
X1197409D01*
G01X1200244D02*
X1199929D01*
G01X1201661D02*
X1201346D01*
G01X1204181D02*
X1203866D01*
G01X1205598D02*
X1205283D01*
G01X1208118D02*
X1207803D01*
G01X1209535D02*
X1209220D01*
G01X1212055D02*
X1211740D01*
G01X1213472D02*
X1213157D01*
G01X1215992D02*
X1215677D01*
G01X1217409D02*
X1217094D01*
G01X1219929D02*
X1219614D01*
G01X1221346D02*
X1221031D01*
G01X1223866D02*
X1223551D01*
G01X1225283D02*
X1224968D01*
G01X1227803D02*
X1227488D01*
G01X1188197Y509984D02*
X1185835D01*
G01X1192134D02*
X1189772D01*
G01X1196071D02*
X1193709D01*
G01X1200008D02*
X1197646D01*
G01X1203945D02*
X1201583D01*
G01X1207882D02*
X1205520D01*
G01X1211819D02*
X1209457D01*
G01X1215756D02*
X1213394D01*
G01X1219693D02*
X1217331D01*
G01X1223630D02*
X1221268D01*
G01X1227567D02*
X1225205D01*
G01X1183607Y509937D02*
X1182550D01*
G01X1187539D02*
X1186483D01*
G01X1191481D02*
X1190424D01*
G01X1195413D02*
X1194357D01*
G01X1199355D02*
X1198298D01*
G01X1203287D02*
X1202231D01*
G01X1207229D02*
X1206172D01*
G01X1211161D02*
X1210105D01*
G01X1215103D02*
X1214047D01*
G01X1219035D02*
X1217979D01*
G01X1222977D02*
X1221921D01*
G01X1226909D02*
X1225853D01*
G01X1225633Y509615D02*
X1227129D01*
G01X1221701D02*
X1223197D01*
G01X1217759D02*
X1219255D01*
G01X1213827D02*
X1215323D01*
G01X1209885D02*
X1211381D01*
G01X1205953D02*
X1207449D01*
G01X1202011D02*
X1203507D01*
G01X1198079D02*
X1199575D01*
G01X1194137D02*
X1195633D01*
G01X1190205D02*
X1191701D01*
G01X1186263D02*
X1187759D01*
G01X1225631Y509606D02*
X1227131D01*
G01X1221699D02*
X1223199D01*
G01X1217757D02*
X1219257D01*
G01X1213825D02*
X1215325D01*
G01X1209883D02*
X1211383D01*
G01X1205951D02*
X1207451D01*
G01X1202009D02*
X1203509D01*
G01X1198077D02*
X1199577D01*
G01X1194135D02*
X1195635D01*
G01X1190203D02*
X1191702D01*
G01X1186261D02*
X1187761D01*
G01X1187843Y509413D02*
X1186189D01*
G01X1195717D02*
X1194063D01*
G01X1203591D02*
X1201937D01*
G01X1211465D02*
X1209811D01*
G01X1219339D02*
X1217685D01*
G01X1227213D02*
X1225559D01*
G01X1225371Y509117D02*
X1227392D01*
G01X1221438D02*
X1223459D01*
G01X1217497D02*
X1219518D01*
G01X1213564D02*
X1215585D01*
G01X1209623D02*
X1211644D01*
G01X1205690D02*
X1207711D01*
G01X1201749D02*
X1203770D01*
G01X1197816D02*
X1199837D01*
G01X1193875D02*
X1195896D01*
G01X1189942D02*
X1191963D01*
G01X1186001D02*
X1188021D01*
G01X1227488Y509020D02*
X1227803D01*
G01X1223551D02*
X1223866D01*
G01X1219614D02*
X1219929D01*
G01X1215677D02*
X1215992D01*
G01X1211740D02*
X1212055D01*
G01X1207803D02*
X1208118D01*
G01X1203866D02*
X1204181D01*
G01X1199929D02*
X1200244D01*
G01X1195992D02*
X1196307D01*
G01X1192055D02*
X1192370D01*
G01X1188118D02*
X1188433D01*
G01X1184181D02*
X1184496D01*
G01X1185913D02*
X1185598D01*
G01X1189850D02*
X1189535D01*
G01X1193787D02*
X1193472D01*
G01X1197724D02*
X1197409D01*
G01X1201661D02*
X1201346D01*
G01X1205598D02*
X1205283D01*
G01X1209535D02*
X1209220D01*
G01X1213472D02*
X1213157D01*
G01X1217409D02*
X1217094D01*
G01X1221346D02*
X1221031D01*
G01X1225283D02*
X1224968D01*
G01X1225898Y509010D02*
X1226864D01*
G01X1221966D02*
X1222931D01*
G01X1218024D02*
X1218990D01*
G01X1214092D02*
X1215057D01*
G01X1210150D02*
X1211116D01*
G01X1206218D02*
X1207183D01*
G01X1202276D02*
X1203242D01*
G01X1198344D02*
X1199309D01*
G01X1194402D02*
X1195368D01*
G01X1190470D02*
X1191435D01*
G01X1186528D02*
X1187494D01*
G01X1182596D02*
X1183561D01*
G01X1225559Y508921D02*
X1227213D01*
G01X1217685D02*
X1219339D01*
G01X1209811D02*
X1211465D01*
G01X1201937D02*
X1203591D01*
G01X1194063D02*
X1195717D01*
G01X1186189D02*
X1187843D01*
G01X1224968Y508823D02*
X1227803D01*
G01X1221031D02*
X1223866D01*
G01X1217094D02*
X1219929D01*
G01X1213157D02*
X1215992D01*
G01X1209220D02*
X1212055D01*
G01X1205283D02*
X1208118D01*
G01X1201346D02*
X1204181D01*
G01X1197409D02*
X1200244D01*
G01X1193472D02*
X1196307D01*
G01X1189535D02*
X1192370D01*
G01X1185598D02*
X1188433D01*
G01X1227213Y508665D02*
X1227803D01*
G01X1224968D02*
X1225559D01*
G01X1223276D02*
X1223866D01*
G01X1221031D02*
X1221622D01*
G01X1219339D02*
X1219929D01*
G01X1217094D02*
X1217685D01*
G01X1215402D02*
X1215992D01*
G01X1213157D02*
X1213748D01*
G01X1211465D02*
X1212055D01*
G01X1209220D02*
X1209811D01*
G01X1207528D02*
X1208118D01*
G01X1205283D02*
X1205874D01*
G01X1203591D02*
X1204181D01*
G01X1201346D02*
X1201937D01*
G01X1199654D02*
X1200244D01*
G01X1197409D02*
X1198000D01*
G01X1195717D02*
X1196307D01*
G01X1193472D02*
X1194063D01*
G01X1191780D02*
X1192370D01*
G01X1189535D02*
X1190126D01*
G01X1187843D02*
X1188433D01*
G01X1185598D02*
X1186189D01*
G01X1183906D02*
X1184496D01*
G01X1187748Y508640D02*
X1186275D01*
G01X1191689D02*
X1190216D01*
G01X1195622D02*
X1194149D01*
G01X1199563D02*
X1198090D01*
G01X1203496D02*
X1202023D01*
G01X1207437D02*
X1205964D01*
G01X1211370D02*
X1209897D01*
G01X1215311D02*
X1213838D01*
G01X1219244D02*
X1217771D01*
G01X1223185D02*
X1221712D01*
G01X1227118D02*
X1225645D01*
G01X1225631Y508621D02*
X1227131D01*
G01X1221699D02*
X1223199D01*
G01X1217757D02*
X1219257D01*
G01X1213825D02*
X1215325D01*
G01X1209883D02*
X1211383D01*
G01X1205951D02*
X1207451D01*
G01X1202009D02*
X1203509D01*
G01X1198077D02*
X1199577D01*
G01X1194135D02*
X1195635D01*
G01X1190203D02*
X1191702D01*
G01X1186261D02*
X1187761D01*
G01X1188017Y508231D02*
X1186005D01*
G01X1191958D02*
X1189947D01*
G01X1195891D02*
X1193879D01*
G01X1199832D02*
X1197821D01*
G01X1203765D02*
X1201753D01*
G01X1207706D02*
X1205695D01*
G01X1211639D02*
X1209627D01*
G01X1215580D02*
X1213569D01*
G01X1219513D02*
X1217502D01*
G01X1223454D02*
X1221443D01*
G01X1227387D02*
X1225376D01*
G01X1184496Y507996D02*
X1183906D01*
G01X1186189D02*
X1185598D01*
G01X1188433D02*
X1187843D01*
G01X1190126D02*
X1189535D01*
G01X1192370D02*
X1191780D01*
G01X1194063D02*
X1193472D01*
G01X1196307D02*
X1195717D01*
G01X1198000D02*
X1197409D01*
G01X1200244D02*
X1199654D01*
G01X1201937D02*
X1201346D01*
G01X1204181D02*
X1203591D01*
G01X1205874D02*
X1205283D01*
G01X1208118D02*
X1207528D01*
G01X1209811D02*
X1209220D01*
G01X1212055D02*
X1211465D01*
G01X1213748D02*
X1213157D01*
G01X1215992D02*
X1215402D01*
G01X1217685D02*
X1217094D01*
G01X1219929D02*
X1219339D01*
G01X1221622D02*
X1221031D01*
G01X1223866D02*
X1223276D01*
G01X1225559D02*
X1224968D01*
G01X1227803D02*
X1227213D01*
G01X1188433Y507839D02*
X1185598D01*
G01X1192370D02*
X1189535D01*
G01X1196307D02*
X1193472D01*
G01X1200244D02*
X1197409D01*
G01X1204181D02*
X1201346D01*
G01X1208118D02*
X1205283D01*
G01X1212055D02*
X1209220D01*
G01X1215992D02*
X1213157D01*
G01X1219929D02*
X1217094D01*
G01X1223866D02*
X1221031D01*
G01X1227803D02*
X1224968D01*
G01X1191780Y507740D02*
X1190126D01*
G01X1199654D02*
X1198000D01*
G01X1207528D02*
X1205874D01*
G01X1215402D02*
X1213748D01*
G01X1223276D02*
X1221622D01*
G01Y507248D02*
X1223276D01*
G01X1213748D02*
X1215402D01*
G01X1205874D02*
X1207528D01*
G01X1198000D02*
X1199654D01*
G01X1190126D02*
X1191780D01*
G01X1224968Y506343D02*
X1227803D01*
G01X1221031D02*
X1223866D01*
G01X1217094D02*
X1219929D01*
G01X1213157D02*
X1215992D01*
G01X1209220D02*
X1212055D01*
G01X1205283D02*
X1208118D01*
G01X1201346D02*
X1204181D01*
G01X1197409D02*
X1200244D01*
G01X1193472D02*
X1196307D01*
G01X1189535D02*
X1192370D01*
G01X1185598D02*
X1188433D01*
G01X1221622Y505476D02*
X1223276D01*
G01X1213748D02*
X1215402D01*
G01X1205874D02*
X1207528D01*
G01X1198000D02*
X1199654D01*
G01X1190126D02*
X1191780D01*
G01X1225205Y505083D02*
X1227567D01*
G01X1188197D02*
X1185835D01*
G01X1192134D02*
X1189772D01*
G01X1196071D02*
X1193709D01*
G01X1200008D02*
X1197646D01*
G01X1203945D02*
X1201583D01*
G01X1207882D02*
X1205520D01*
G01X1211819D02*
X1209457D01*
G01X1215756D02*
X1213394D01*
G01X1219693D02*
X1217331D01*
G01X1223630D02*
X1221268D01*
G01X1191780Y504984D02*
X1190126D01*
G01X1199654D02*
X1198000D01*
G01X1207528D02*
X1205874D01*
G01X1215402D02*
X1213748D01*
G01X1223276D02*
X1221622D01*
G01X1183748Y504886D02*
X1182409D01*
G01X1191622D02*
X1190283D01*
G01X1199496D02*
X1198157D01*
G01X1207370D02*
X1206031D01*
G01X1215244D02*
X1213906D01*
G01X1223118D02*
X1221780D01*
G01X1225205Y503902D02*
X1227567D01*
G01X1221268D02*
X1223630D01*
G01X1217331D02*
X1219693D01*
G01X1213394D02*
X1215756D01*
G01X1209457D02*
X1211819D01*
G01X1205520D02*
X1207882D01*
G01X1201583D02*
X1203945D01*
G01X1197646D02*
X1200008D01*
G01X1193709D02*
X1196071D01*
G01X1189772D02*
X1192134D01*
G01X1185835D02*
X1188197D01*
G01X1225908Y525368D02*
X1225654Y525738D01*
G01X1225862Y524441D02*
X1225641Y524763D01*
G01X1221712Y525738D02*
X1221966Y525368D01*
G01X1221921Y524441D02*
X1221699Y524763D01*
G01X1217780Y525738D02*
X1218034Y525368D01*
G01X1217988Y524441D02*
X1217767Y524763D01*
G01X1226909Y509937D02*
X1227131Y509615D01*
G01X1226864Y509010D02*
X1227118Y508640D01*
G01X1213838Y525738D02*
X1214092Y525368D01*
G01X1214047Y524441D02*
X1213825Y524763D01*
G01X1222977Y509937D02*
X1223198Y509615D01*
G01X1223185Y508640D02*
X1222931Y509010D01*
G01X1209906Y525738D02*
X1210160Y525368D01*
G01X1210114Y524441D02*
X1209893Y524763D01*
G01X1219035Y509937D02*
X1219257Y509615D01*
G01X1219244Y508640D02*
X1218990Y509010D01*
G01X1205964Y525738D02*
X1206218Y525368D01*
G01X1206172Y524441D02*
X1205951Y524763D01*
G01X1215103Y509937D02*
X1215324Y509615D01*
G01X1225862Y524441D02*
X1225872Y524394D01*
G01X1226909Y509937D02*
X1226900Y509984D01*
G01X1221921Y524441D02*
X1221930Y524394D01*
G01X1215311Y508640D02*
X1215057Y509010D01*
G01X1202032Y525738D02*
X1202286Y525368D01*
G01X1202240Y524441D02*
X1202019Y524763D01*
G01X1211161Y509937D02*
X1211383Y509615D01*
G01X1211370Y508640D02*
X1211116Y509010D01*
G01X1198090Y525738D02*
X1198344Y525368D01*
G01X1198298Y524441D02*
X1198077Y524763D01*
G01X1207229Y509937D02*
X1207450Y509615D01*
G01X1207437Y508640D02*
X1207183Y509010D01*
G01X1194158Y525738D02*
X1194412Y525368D01*
G01X1194366Y524441D02*
X1194145Y524763D01*
G01X1203287Y509937D02*
X1203509Y509615D01*
G01X1203496Y508640D02*
X1203242Y509010D01*
G01X1190216Y525738D02*
X1190470Y525368D01*
G01X1190424Y524441D02*
X1190203Y524763D01*
G01X1199355Y509937D02*
X1199576Y509615D01*
G01X1199563Y508640D02*
X1199309Y509010D01*
G01X1186284Y525738D02*
X1186538Y525368D01*
G01X1186492Y524441D02*
X1186271Y524763D01*
G01X1195413Y509937D02*
X1195635Y509615D01*
G01X1195622Y508640D02*
X1195368Y509010D01*
G01X1191481Y509937D02*
X1191702Y509615D01*
G01X1191689Y508640D02*
X1191435Y509010D01*
G01X1187539Y509937D02*
X1187761Y509615D01*
G01X1187748Y508640D02*
X1187494Y509010D01*
G01X1222977Y509937D02*
X1222968Y509984D01*
G01X1217988Y524441D02*
X1217998Y524394D01*
G01X1219035Y509937D02*
X1219026Y509984D01*
G01X1214047Y524441D02*
X1214056Y524394D01*
G01X1215103Y509937D02*
X1215093Y509984D01*
G01X1210114Y524441D02*
X1210124Y524394D01*
G01X1211161Y509937D02*
X1211152Y509984D01*
G01X1206172Y524441D02*
X1206182Y524394D01*
G01X1207229Y509937D02*
X1207219Y509984D01*
G01X1202240Y524441D02*
X1202250Y524394D01*
G01X1203287Y509937D02*
X1203278Y509984D01*
G01X1198298Y524441D02*
X1198308Y524394D01*
G01X1199355Y509937D02*
X1199345Y509984D01*
G01X1183607Y509937D02*
X1183828Y509615D01*
G01X1183815Y508640D02*
X1183561Y509010D01*
G01X1225645Y508640D02*
X1225898Y509010D01*
G01X1225632Y509615D02*
X1225853Y509937D01*
G01X1225862Y509984D02*
X1225853Y509937D01*
G01X1226909Y524394D02*
X1226919Y524441D01*
G01X1221930Y509984D02*
X1221921Y509937D01*
G01X1222968Y524394D02*
X1222977Y524441D01*
G01X1227179Y513379D02*
X1227229Y514365D01*
G01X1227227Y515327D02*
X1227176Y514341D01*
G01X1225545Y519051D02*
X1225595Y520037D01*
G01X1225593Y520999D02*
X1225542Y520013D01*
G01X1223246Y513379D02*
X1223297Y514365D01*
G01X1223295Y515327D02*
X1223244Y514341D01*
G01X1221603Y519051D02*
X1221654Y520037D01*
G01X1221651Y520999D02*
X1221601Y520013D01*
G01X1219305Y513379D02*
X1219355Y514365D01*
G01X1219353Y515327D02*
X1219302Y514341D01*
G01X1217671Y519051D02*
X1217721Y520037D01*
G01X1217719Y520999D02*
X1217668Y520013D01*
G01X1215372Y513379D02*
X1215423Y514365D01*
G01X1215421Y515327D02*
X1215370Y514341D01*
G01X1213729Y519051D02*
X1213780Y520037D01*
G01X1227265Y519353D02*
X1227401Y525261D01*
G01X1227396Y526147D02*
X1227260Y520239D01*
G01X1225376Y508231D02*
X1225512Y514139D01*
G01X1225507Y515025D02*
X1225371Y509117D01*
G01X1223323Y519353D02*
X1223459Y525261D01*
G01X1223454Y526147D02*
X1223318Y520239D01*
G01X1221443Y508231D02*
X1221579Y514139D01*
G01X1221575Y515025D02*
X1221438Y509117D01*
G01X1219391Y519353D02*
X1219527Y525261D01*
G01X1219522Y526147D02*
X1219386Y520239D01*
G01X1217502Y508231D02*
X1217638Y514139D01*
G01X1217633Y515025D02*
X1217497Y509117D01*
G01X1215449Y519353D02*
X1215585Y525261D01*
G01X1215580Y526147D02*
X1215444Y520239D01*
G01X1213569Y508231D02*
X1213705Y514139D01*
G01X1213701Y515025D02*
X1213564Y509117D01*
G01X1226877Y509984D02*
X1226864Y509010D01*
G01X1225895Y524394D02*
X1225908Y525368D01*
G01X1222945Y509984D02*
X1222931Y509010D01*
G01X1221953Y524394D02*
X1221966Y525368D01*
G01X1219003Y509984D02*
X1218990Y509010D01*
G01X1218021Y524394D02*
X1218034Y525368D01*
G01X1215071Y509984D02*
X1215057Y509010D01*
G01X1214079Y524394D02*
X1214092Y525368D01*
G01X1227567Y509984D02*
Y503902D01*
G01Y530476D02*
Y524394D01*
G01X1227488Y507839D02*
Y526539D01*
G01X1227414Y526538D02*
Y525553D01*
G01X1227405Y508825D02*
Y507840D01*
G01X1227213Y521698D02*
Y526539D01*
G01Y507839D02*
Y512680D01*
G01X1227139Y524760D02*
Y525751D01*
G01X1227129Y508627D02*
Y509618D01*
G01X1227055Y512760D02*
Y511696D01*
G01Y522681D02*
Y521618D01*
G01X1226780D02*
Y522602D01*
G01Y512760D02*
Y511776D01*
G01X1225992Y521618D02*
Y522602D01*
G01Y512760D02*
Y511776D01*
G01X1225717Y512760D02*
Y511696D01*
G01Y522682D02*
Y521618D01*
G01X1225642Y525751D02*
Y524760D01*
G01X1225633Y509618D02*
Y508627D01*
G01X1225559Y521698D02*
Y526539D01*
G01Y507839D02*
Y512680D01*
G01X1225367Y525553D02*
Y526538D01*
G01X1225358Y507840D02*
Y508825D01*
G01X1225283Y526539D02*
Y507839D01*
G01X1225205Y509984D02*
Y503902D01*
G01Y530476D02*
Y524394D01*
G01X1225013Y526539D02*
Y525555D01*
G01X1225008Y526539D02*
Y525555D01*
G01X1225003Y508823D02*
Y507839D01*
G01X1224968Y510516D02*
Y506343D01*
G01Y528035D02*
Y523862D01*
G01X1223866D02*
Y528035D01*
G01Y506343D02*
Y510516D01*
G01X1223831Y508823D02*
Y507839D01*
G01X1223827Y508823D02*
Y507839D01*
G01Y526539D02*
Y525555D01*
G01X1223630Y509984D02*
Y503902D01*
G01Y530476D02*
Y524394D01*
G01X1223551Y507839D02*
Y526539D01*
G01X1223472Y508825D02*
Y507840D01*
G01Y526538D02*
Y525553D01*
G01X1223276Y525555D02*
Y530396D01*
G01Y503982D02*
Y508823D01*
G01X1223197Y524760D02*
Y525751D01*
G01Y508627D02*
Y509618D01*
G01X1223118Y504965D02*
Y503902D01*
G01Y530476D02*
Y529413D01*
G01X1222843Y504886D02*
Y503902D01*
G01Y530476D02*
Y529492D01*
G01X1222055D02*
Y530476D01*
G01Y504886D02*
Y503902D01*
G01X1221780Y504965D02*
Y503902D01*
G01Y530476D02*
Y529413D01*
G01X1221701Y509618D02*
Y508627D01*
G01Y525751D02*
Y524760D01*
G01X1221622Y525555D02*
Y530396D01*
G01Y503982D02*
Y508823D01*
G01X1221425Y525553D02*
Y526538D01*
G01Y507840D02*
Y508825D01*
G01X1221346Y526539D02*
Y507839D01*
G01X1221268Y509984D02*
Y503902D01*
G01Y530476D02*
Y524394D01*
G01X1221071Y508823D02*
Y507839D01*
G01Y526539D02*
Y525555D01*
G01X1221066Y526539D02*
Y525555D01*
G01X1221031Y510516D02*
Y506343D01*
G01Y528035D02*
Y523862D01*
G01X1219929D02*
Y528035D01*
G01Y506343D02*
Y510516D01*
G01X1219894Y526539D02*
Y525555D01*
G01X1219890Y508823D02*
Y507839D01*
G01X1219885Y508823D02*
Y507839D01*
G01X1219693Y509984D02*
Y503902D01*
G01Y530476D02*
Y524394D01*
G01X1219614Y507839D02*
Y526539D01*
G01X1219540Y526538D02*
Y525553D01*
G01X1219531Y508825D02*
Y507840D01*
G01X1219339Y521698D02*
Y526539D01*
G01Y507839D02*
Y512680D01*
G01X1219265Y524760D02*
Y525751D01*
G01X1219255Y508627D02*
Y509618D01*
G01X1219181Y512760D02*
Y511696D01*
G01Y522681D02*
Y521618D01*
G01X1218906Y512760D02*
Y511776D01*
G01Y522602D02*
Y521618D01*
G01X1218118Y512760D02*
Y511776D01*
G01Y522602D02*
Y521618D01*
G01X1217843Y512760D02*
Y511696D01*
G01Y522682D02*
Y521618D01*
G01X1217768Y525751D02*
Y524760D01*
G01X1217759Y509618D02*
Y508627D01*
G01X1217685Y521698D02*
Y526539D01*
G01Y507839D02*
Y512680D01*
G01X1217493Y525553D02*
Y526538D01*
G01X1217484Y507840D02*
Y508825D01*
G01X1217409Y526539D02*
Y507839D01*
G01X1217331Y509984D02*
Y503902D01*
G01Y530476D02*
Y524394D01*
G01X1217139Y526539D02*
Y525555D01*
G01X1217134Y526539D02*
Y525555D01*
G01X1217129Y508823D02*
Y507839D01*
G01X1217094Y510516D02*
Y506343D01*
G01Y528035D02*
Y523862D01*
G01X1215992D02*
Y528035D01*
G01Y506343D02*
Y510516D01*
G01X1215957Y508823D02*
Y507839D01*
G01X1215953Y508823D02*
Y507839D01*
G01Y526539D02*
Y525555D01*
G01X1215756Y509984D02*
Y503902D01*
G01Y530476D02*
Y524394D01*
G01X1215677Y507839D02*
Y526539D01*
G01X1215598Y508825D02*
Y507840D01*
G01Y526538D02*
Y525553D01*
G01X1215402Y525555D02*
Y530396D01*
G01Y503982D02*
Y508823D01*
G01X1215323Y524760D02*
Y525751D01*
G01Y508627D02*
Y509618D01*
G01X1215244Y504965D02*
Y503902D01*
G01Y530476D02*
Y529413D01*
G01X1214968Y504886D02*
Y503902D01*
G01Y530476D02*
Y529492D01*
G01X1214181D02*
Y530476D01*
G01Y504886D02*
Y503902D01*
G01X1213906Y504965D02*
Y503902D01*
G01Y530476D02*
Y529413D01*
G01X1213827Y509618D02*
Y508627D01*
G01Y525751D02*
Y524760D01*
G01X1213748Y525555D02*
Y530396D01*
G01Y503982D02*
Y508823D01*
G01X1213551Y525553D02*
Y526538D01*
G01Y507840D02*
Y508825D01*
G01X1213472Y526539D02*
Y507839D01*
G01X1213394Y509984D02*
Y503902D01*
G01Y530476D02*
Y524394D01*
G01X1213197Y508823D02*
Y507839D01*
G01Y526539D02*
Y525555D01*
G01X1213192Y526539D02*
Y525555D01*
G01X1213157Y510516D02*
Y506343D01*
G01Y528035D02*
Y523862D01*
G01X1212055D02*
Y528035D01*
G01Y506343D02*
Y510516D01*
G01X1212020Y526539D02*
Y525555D01*
G01X1212016Y508823D02*
Y507839D01*
G01X1212011Y508823D02*
Y507839D01*
G01X1211819Y509984D02*
Y503902D01*
G01Y530476D02*
Y524394D01*
G01X1211740Y507839D02*
Y526539D01*
G01X1211666Y526538D02*
Y525553D01*
G01X1211657Y508825D02*
Y507840D01*
G01X1211465Y521698D02*
Y526539D01*
G01Y507839D02*
Y512680D01*
G01X1211390Y524760D02*
Y525751D01*
G01X1211381Y508627D02*
Y509618D01*
G01X1211307Y512760D02*
Y511696D01*
G01Y522681D02*
Y521618D01*
G01X1211031D02*
Y522602D01*
G01Y512760D02*
Y511776D01*
G01X1226873Y525368D02*
X1226886Y524394D01*
G01X1225898Y509010D02*
X1225885Y509984D01*
G01X1222931Y525368D02*
X1222945Y524394D01*
G01X1221966Y509010D02*
X1221953Y509984D01*
G01X1218999Y525368D02*
X1219012Y524394D01*
G01X1218024Y509010D02*
X1218011Y509984D01*
G01X1215057Y525368D02*
X1215071Y524394D01*
G01X1214092Y509010D02*
X1214079Y509984D01*
G01X1211125Y525368D02*
X1211138Y524394D01*
G01X1210150Y509010D02*
X1210137Y509984D01*
G01X1227392Y509117D02*
X1227255Y515025D01*
G01X1227251Y514139D02*
X1227387Y508231D01*
G01X1225521Y520239D02*
X1225385Y526147D01*
G01X1225380Y525261D02*
X1225516Y519353D01*
G01X1223459Y509117D02*
X1223323Y515025D01*
G01X1223318Y514139D02*
X1223454Y508231D01*
G01X1221579Y520239D02*
X1221443Y526147D01*
G01X1221438Y525261D02*
X1221575Y519353D01*
G01X1219518Y509117D02*
X1219381Y515025D01*
G01X1219377Y514139D02*
X1219513Y508231D01*
G01X1217647Y520239D02*
X1217511Y526147D01*
G01X1217506Y525261D02*
X1217642Y519353D01*
G01X1215585Y509117D02*
X1215449Y515025D01*
G01X1215444Y514139D02*
X1215580Y508231D01*
G01X1213705Y520239D02*
X1213569Y526147D01*
G01X1213564Y525261D02*
X1213701Y519353D01*
G01X1211644Y509117D02*
X1211507Y515025D01*
G01X1211503Y514139D02*
X1211639Y508231D01*
G01X1209773Y520239D02*
X1209637Y526147D01*
G01X1209632Y525261D02*
X1209768Y519353D01*
G01X1227239Y520013D02*
X1227188Y520999D01*
G01X1227186Y520037D02*
X1227236Y519051D01*
G01X1225586Y514341D02*
X1225535Y515327D01*
G01X1225533Y514365D02*
X1225584Y513379D01*
G01X1223297Y520013D02*
X1223246Y520999D01*
G01X1223244Y520037D02*
X1223295Y519051D01*
G01X1221654Y514341D02*
X1221603Y515327D01*
G01X1221601Y514365D02*
X1221651Y513379D01*
G01X1219365Y520013D02*
X1219314Y520999D01*
G01X1219312Y520037D02*
X1219362Y519051D01*
G01X1217712Y514341D02*
X1217661Y515327D01*
G01X1217659Y514365D02*
X1217710Y513379D01*
G01X1215423Y520013D02*
X1215372Y520999D01*
G01X1215370Y520037D02*
X1215421Y519051D01*
G01X1213780Y514341D02*
X1213729Y515327D01*
G01X1213727Y514365D02*
X1213777Y513379D01*
G01X1211491Y520013D02*
X1211440Y520999D01*
G01X1211438Y520037D02*
X1211488Y519051D01*
G01X1209838Y514341D02*
X1209787Y515327D01*
G01X1209785Y514365D02*
X1209836Y513379D01*
G01X1207549Y520013D02*
X1207498Y520999D01*
G01X1207496Y520037D02*
X1207547Y519051D01*
G01X1194366Y524441D02*
X1194376Y524394D01*
G01X1195413Y509937D02*
X1195404Y509984D01*
G01X1190424Y524441D02*
X1190434Y524394D01*
G01X1191481Y509937D02*
X1191471Y509984D01*
G01X1186492Y524441D02*
X1186502Y524394D01*
G01X1187539Y509937D02*
X1187530Y509984D01*
G01X1182550Y524441D02*
X1182560Y524394D01*
G01X1183607Y509937D02*
X1183597Y509984D01*
G01X1221712Y508640D02*
X1221966Y509010D01*
G01X1221699Y509615D02*
X1221921Y509937D01*
G01X1217771Y508640D02*
X1218024Y509010D01*
G01X1217758Y509615D02*
X1217979Y509937D01*
G01X1227140Y524763D02*
X1226919Y524441D01*
G01X1227127Y525738D02*
X1226873Y525368D01*
G01X1213838Y508640D02*
X1214092Y509010D01*
G01X1213825Y509615D02*
X1214047Y509937D01*
G01X1223198Y524763D02*
X1222977Y524441D01*
G01X1223185Y525738D02*
X1222931Y525368D01*
G01X1209897Y508640D02*
X1210150Y509010D01*
G01X1209883Y509615D02*
X1210105Y509937D01*
G01X1219266Y524763D02*
X1219045Y524441D01*
G01X1219253Y525738D02*
X1218999Y525368D01*
G01X1205964Y508640D02*
X1206218Y509010D01*
G01X1205951Y509615D02*
X1206172Y509937D01*
G01X1215324Y524763D02*
X1215103Y524441D01*
G01X1215311Y525738D02*
X1215057Y525368D01*
G01X1202023Y508640D02*
X1202276Y509010D01*
G01X1202009Y509615D02*
X1202231Y509937D01*
G01X1211392Y524763D02*
X1211171Y524441D01*
G01X1211379Y525738D02*
X1211125Y525368D01*
G01X1198090Y508640D02*
X1198344Y509010D01*
G01X1198077Y509615D02*
X1198298Y509937D01*
G01X1207450Y524763D02*
X1207229Y524441D01*
G01X1207437Y525738D02*
X1207183Y525368D01*
G01X1217988Y509984D02*
X1217979Y509937D01*
G01X1219035Y524394D02*
X1219045Y524441D01*
G01X1214056Y509984D02*
X1214047Y509937D01*
G01X1215093Y524394D02*
X1215103Y524441D01*
G01X1210114Y509984D02*
X1210105Y509937D01*
G01X1211161Y524394D02*
X1211171Y524441D01*
G01X1206182Y509984D02*
X1206172Y509937D01*
G01X1207219Y524394D02*
X1207229Y524441D01*
G01X1202240Y509984D02*
X1202231Y509937D01*
G01X1203287Y524394D02*
X1203297Y524441D01*
G01X1198308Y509984D02*
X1198298Y509937D01*
G01X1199345Y524394D02*
X1199355Y524441D01*
G01X1194366Y509984D02*
X1194357Y509937D01*
G01X1213777Y520999D02*
X1213727Y520013D01*
G01X1211431Y513379D02*
X1211481Y514365D01*
G01X1211479Y515327D02*
X1211428Y514341D01*
G01X1209797Y519051D02*
X1209847Y520037D01*
G01X1209845Y520999D02*
X1209794Y520013D01*
G01X1207498Y513379D02*
X1207549Y514365D01*
G01X1207547Y515327D02*
X1207496Y514341D01*
G01X1205855Y519051D02*
X1205906Y520037D01*
G01X1205903Y520999D02*
X1205853Y520013D01*
G01X1203557Y513379D02*
X1203607Y514365D01*
G01X1203605Y515327D02*
X1203554Y514341D01*
G01X1201923Y519051D02*
X1201973Y520037D01*
G01X1201971Y520999D02*
X1201920Y520013D01*
G01X1199624Y513379D02*
X1199675Y514365D01*
G01X1199673Y515327D02*
X1199622Y514341D01*
G01X1197981Y519051D02*
X1198032Y520037D01*
G01X1198029Y520999D02*
X1197979Y520013D01*
G01X1195683Y513379D02*
X1195733Y514365D01*
G01X1195731Y515327D02*
X1195680Y514341D01*
G01X1194049Y519051D02*
X1194099Y520037D01*
G01X1194097Y520999D02*
X1194046Y520013D01*
G01X1191750Y513379D02*
X1191801Y514365D01*
G01X1191798Y515327D02*
X1191748Y514341D01*
G01X1190107Y519051D02*
X1190158Y520037D01*
G01X1190155Y520999D02*
X1190105Y520013D01*
G01X1211517Y519353D02*
X1211653Y525261D01*
G01X1211648Y526147D02*
X1211512Y520239D01*
G01X1209627Y508231D02*
X1209764Y514139D01*
G01X1209759Y515025D02*
X1209623Y509117D01*
G01X1207575Y519353D02*
X1207711Y525261D01*
G01X1207706Y526147D02*
X1207570Y520239D01*
G01X1205695Y508231D02*
X1205831Y514139D01*
G01X1205827Y515025D02*
X1205690Y509117D01*
G01X1203643Y519353D02*
X1203779Y525261D01*
G01X1203774Y526147D02*
X1203638Y520239D01*
G01X1201753Y508231D02*
X1201890Y514139D01*
G01X1201885Y515025D02*
X1201749Y509117D01*
G01X1199701Y519353D02*
X1199837Y525261D01*
G01X1199832Y526147D02*
X1199696Y520239D01*
G01X1197821Y508231D02*
X1197957Y514139D01*
G01X1197953Y515025D02*
X1197816Y509117D01*
G01X1195769Y519353D02*
X1195905Y525261D01*
G01X1195900Y526147D02*
X1195764Y520239D01*
G01X1193879Y508231D02*
X1194016Y514139D01*
G01X1194011Y515025D02*
X1193875Y509117D01*
G01X1191827Y519353D02*
X1191963Y525261D01*
G01X1191958Y526147D02*
X1191822Y520239D01*
G01X1189947Y508231D02*
X1190083Y514139D01*
G01X1190079Y515025D02*
X1189942Y509117D01*
G01X1187895Y519353D02*
X1188031Y525261D01*
G01X1188026Y526147D02*
X1187890Y520239D01*
G01X1211129Y509984D02*
X1211116Y509010D01*
G01X1210147Y524394D02*
X1210160Y525368D01*
G01X1207197Y509984D02*
X1207183Y509010D01*
G01X1206205Y524394D02*
X1206218Y525368D01*
G01X1203255Y509984D02*
X1203242Y509010D01*
G01X1202273Y524394D02*
X1202286Y525368D01*
G01X1199323Y509984D02*
X1199309Y509010D01*
G01X1198331Y524394D02*
X1198344Y525368D01*
G01X1195381Y509984D02*
X1195368Y509010D01*
G01X1194399Y524394D02*
X1194412Y525368D01*
G01X1191449Y509984D02*
X1191435Y509010D01*
G01X1190457Y524394D02*
X1190470Y525368D01*
G01X1187507Y509984D02*
X1187494Y509010D01*
G01X1210244Y521618D02*
Y522602D01*
G01Y511776D02*
Y512760D01*
G01X1209968D02*
Y511696D01*
G01Y522682D02*
Y521618D01*
G01X1209894Y525751D02*
Y524760D01*
G01X1209885Y509618D02*
Y508627D01*
G01X1209811Y521698D02*
Y526539D01*
G01Y507839D02*
Y512680D01*
G01X1209619Y525553D02*
Y526538D01*
G01X1209610Y507840D02*
Y508825D01*
G01X1209535Y526539D02*
Y507839D01*
G01X1209457Y509984D02*
Y503902D01*
G01Y530476D02*
Y524394D01*
G01X1209265Y526539D02*
Y525555D01*
G01X1209260Y526539D02*
Y525555D01*
G01X1209255Y508823D02*
Y507839D01*
G01X1209220Y510516D02*
Y506343D01*
G01Y528035D02*
Y523862D01*
G01X1208118D02*
Y528035D01*
G01Y506343D02*
Y510516D01*
G01X1208083Y508823D02*
Y507839D01*
G01X1208079Y508823D02*
Y507839D01*
G01Y526539D02*
Y525555D01*
G01X1207882Y509984D02*
Y503902D01*
G01Y530476D02*
Y524394D01*
G01X1207803Y507839D02*
Y526539D01*
G01X1207724Y508825D02*
Y507840D01*
G01Y526538D02*
Y525553D01*
G01X1207528Y525555D02*
Y530396D01*
G01Y503982D02*
Y508823D01*
G01X1207449Y524760D02*
Y525751D01*
G01Y508627D02*
Y509618D01*
G01X1207370Y504965D02*
Y503902D01*
G01Y530476D02*
Y529413D01*
G01X1207094Y504886D02*
Y503902D01*
G01Y530476D02*
Y529492D01*
G01X1206307D02*
Y530476D01*
G01Y504886D02*
Y503902D01*
G01X1206031Y504965D02*
Y503902D01*
G01Y530476D02*
Y529413D01*
G01X1205953Y509618D02*
Y508627D01*
G01Y525751D02*
Y524760D01*
G01X1205874Y525555D02*
Y530396D01*
G01Y503982D02*
Y508823D01*
G01X1205677Y525553D02*
Y526538D01*
G01Y507840D02*
Y508825D01*
G01X1205598Y526539D02*
Y507839D01*
G01X1205520Y509984D02*
Y503902D01*
G01Y530476D02*
Y524394D01*
G01X1205323Y508823D02*
Y507839D01*
G01Y526539D02*
Y525555D01*
G01X1205318Y526539D02*
Y525555D01*
G01X1205283Y510516D02*
Y506343D01*
G01Y528035D02*
Y523862D01*
G01X1204181D02*
Y528035D01*
G01Y506343D02*
Y510516D01*
G01X1204146Y526539D02*
Y525555D01*
G01X1204142Y508823D02*
Y507839D01*
G01X1204137Y508823D02*
Y507839D01*
G01X1203945Y509984D02*
Y503902D01*
G01Y530476D02*
Y524394D01*
G01X1203866Y507839D02*
Y526539D01*
G01X1203792Y526538D02*
Y525553D01*
G01X1203783Y508825D02*
Y507840D01*
G01X1203591Y521698D02*
Y526539D01*
G01Y507839D02*
Y512680D01*
G01X1203516Y524760D02*
Y525751D01*
G01X1203507Y508627D02*
Y509618D01*
G01X1203433Y512760D02*
Y511696D01*
G01Y522681D02*
Y521618D01*
G01X1203157D02*
Y522602D01*
G01Y512760D02*
Y511776D01*
G01X1202370Y521618D02*
Y522602D01*
G01Y511776D02*
Y512760D01*
G01X1202094D02*
Y511696D01*
G01Y522682D02*
Y521618D01*
G01X1202020Y525751D02*
Y524760D01*
G01X1202011Y509618D02*
Y508627D01*
G01X1201937Y521698D02*
Y526539D01*
G01Y507839D02*
Y512680D01*
G01X1201745Y525553D02*
Y526538D01*
G01X1201735Y507840D02*
Y508825D01*
G01X1201661Y526539D02*
Y507839D01*
G01X1201583Y509984D02*
Y503902D01*
G01Y530476D02*
Y524394D01*
G01X1201390Y526539D02*
Y525555D01*
G01X1201386Y526539D02*
Y525555D01*
G01X1201381Y508823D02*
Y507839D01*
G01X1201346Y510516D02*
Y506343D01*
G01Y528035D02*
Y523862D01*
G01X1200244D02*
Y528035D01*
G01Y506343D02*
Y510516D01*
G01X1200209Y508823D02*
Y507839D01*
G01X1200205Y508823D02*
Y507839D01*
G01Y526539D02*
Y525555D01*
G01X1200008Y509984D02*
Y503902D01*
G01Y530476D02*
Y524394D01*
G01X1199929Y507839D02*
Y526539D01*
G01X1199850Y508825D02*
Y507840D01*
G01Y526538D02*
Y525553D01*
G01X1199654Y525555D02*
Y530396D01*
G01Y503982D02*
Y508823D01*
G01X1199575Y524760D02*
Y525751D01*
G01Y508627D02*
Y509618D01*
G01X1199496Y504965D02*
Y503902D01*
G01Y530476D02*
Y529413D01*
G01X1199220Y504886D02*
Y503902D01*
G01Y530476D02*
Y529492D01*
G01X1198433D02*
Y530476D01*
G01Y504886D02*
Y503902D01*
G01X1198157Y504965D02*
Y503902D01*
G01Y530476D02*
Y529413D01*
G01X1198079Y509618D02*
Y508627D01*
G01Y525751D02*
Y524760D01*
G01X1198000Y525555D02*
Y530396D01*
G01Y503982D02*
Y508823D01*
G01X1197803Y525553D02*
Y526538D01*
G01Y507840D02*
Y508825D01*
G01X1197724Y526539D02*
Y507839D01*
G01X1197646Y509984D02*
Y503902D01*
G01Y530476D02*
Y524394D01*
G01X1197449Y508823D02*
Y507839D01*
G01Y526539D02*
Y525555D01*
G01X1197444Y526539D02*
Y525555D01*
G01X1197409Y510516D02*
Y506343D01*
G01Y528035D02*
Y523862D01*
G01X1196307D02*
Y528035D01*
G01Y506343D02*
Y510516D01*
G01X1196272Y526539D02*
Y525555D01*
G01X1196268Y508823D02*
Y507839D01*
G01X1196263Y508823D02*
Y507839D01*
G01X1196071Y509984D02*
Y503902D01*
G01Y530476D02*
Y524394D01*
G01X1195992Y507839D02*
Y526539D01*
G01X1195918Y526538D02*
Y525553D01*
G01X1195909Y508825D02*
Y507840D01*
G01X1195717Y521698D02*
Y526539D01*
G01Y507839D02*
Y512680D01*
G01X1195642Y524760D02*
Y525751D01*
G01X1195633Y508627D02*
Y509618D01*
G01X1195559Y512760D02*
Y511696D01*
G01Y522681D02*
Y521618D01*
G01X1195283Y512760D02*
Y511776D01*
G01Y522602D02*
Y521618D01*
G01X1194496Y512760D02*
Y511776D01*
G01Y522602D02*
Y521618D01*
G01X1194220Y512760D02*
Y511696D01*
G01Y522682D02*
Y521618D01*
G01X1194146Y525751D02*
Y524760D01*
G01X1194137Y509618D02*
Y508627D01*
G01X1194063Y521698D02*
Y526539D01*
G01Y507839D02*
Y512680D01*
G01X1193871Y525553D02*
Y526538D01*
G01X1193861Y507840D02*
Y508825D01*
G01X1193787Y526539D02*
Y507839D01*
G01X1193709Y509984D02*
Y503902D01*
G01Y530476D02*
Y524394D01*
G01X1193516Y526539D02*
Y525555D01*
G01X1193512Y526539D02*
Y525555D01*
G01X1193507Y508823D02*
Y507839D01*
G01X1193472Y510516D02*
Y506343D01*
G01Y528035D02*
Y523862D01*
G01X1192370D02*
Y528035D01*
G01Y506343D02*
Y510516D01*
G01X1192335Y508823D02*
Y507839D01*
G01X1192331Y508823D02*
Y507839D01*
G01Y526539D02*
Y525555D01*
G01X1192134Y509984D02*
Y503902D01*
G01Y530476D02*
Y524394D01*
G01X1192055Y507839D02*
Y526539D01*
G01X1191976Y508825D02*
Y507840D01*
G01Y526538D02*
Y525553D01*
G01X1191780Y525555D02*
Y530396D01*
G01Y503982D02*
Y508823D01*
G01X1191701Y524760D02*
Y525751D01*
G01Y508627D02*
Y509618D01*
G01X1191622Y504965D02*
Y503902D01*
G01Y530476D02*
Y529413D01*
G01X1191346Y504886D02*
Y503902D01*
G01Y530476D02*
Y529492D01*
G01X1190559D02*
Y530476D01*
G01Y504886D02*
Y503902D01*
G01X1190283Y504965D02*
Y503902D01*
G01Y530476D02*
Y529413D01*
G01X1190205Y509618D02*
Y508627D01*
G01Y525751D02*
Y524760D01*
G01X1190126Y525555D02*
Y530396D01*
G01Y503982D02*
Y508823D01*
G01X1189929Y525553D02*
Y526538D01*
G01Y507840D02*
Y508825D01*
G01X1189850Y526539D02*
Y507839D01*
G01X1189772Y509984D02*
Y503902D01*
G01Y530476D02*
Y524394D01*
G01X1189575Y508823D02*
Y507839D01*
G01Y526539D02*
Y525555D01*
G01X1189570Y526539D02*
Y525555D01*
G01X1189535Y510516D02*
Y506343D01*
G01Y528035D02*
Y523862D01*
G01X1188433D02*
Y528035D01*
G01Y506343D02*
Y510516D01*
G01X1188398Y526539D02*
Y525555D01*
G01X1188394Y508823D02*
Y507839D01*
G01X1188389Y508823D02*
Y507839D01*
G01X1188197Y509984D02*
Y503902D01*
G01Y530476D02*
Y524394D01*
G01X1188118Y507839D02*
Y526539D01*
G01X1188044Y526538D02*
Y525553D01*
G01X1188035Y508825D02*
Y507840D01*
G01X1187843Y521698D02*
Y526539D01*
G01Y507839D02*
Y512680D01*
G01X1187768Y524760D02*
Y525751D01*
G01X1187759Y508627D02*
Y509618D01*
G01X1187685Y512760D02*
Y511696D01*
G01Y522681D02*
Y521618D01*
G01X1187409Y512760D02*
Y511776D01*
G01Y522602D02*
Y521618D01*
G01X1186622Y512760D02*
Y511776D01*
G01Y522602D02*
Y521618D01*
G01X1186346Y512760D02*
Y511696D01*
G01Y522682D02*
Y521618D01*
G01X1186272Y525751D02*
Y524760D01*
G01X1186263Y509618D02*
Y508627D01*
G01X1207183Y525368D02*
X1207197Y524394D01*
G01X1206218Y509010D02*
X1206205Y509984D01*
G01X1203251Y525368D02*
X1203264Y524394D01*
G01X1202276Y509010D02*
X1202263Y509984D01*
G01X1199309Y525368D02*
X1199323Y524394D01*
G01X1198344Y509010D02*
X1198331Y509984D01*
G01X1195377Y525368D02*
X1195390Y524394D01*
G01X1194402Y509010D02*
X1194389Y509984D01*
G01X1191435Y525368D02*
X1191449Y524394D01*
G01X1190470Y509010D02*
X1190457Y509984D01*
G01X1187503Y525368D02*
X1187516Y524394D01*
G01X1186528Y509010D02*
X1186515Y509984D01*
G01X1207711Y509117D02*
X1207575Y515025D01*
G01X1207570Y514139D02*
X1207706Y508231D01*
G01X1205831Y520239D02*
X1205695Y526147D01*
G01X1205690Y525261D02*
X1205827Y519353D01*
G01X1203770Y509117D02*
X1203633Y515025D01*
G01X1203629Y514139D02*
X1203765Y508231D01*
G01X1201899Y520239D02*
X1201763Y526147D01*
G01X1201758Y525261D02*
X1201894Y519353D01*
G01X1199837Y509117D02*
X1199701Y515025D01*
G01X1199696Y514139D02*
X1199832Y508231D01*
G01X1197957Y520239D02*
X1197821Y526147D01*
G01X1197816Y525261D02*
X1197953Y519353D01*
G01X1195896Y509117D02*
X1195759Y515025D01*
G01X1195754Y514139D02*
X1195891Y508231D01*
G01X1194025Y520239D02*
X1193889Y526147D01*
G01X1193884Y525261D02*
X1194020Y519353D01*
G01X1191963Y509117D02*
X1191827Y515025D01*
G01X1191822Y514139D02*
X1191958Y508231D01*
G01X1190083Y520239D02*
X1189947Y526147D01*
G01X1189942Y525261D02*
X1190079Y519353D01*
G01X1188021Y509117D02*
X1187885Y515025D01*
G01X1187880Y514139D02*
X1188017Y508231D01*
G01X1186151Y520239D02*
X1186015Y526147D01*
G01X1186010Y525261D02*
X1186146Y519353D01*
G01X1205906Y514341D02*
X1205855Y515327D01*
G01X1205853Y514365D02*
X1205903Y513379D01*
G01X1203617Y520013D02*
X1203566Y520999D01*
G01X1203564Y520037D02*
X1203614Y519051D01*
G01X1201964Y514341D02*
X1201913Y515327D01*
G01X1201911Y514365D02*
X1201962Y513379D01*
G01X1199675Y520013D02*
X1199624Y520999D01*
G01X1199622Y520037D02*
X1199673Y519051D01*
G01X1198032Y514341D02*
X1197981Y515327D01*
G01X1197979Y514365D02*
X1198029Y513379D01*
G01X1195742Y520013D02*
X1195692Y520999D01*
G01X1195690Y520037D02*
X1195740Y519051D01*
G01X1194090Y514341D02*
X1194039Y515327D01*
G01X1194037Y514365D02*
X1194088Y513379D01*
G01X1191801Y520013D02*
X1191750Y520999D01*
G01X1191748Y520037D02*
X1191798Y519051D01*
G01X1190158Y514341D02*
X1190107Y515327D01*
G01X1190105Y514365D02*
X1190155Y513379D01*
G01X1187868Y520013D02*
X1187818Y520999D01*
G01X1187816Y520037D02*
X1187866Y519051D01*
G01X1186216Y514341D02*
X1186165Y515327D01*
G01X1186163Y514365D02*
X1186213Y513379D01*
G01X1183927Y520013D02*
X1183876Y520999D01*
G01X1183874Y520037D02*
X1183924Y519051D01*
G01X1194149Y508640D02*
X1194402Y509010D01*
G01X1194135Y509615D02*
X1194357Y509937D01*
G01X1203518Y524763D02*
X1203297Y524441D01*
G01X1203505Y525738D02*
X1203251Y525368D01*
G01X1190216Y508640D02*
X1190470Y509010D01*
G01X1190203Y509615D02*
X1190424Y509937D01*
G01X1199576Y524763D02*
X1199355Y524441D01*
G01X1199563Y525738D02*
X1199309Y525368D01*
G01X1186275Y508640D02*
X1186528Y509010D01*
G01X1186261Y509615D02*
X1186483Y509937D01*
G01X1195644Y524763D02*
X1195423Y524441D01*
G01X1195631Y525738D02*
X1195377Y525368D01*
G01X1191702Y524763D02*
X1191481Y524441D01*
G01X1191689Y525738D02*
X1191435Y525368D01*
G01X1187770Y524763D02*
X1187549Y524441D01*
G01X1187757Y525738D02*
X1187503Y525368D01*
G01X1183828Y524763D02*
X1183607Y524441D01*
G01X1183815Y525738D02*
X1183561Y525368D01*
G01X1195413Y524394D02*
X1195423Y524441D01*
G01X1190434Y509984D02*
X1190424Y509937D01*
G01X1191471Y524394D02*
X1191481Y524441D01*
G01X1186492Y509984D02*
X1186483Y509937D01*
G01X1187539Y524394D02*
X1187549Y524441D01*
G01X1182560Y509984D02*
X1182550Y509937D01*
G01X1183597Y524394D02*
X1183607Y524441D01*
G01X1187809Y513379D02*
X1187859Y514365D01*
G01X1187857Y515327D02*
X1187806Y514341D01*
G01X1186175Y519051D02*
X1186225Y520037D01*
G01X1186223Y520999D02*
X1186172Y520013D01*
G01X1183876Y513379D02*
X1183927Y514365D01*
G01X1183924Y515327D02*
X1183874Y514341D01*
G01X1186005Y508231D02*
X1186142Y514139D01*
G01X1186137Y515025D02*
X1186001Y509117D01*
G01X1183953Y519353D02*
X1184089Y525261D01*
G01X1184084Y526147D02*
X1183948Y520239D01*
G01X1186525Y524394D02*
X1186538Y525368D01*
G01X1183575Y509984D02*
X1183561Y509010D01*
G01X1182583Y524394D02*
X1182596Y525368D01*
G01X1186189Y521698D02*
Y526539D01*
G01Y507839D02*
Y512680D01*
G01X1185997Y525553D02*
Y526538D01*
G01X1185987Y507840D02*
Y508825D01*
G01X1185913Y526539D02*
Y507839D01*
G01X1185835Y509984D02*
Y503902D01*
G01Y530476D02*
Y524394D01*
G01X1185642Y526539D02*
Y525555D01*
G01X1185638Y526539D02*
Y525555D01*
G01X1185633Y508823D02*
Y507839D01*
G01X1185598Y510516D02*
Y506343D01*
G01Y528035D02*
Y523862D01*
G01X1184496D02*
Y528035D01*
G01Y506343D02*
Y510516D01*
G01X1184461Y508823D02*
Y507839D01*
G01X1184457Y508823D02*
Y507839D01*
G01Y526539D02*
Y525555D01*
G01X1184260Y509984D02*
Y503902D01*
G01Y530476D02*
Y524394D01*
G01X1184181Y507839D02*
Y526539D01*
G01X1184102Y508825D02*
Y507840D01*
G01Y526538D02*
Y525553D01*
G01X1183906Y525555D02*
Y530396D01*
G01Y503982D02*
Y508823D01*
G01X1183827Y524760D02*
Y525751D01*
G01Y508627D02*
Y509618D01*
G01X1183748Y504965D02*
Y503902D01*
G01Y530476D02*
Y529413D01*
G01X1183472Y504886D02*
Y503902D01*
G01Y530476D02*
Y529492D01*
G01X1182685D02*
Y530476D01*
G01Y504886D02*
Y503902D01*
G01X1182409Y504965D02*
Y503902D01*
G01Y530476D02*
Y529413D01*
G01X1183561Y525368D02*
X1183575Y524394D01*
G01X1182596Y509010D02*
X1182583Y509984D01*
G01X1184089Y509117D02*
X1183953Y515025D01*
G01X1183948Y514139D02*
X1184084Y508231D01*
G01X1152331Y605754D02*
Y605751D01*
G01X1152332Y605756D02*
X1152331Y605754D01*
G01X1152332Y605757D02*
Y605756D01*
G01X1150834Y588624D02*
X1150835Y588627D01*
G01X1150834Y588622D02*
Y588624D01*
G01X1150833Y588621D02*
X1150834Y588622D01*
G01X1158708Y588624D02*
X1158709Y588627D01*
G01X1158708Y588622D02*
Y588624D01*
G01X1158707Y588621D02*
X1158708Y588622D01*
G01X1148744Y600142D02*
X1149122Y600314D01*
G01X1148376Y599965D02*
X1148744Y600142D01*
G01X1148020Y599783D02*
X1148376Y599965D01*
G01X1152594Y606353D02*
X1152588Y606147D01*
G01X1152600Y606485D02*
X1152594Y606353D01*
G01X1152606Y606538D02*
X1152600Y606485D01*
G01X1150571Y588025D02*
X1150577Y588231D01*
G01X1150565Y587893D02*
X1150571Y588025D01*
G01X1150559Y587840D02*
X1150565Y587893D01*
G01X1154765Y604209D02*
X1154764Y603807D01*
G01X1154767Y604537D02*
X1154765Y604209D01*
G01X1154772Y604733D02*
X1154767Y604537D01*
G01X1154776Y604763D02*
X1154772Y604733D01*
G01X1150823Y590197D02*
X1150822Y590571D01*
G01X1150825Y589887D02*
X1150823Y590197D01*
G01X1150829Y589680D02*
X1150825Y589887D01*
G01X1150833Y589606D02*
X1150829Y589680D01*
G01X1152342Y604181D02*
X1152343Y603807D01*
G01X1152340Y604491D02*
X1152342Y604181D01*
G01X1152337Y604698D02*
X1152340Y604491D01*
G01X1152332Y604772D02*
X1152337Y604698D01*
G01X1150565Y606485D02*
X1150559Y606538D01*
G01X1150571Y606353D02*
X1150565Y606485D01*
G01X1150577Y606147D02*
X1150571Y606353D01*
G01X1152600Y587893D02*
X1152606Y587840D01*
G01X1152594Y588025D02*
X1152600Y587893D01*
G01X1152588Y588231D02*
X1152594Y588025D01*
G01X1154507Y606485D02*
X1154501Y606538D01*
G01X1154513Y606353D02*
X1154507Y606485D01*
G01X1154519Y606147D02*
X1154513Y606353D01*
G01X1156532Y587893D02*
X1156539Y587840D01*
G01X1156526Y588025D02*
X1156532Y587893D01*
G01X1156521Y588231D02*
X1156526Y588025D01*
G01X1150564Y605511D02*
X1150559Y605553D01*
G01X1150568Y605413D02*
X1150564Y605511D01*
G01X1150572Y605261D02*
X1150568Y605413D01*
G01X1152602Y588867D02*
X1152606Y588825D01*
G01X1152597Y588965D02*
X1152602Y588867D01*
G01X1152593Y589117D02*
X1152597Y588965D01*
G01X1154505Y605511D02*
X1154501Y605553D01*
G01X1154510Y605413D02*
X1154505Y605511D01*
G01X1154514Y605261D02*
X1154510Y605413D01*
G01X1156534Y588867D02*
X1156539Y588825D01*
G01X1156530Y588965D02*
X1156534Y588867D01*
G01X1156525Y589117D02*
X1156530Y588965D01*
G01X1154762Y589645D02*
X1154767Y589615D01*
G01X1154758Y589841D02*
X1154762Y589645D01*
G01X1154755Y590169D02*
X1154758Y589841D01*
G01X1154754Y590571D02*
X1154755Y590169D01*
G01X1156277Y604733D02*
X1156273Y604763D01*
G01X1156281Y604537D02*
X1156277Y604733D01*
G01X1156284Y604209D02*
X1156281Y604537D01*
G01X1156285Y603807D02*
X1156284Y604209D01*
G01X1150825Y588770D02*
X1150833Y588621D01*
G01X1150818Y589184D02*
X1150825Y588770D01*
G01X1150813Y589804D02*
X1150818Y589184D01*
G01X1150811Y590552D02*
X1150813Y589804D01*
G01X1152341Y605608D02*
X1152332Y605757D01*
G01X1152348Y605193D02*
X1152341Y605608D01*
G01X1152353Y604573D02*
X1152348Y605193D01*
G01X1152354Y603826D02*
X1152353Y604573D01*
G01X1158699Y588770D02*
X1158707Y588621D01*
G01X1158692Y589184D02*
X1158699Y588770D01*
G01X1158687Y589804D02*
X1158692Y589184D01*
G01X1158685Y590552D02*
X1158687Y589804D01*
G01X1150829Y604698D02*
X1150833Y604772D01*
G01X1150825Y604491D02*
X1150829Y604698D01*
G01X1150823Y604181D02*
X1150825Y604491D01*
G01X1150822Y603807D02*
X1150823Y604181D01*
G01X1152337Y589680D02*
X1152332Y589606D01*
G01X1152340Y589887D02*
X1152337Y589680D01*
G01X1152342Y590197D02*
X1152340Y589887D01*
G01X1152343Y590571D02*
X1152342Y590197D01*
G01X1158703Y604698D02*
X1158707Y604772D01*
G01X1158699Y604491D02*
X1158703Y604698D01*
G01X1158697Y604181D02*
X1158699Y604491D01*
G01X1158696Y603807D02*
X1158697Y604181D01*
G01X1150813Y604573D02*
X1150811Y603826D01*
G01X1150818Y605193D02*
X1150813Y604573D01*
G01X1150825Y605608D02*
X1150818Y605193D01*
G01X1150833Y605757D02*
X1150825Y605608D01*
G01X1152353Y589804D02*
X1152354Y590552D01*
G01X1152348Y589184D02*
X1152353Y589804D01*
G01X1152341Y588770D02*
X1152348Y589184D01*
G01X1152332Y588621D02*
X1152341Y588770D01*
G01X1158687Y604573D02*
X1158685Y603826D01*
G01X1158692Y605193D02*
X1158687Y604573D01*
G01X1158699Y605608D02*
X1158692Y605193D01*
G01X1158707Y605757D02*
X1158699Y605608D01*
G01X1150833Y589607D02*
Y589606D01*
G01X1150834Y589610D02*
X1150833Y589607D01*
G01X1150835Y589617D02*
X1150834Y589610D01*
G01X1152332Y604771D02*
Y604772D01*
G01X1152331Y604768D02*
X1152332Y604771D01*
G01X1152331Y604761D02*
Y604768D01*
G01X1158707Y589607D02*
Y589606D01*
G01X1158708Y589610D02*
X1158707Y589607D01*
G01X1158709Y589617D02*
X1158708Y589610D01*
G01X1150568Y588965D02*
X1150572Y589117D01*
G01X1150564Y588867D02*
X1150568Y588965D01*
G01X1150559Y588825D02*
X1150564Y588867D01*
G01X1152597Y605413D02*
X1152593Y605261D01*
G01X1152602Y605511D02*
X1152597Y605413D01*
G01X1152606Y605553D02*
X1152602Y605511D01*
G01X1154500Y588965D02*
X1154505Y589117D01*
G01X1154496Y588867D02*
X1154500Y588965D01*
G01X1154491Y588825D02*
X1154496Y588867D01*
G01X1156539Y605413D02*
X1156535Y605261D01*
G01X1156543Y605511D02*
X1156539Y605413D01*
G01X1156548Y605553D02*
X1156543Y605511D01*
G01X1158442Y588965D02*
X1158446Y589117D01*
G01X1158438Y588867D02*
X1158442Y588965D01*
G01X1158433Y588825D02*
X1158438Y588867D01*
G01X1156536Y606353D02*
X1156530Y606147D01*
G01X1156542Y606485D02*
X1156536Y606353D01*
G01X1156548Y606538D02*
X1156542Y606485D01*
G01X1154504Y588025D02*
X1154509Y588231D01*
G01X1154498Y587893D02*
X1154504Y588025D01*
G01X1154491Y587840D02*
X1154498Y587893D01*
G01X1158445Y588025D02*
X1158451Y588231D01*
G01X1158439Y587893D02*
X1158445Y588025D01*
G01X1158433Y587840D02*
X1158439Y587893D01*
G01X1156275Y590169D02*
X1156276Y590571D01*
G01X1156272Y589841D02*
X1156275Y590169D01*
G01X1156268Y589645D02*
X1156272Y589841D01*
G01X1156263Y589615D02*
X1156268Y589645D01*
G01X1158697Y590197D02*
X1158696Y590571D01*
G01X1158699Y589887D02*
X1158697Y590197D01*
G01X1158703Y589680D02*
X1158699Y589887D01*
G01X1158707Y589606D02*
X1158703Y589680D01*
G01X1158439Y606485D02*
X1158433Y606538D01*
G01X1158445Y606353D02*
X1158439Y606485D01*
G01X1158451Y606147D02*
X1158445Y606353D01*
G01X1158438Y605511D02*
X1158433Y605553D01*
G01X1158442Y605413D02*
X1158438Y605511D01*
G01X1158446Y605261D02*
X1158442Y605413D01*
G01X1152332Y588622D02*
Y588621D01*
G01X1152331Y588624D02*
X1152332Y588622D01*
G01X1152331Y588627D02*
Y588624D01*
G01X1150834Y605756D02*
X1150833Y605757D01*
G01X1150834Y605754D02*
Y605756D01*
G01X1150835Y605751D02*
X1150834Y605754D01*
G01X1158708Y605756D02*
X1158707Y605757D01*
G01X1158708Y605754D02*
Y605756D01*
G01X1158709Y605751D02*
X1158708Y605754D01*
G01X1152331Y589610D02*
Y589617D01*
G01X1152332Y589607D02*
X1152331Y589610D01*
G01X1152332Y589606D02*
Y589607D01*
G01X1150834Y604768D02*
X1150835Y604761D01*
G01X1150833Y604771D02*
X1150834Y604768D01*
G01X1150833Y604772D02*
Y604771D01*
G01X1158708Y604768D02*
X1158709Y604761D01*
G01X1158707Y604771D02*
X1158708Y604768D01*
G01X1158707Y604772D02*
Y604771D01*
G01X1148744Y594236D02*
X1149122Y594064D01*
G01X1148376Y594412D02*
X1148744Y594236D01*
G01X1148020Y594595D02*
X1148376Y594412D01*
G01X1156569Y588823D02*
X1156584D01*
G01X1156554Y588824D02*
X1156569Y588823D01*
G01X1156539Y588825D02*
X1156554Y588824D01*
G01X1158403Y588823D02*
X1158388D01*
G01X1158418Y588824D02*
X1158403Y588823D01*
G01X1158433Y588825D02*
X1158418Y588824D01*
G01X1150529Y588823D02*
X1150514D01*
G01X1150544Y588824D02*
X1150529Y588823D01*
G01X1150559Y588825D02*
X1150544Y588824D01*
G01X1154461Y587839D02*
X1154446D01*
G01X1154476D02*
X1154461D01*
G01X1154491Y587840D02*
X1154476Y587839D01*
G01X1152621D02*
X1152606Y587840D01*
G01X1152636Y587839D02*
X1152621D01*
G01X1152651D02*
X1152636D01*
G01X1156554D02*
X1156539Y587840D01*
G01X1156569Y587839D02*
X1156554D01*
G01X1156584D02*
X1156569D01*
G01X1150544Y606539D02*
X1150559Y606538D01*
G01X1150529Y606539D02*
X1150544D01*
G01X1150514D02*
X1150529D01*
G01X1154486D02*
X1154501Y606538D01*
G01X1154471Y606539D02*
X1154486D01*
G01X1154456D02*
X1154471D01*
G01X1158418D02*
X1158433Y606538D01*
G01X1158403Y606539D02*
X1158418D01*
G01X1158388D02*
X1158403D01*
G01X1152621Y588824D02*
X1152606Y588825D01*
G01X1152636Y588823D02*
X1152621Y588824D01*
G01X1152651Y588823D02*
X1152636D01*
G01X1150544Y605554D02*
X1150559Y605553D01*
G01X1150529Y605555D02*
X1150544Y605554D01*
G01X1150514Y605555D02*
X1150529D01*
G01X1154486Y605554D02*
X1154501Y605553D01*
G01X1154471Y605555D02*
X1154486Y605554D01*
G01X1154456Y605555D02*
X1154471D01*
G01X1158418Y605554D02*
X1158433Y605553D01*
G01X1158403Y605555D02*
X1158418Y605554D01*
G01X1158388Y605555D02*
X1158403D01*
G01X1156578D02*
X1156593D01*
G01X1156563Y605554D02*
X1156578Y605555D01*
G01X1156548Y605553D02*
X1156563Y605554D01*
G01X1152636Y605555D02*
X1152651D01*
G01X1152621Y605554D02*
X1152636Y605555D01*
G01X1152606Y605553D02*
X1152621Y605554D01*
G01X1156578Y606539D02*
X1156593D01*
G01X1156563D02*
X1156578D01*
G01X1156548Y606538D02*
X1156563Y606539D01*
G01X1152764Y610476D02*
X1150402D01*
G01X1156701D02*
X1154339D01*
G01X1160638D02*
X1158276D01*
G01X1152252Y609492D02*
X1150913D01*
G01X1160126D02*
X1158787D01*
G01X1158630Y609394D02*
X1160283D01*
G01X1150756D02*
X1152409D01*
G01X1152764Y609295D02*
X1150402D01*
G01X1156701D02*
X1154339D01*
G01X1160638D02*
X1158276D01*
G01X1152409Y608902D02*
X1150756D01*
G01X1160283D02*
X1158630D01*
G01X1153000Y608035D02*
X1150165D01*
G01X1156937D02*
X1154102D01*
G01X1160874D02*
X1158039D01*
G01X1152409Y607130D02*
X1150756D01*
G01X1160283D02*
X1158630D01*
G01Y606638D02*
X1160283D01*
G01X1150756D02*
X1152409D01*
G01X1153000Y606539D02*
X1150165D01*
G01X1156937D02*
X1154102D01*
G01X1160874D02*
X1158039D01*
G01Y606382D02*
X1158630D01*
G01X1156346D02*
X1156937D01*
G01X1154102D02*
X1154693D01*
G01X1152409D02*
X1153000D01*
G01X1150165D02*
X1150756D01*
G01X1158451Y606147D02*
X1160462D01*
G01X1154519D02*
X1156530D01*
G01X1150577D02*
X1152588D01*
G01X1152332Y605757D02*
X1150833D01*
G01X1156274D02*
X1154775D01*
G01X1160206D02*
X1158707D01*
G01X1158720Y605738D02*
X1160193D01*
G01X1154788D02*
X1156261D01*
G01X1150846D02*
X1152319D01*
G01X1150756Y605713D02*
X1150165D01*
G01X1153000D02*
X1152409D01*
G01X1154693D02*
X1154102D01*
G01X1156937D02*
X1156346D01*
G01X1158630D02*
X1158039D01*
G01Y605555D02*
X1160874D01*
G01X1154102D02*
X1156937D01*
G01X1150165D02*
X1153000D01*
G01X1156346Y605457D02*
X1154693D01*
G01X1152065Y605368D02*
X1151100D01*
G01X1156007D02*
X1155042D01*
G01X1159939D02*
X1158974D01*
G01X1154102Y605358D02*
X1154417D01*
G01X1150480D02*
X1150165D01*
G01X1153000D02*
X1152685D01*
G01X1156937D02*
X1156622D01*
G01X1158354D02*
X1158039D01*
G01X1152593Y605261D02*
X1150572D01*
G01X1156535D02*
X1154514D01*
G01X1160467D02*
X1158446D01*
G01X1154693Y604965D02*
X1156346D01*
G01X1152332Y604772D02*
X1150833D01*
G01X1156274D02*
X1154775D01*
G01X1160206D02*
X1158707D01*
G01X1152331Y604763D02*
X1150834D01*
G01X1156273D02*
X1154776D01*
G01X1160205D02*
X1158708D01*
G01X1158928Y604441D02*
X1159985D01*
G01X1154996D02*
X1156053D01*
G01X1151054D02*
X1152111D01*
G01X1158276Y604394D02*
X1160638D01*
G01X1154339D02*
X1156701D01*
G01X1150402D02*
X1152764D01*
G01X1158039Y603862D02*
X1158354D01*
G01X1156622D02*
X1156937D01*
G01X1152685D02*
X1153000D01*
G01X1154102D02*
X1154417D01*
G01X1150165D02*
X1150480D01*
G01X1158685Y603826D02*
X1160228D01*
G01X1154753D02*
X1156296D01*
G01X1150811D02*
X1152354D01*
G01X1158696Y603807D02*
X1160217D01*
G01X1154764D02*
X1156285D01*
G01X1150822D02*
X1152343D01*
G01X1154693Y603193D02*
X1156346D01*
G01Y602701D02*
X1154693D01*
G01X1156189Y602602D02*
X1154850D01*
G01Y601618D02*
X1156189D01*
G01X1152380Y600999D02*
X1150785D01*
G01X1156322D02*
X1154727D01*
G01X1160254D02*
X1158659D01*
G01X1152685Y600890D02*
X1150480D01*
G01X1156622D02*
X1154417D01*
G01X1160559D02*
X1158354D01*
G01X1432617Y600732D02*
X1148422D01*
G01X1152452Y600239D02*
X1150713D01*
G01X1156394D02*
X1154655D01*
G01X1160326D02*
X1158587D01*
G01X1158661Y600037D02*
X1160252D01*
G01X1154729D02*
X1156320D01*
G01X1150787D02*
X1152378D01*
G01X1158609Y600013D02*
X1160305D01*
G01X1154676D02*
X1156372D01*
G01X1150735D02*
X1152431D01*
G01X1152438Y599945D02*
X1150728D01*
G01X1156379D02*
X1154669D01*
G01X1160312D02*
X1158602D01*
G01X1158583Y599353D02*
X1160331D01*
G01X1154650D02*
X1156399D01*
G01X1150708D02*
X1152457D01*
G01X1152428Y599051D02*
X1150737D01*
G01X1156370D02*
X1154679D01*
G01X1160302D02*
X1158611D01*
G01X1152438Y598961D02*
X1150728D01*
G01X1156379D02*
X1154669D01*
G01X1160312D02*
X1158602D01*
G01X1158354Y598635D02*
X1160559D01*
G01X1154417D02*
X1156622D01*
G01X1150480D02*
X1152685D01*
G01X1158354Y598468D02*
X1160559D01*
G01X1154417D02*
X1156622D01*
G01X1150480D02*
X1152685D01*
G01Y595910D02*
X1150480D01*
G01X1156622D02*
X1154417D01*
G01X1160559D02*
X1158354D01*
G01X1152685Y595743D02*
X1150480D01*
G01X1156622D02*
X1154417D01*
G01X1160559D02*
X1158354D01*
G01X1158602Y595417D02*
X1160312D01*
G01X1154660D02*
X1156370D01*
G01X1150728D02*
X1152438D01*
G01X1158611Y595327D02*
X1160302D01*
G01X1154669D02*
X1156361D01*
G01X1150737D02*
X1152428D01*
G01X1152457Y595025D02*
X1150708D01*
G01X1156389D02*
X1154641D01*
G01X1160331D02*
X1158583D01*
G01X1158602Y594433D02*
X1160312D01*
G01X1154660D02*
X1156370D01*
G01X1150728D02*
X1152438D01*
G01X1152431Y594365D02*
X1150735D01*
G01X1156363D02*
X1154667D01*
G01X1160305D02*
X1158609D01*
G01X1152378Y594341D02*
X1150787D01*
G01X1156310D02*
X1154720D01*
G01X1160252D02*
X1158661D01*
G01X1158587Y594139D02*
X1160326D01*
G01X1154646D02*
X1156384D01*
G01X1150713D02*
X1152452D01*
G01X1148422Y593646D02*
X1432617D01*
G01X1158354Y593488D02*
X1160559D01*
G01X1154417D02*
X1156622D01*
G01X1150480D02*
X1152685D01*
G01X1158659Y593379D02*
X1160254D01*
G01X1154717D02*
X1156313D01*
G01X1150785D02*
X1152380D01*
G01X1156189Y592760D02*
X1154850D01*
G01X1156189Y591776D02*
X1154850D01*
G01X1154693Y591677D02*
X1156346D01*
G01Y591185D02*
X1154693D01*
G01X1152343Y590571D02*
X1150822D01*
G01X1156276D02*
X1154754D01*
G01X1160217D02*
X1158696D01*
G01X1152354Y590552D02*
X1150811D01*
G01X1156287D02*
X1154743D01*
G01X1160228D02*
X1158685D01*
G01X1150480Y590516D02*
X1150165D01*
G01X1153000D02*
X1152685D01*
G01X1154417D02*
X1154102D01*
G01X1156937D02*
X1156622D01*
G01X1158354D02*
X1158039D01*
G01X1152764Y589984D02*
X1150402D01*
G01X1156701D02*
X1154339D01*
G01X1160638D02*
X1158276D01*
G01X1152111Y589937D02*
X1151054D01*
G01X1156043D02*
X1154987D01*
G01X1159985D02*
X1158928D01*
G01X1158708Y589615D02*
X1160205D01*
G01X1154767D02*
X1156263D01*
G01X1150834D02*
X1152331D01*
G01X1158707Y589606D02*
X1160206D01*
G01X1154765D02*
X1156265D01*
G01X1150833D02*
X1152332D01*
G01X1156346Y589413D02*
X1154693D01*
G01X1158446Y589117D02*
X1160467D01*
G01X1154505D02*
X1156525D01*
G01X1150572D02*
X1152593D01*
G01X1156622Y589020D02*
X1156937D01*
G01X1150480D02*
X1150165D01*
G01X1154417D02*
X1154102D01*
G01X1153000D02*
X1152685D01*
G01X1158354D02*
X1158039D01*
G01X1158974Y589010D02*
X1159939D01*
G01X1155032D02*
X1155998D01*
G01X1151100D02*
X1152065D01*
G01X1154693Y588921D02*
X1156346D01*
G01X1158039Y588823D02*
X1160874D01*
G01X1154102D02*
X1156937D01*
G01X1150165D02*
X1153000D01*
G01X1158039Y588665D02*
X1158630D01*
G01X1156346D02*
X1156937D01*
G01X1154102D02*
X1154693D01*
G01X1152409D02*
X1153000D01*
G01X1150165D02*
X1150756D01*
G01X1152319Y588640D02*
X1150846D01*
G01X1156252D02*
X1154779D01*
G01X1160193D02*
X1158720D01*
G01X1158707Y588621D02*
X1160206D01*
G01X1154765D02*
X1156265D01*
G01X1150833D02*
X1152332D01*
G01X1152588Y588231D02*
X1150577D01*
G01X1156521D02*
X1154509D01*
G01X1160462D02*
X1158451D01*
G01X1150756Y587996D02*
X1150165D01*
G01X1153000D02*
X1152409D01*
G01X1154693D02*
X1154102D01*
G01X1156937D02*
X1156346D01*
G01X1158630D02*
X1158039D01*
G01X1153000Y587839D02*
X1150165D01*
G01X1156937D02*
X1154102D01*
G01X1160874D02*
X1158039D01*
G01X1152409Y587740D02*
X1150756D01*
G01X1160283D02*
X1158630D01*
G01Y587248D02*
X1160283D01*
G01X1150756D02*
X1152409D01*
G01X1158039Y586343D02*
X1160874D01*
G01X1154102D02*
X1156937D01*
G01X1150165D02*
X1153000D01*
G01X1158630Y585476D02*
X1160283D01*
G01X1150756D02*
X1152409D01*
G01X1158276Y585083D02*
X1160638D01*
G01X1150402D02*
X1152764D01*
G01X1156701D02*
X1154339D01*
G01X1152409Y584984D02*
X1150756D01*
G01X1160283D02*
X1158630D01*
G01X1152252Y584886D02*
X1150913D01*
G01X1160126D02*
X1158787D01*
G01X1158276Y583902D02*
X1160638D01*
G01X1154339D02*
X1156701D01*
G01X1150402D02*
X1152764D01*
G01X1158974Y605368D02*
X1158720Y605738D01*
G01X1158709Y604760D02*
X1158928Y604441D01*
G01X1155042Y605368D02*
X1154788Y605738D01*
G01X1154996Y604441D02*
X1154775Y604763D01*
G01X1151100Y605368D02*
X1150846Y605738D01*
G01X1150835Y604760D02*
X1151054Y604441D01*
G01X1156043Y589937D02*
X1156265Y589615D01*
G01X1155998Y589010D02*
X1156252Y588640D01*
G01X1152331Y589618D02*
X1152111Y589937D01*
G01X1152065Y589010D02*
X1152319Y588640D01*
G01X1158938Y604394D02*
X1158928Y604441D01*
G01X1154996D02*
X1155006Y604394D01*
G01X1156043Y589937D02*
X1156034Y589984D01*
G01X1151064Y604394D02*
X1151054Y604441D01*
G01X1152101Y589984D02*
X1152111Y589937D01*
G01X1158587Y600239D02*
X1158451Y606147D01*
G01X1158446Y605261D02*
X1158583Y599353D01*
G01X1158661Y594341D02*
X1158611Y595327D01*
G01X1158609Y594365D02*
X1158659Y593379D01*
G01X1156372Y600013D02*
X1156322Y600999D01*
G01X1156320Y600037D02*
X1156370Y599051D01*
G01X1154720Y594341D02*
X1154669Y595327D01*
G01X1154667Y594365D02*
X1154717Y593379D01*
G01X1158611Y599051D02*
X1158661Y600037D01*
G01X1158659Y600999D02*
X1158609Y600013D01*
G01X1156313Y593379D02*
X1156363Y594365D01*
G01X1156361Y595327D02*
X1156310Y594341D01*
G01X1154679Y599051D02*
X1154729Y600037D01*
G01X1154727Y600999D02*
X1154676Y600013D01*
G01X1152380Y593379D02*
X1152431Y594365D01*
G01X1152428Y595327D02*
X1152378Y594341D01*
G01X1150737Y599051D02*
X1150787Y600037D01*
G01X1150785Y600999D02*
X1150735Y600013D01*
G01X1158451Y588231D02*
X1158587Y594139D01*
G01X1158583Y595025D02*
X1158446Y589117D01*
G01X1156399Y599353D02*
X1156535Y605261D01*
G01X1156530Y606147D02*
X1156394Y600239D01*
G01X1154509Y588231D02*
X1154646Y594139D01*
G01X1154641Y595025D02*
X1154505Y589117D01*
G01X1152457Y599353D02*
X1152593Y605261D01*
G01X1152588Y606147D02*
X1152452Y600239D01*
G01X1150577Y588231D02*
X1150713Y594139D01*
G01X1150708Y595025D02*
X1150572Y589117D01*
G01X1158961Y604394D02*
X1158974Y605368D01*
G01X1156011Y589984D02*
X1155998Y589010D01*
G01X1155029Y604394D02*
X1155042Y605368D01*
G01X1152078Y589984D02*
X1152065Y589010D01*
G01X1151087Y604394D02*
X1151100Y605368D01*
G01X1158787Y584965D02*
Y583902D01*
G01Y610476D02*
Y609413D01*
G01X1158709Y589618D02*
Y588627D01*
G01Y605751D02*
Y604760D01*
G01X1158630Y605555D02*
Y610396D01*
G01Y583982D02*
Y588823D01*
G01X1158433Y587840D02*
Y588825D01*
G01Y605553D02*
Y606538D01*
G01X1158354Y606539D02*
Y587839D01*
G01X1158276Y589984D02*
Y583902D01*
G01Y610476D02*
Y604394D01*
G01X1158079Y588823D02*
Y587839D01*
G01Y606539D02*
Y605555D01*
G01X1158074Y606539D02*
Y605555D01*
G01X1158039Y590516D02*
Y586343D01*
G01Y608035D02*
Y603862D01*
G01X1156937D02*
Y608035D01*
G01Y586343D02*
Y590516D01*
G01X1156902Y606539D02*
Y605555D01*
G01X1156898Y588823D02*
Y587839D01*
G01X1156893Y588823D02*
Y587839D01*
G01X1156701Y589984D02*
Y583902D01*
G01Y610476D02*
Y604394D01*
G01X1156622Y587839D02*
Y606539D01*
G01X1156548Y606538D02*
Y605553D01*
G01X1156539Y588825D02*
Y587840D01*
G01X1156346Y601698D02*
Y606539D01*
G01Y587839D02*
Y592680D01*
G01X1156272Y604760D02*
Y605751D01*
G01X1156263Y588627D02*
Y589618D01*
G01X1156189Y592760D02*
Y591696D01*
G01Y602681D02*
Y601618D01*
G01X1155913D02*
Y602602D01*
G01Y592760D02*
Y591776D01*
G01X1155126Y601618D02*
Y602602D01*
G01Y592760D02*
Y591776D01*
G01X1154850Y592760D02*
Y591696D01*
G01Y602682D02*
Y601618D01*
G01X1154776Y605751D02*
Y604760D01*
G01X1154767Y589618D02*
Y588627D01*
G01X1154693Y601698D02*
Y606539D01*
G01Y587839D02*
Y592680D01*
G01X1154501Y605553D02*
Y606538D01*
G01X1154491Y587840D02*
Y588825D01*
G01X1154417Y606539D02*
Y587839D01*
G01X1154339Y589984D02*
Y583902D01*
G01Y610476D02*
Y604394D01*
G01X1154146Y606539D02*
Y605555D01*
G01X1154142Y606539D02*
Y605555D01*
G01X1154137Y588823D02*
Y587839D01*
G01X1154102Y590516D02*
Y586343D01*
G01Y608035D02*
Y603862D01*
G01X1153000D02*
Y608035D01*
G01Y586343D02*
Y590516D01*
G01X1152965Y588823D02*
Y587839D01*
G01X1152961Y588823D02*
Y587839D01*
G01Y606539D02*
Y605555D01*
G01X1152764Y589984D02*
Y583902D01*
G01Y610476D02*
Y604394D01*
G01X1152685Y587839D02*
Y606539D01*
G01X1152606Y588825D02*
Y587840D01*
G01Y606538D02*
Y605553D01*
G01X1152409Y605555D02*
Y610396D01*
G01Y583982D02*
Y588823D01*
G01X1152331Y604760D02*
Y605751D01*
G01Y588627D02*
Y589618D01*
G01X1152252Y584965D02*
Y583902D01*
G01Y610476D02*
Y609413D01*
G01X1151976Y583902D02*
Y584886D01*
G01Y610476D02*
Y609492D01*
G01X1151189Y584886D02*
Y583902D01*
G01Y610476D02*
Y609492D01*
G01X1150913Y584965D02*
Y583902D01*
G01Y610476D02*
Y609413D01*
G01X1150835Y589618D02*
Y588627D01*
G01Y605751D02*
Y604760D01*
G01X1150756Y605555D02*
Y610396D01*
G01Y583982D02*
Y588823D01*
G01X1150559Y605553D02*
Y606538D01*
G01Y587840D02*
Y588825D01*
G01X1150480Y606539D02*
Y587839D01*
G01X1150402Y589984D02*
Y583902D01*
G01Y610476D02*
Y604394D01*
G01X1150205Y588823D02*
Y587839D01*
G01Y606539D02*
Y605555D01*
G01X1150200Y606539D02*
Y605555D01*
G01X1150165Y590516D02*
Y586343D01*
G01Y608035D02*
Y603862D01*
G01X1149122Y594064D02*
Y600314D01*
G01X1149083Y600732D02*
Y593646D01*
G01X1148727Y600732D02*
Y593646D01*
G01X1148177Y604768D02*
Y609492D01*
G01Y584886D02*
Y589610D01*
G01X1148020Y594595D02*
Y599783D01*
G01X1158974Y589010D02*
X1158961Y589984D01*
G01X1156007Y605368D02*
X1156020Y604394D01*
G01X1155032Y589010D02*
X1155019Y589984D01*
G01X1152065Y605368D02*
X1152078Y604394D01*
G01X1151100Y589010D02*
X1151087Y589984D01*
G01X1156525Y589117D02*
X1156389Y595025D01*
G01X1156384Y594139D02*
X1156521Y588231D01*
G01X1154655Y600239D02*
X1154519Y606147D01*
G01X1154514Y605261D02*
X1154650Y599353D01*
G01X1152593Y589117D02*
X1152457Y595025D01*
G01X1152452Y594139D02*
X1152588Y588231D01*
G01X1150713Y600239D02*
X1150577Y606147D01*
G01X1150572Y605261D02*
X1150708Y599353D01*
G01X1152431Y600013D02*
X1152380Y600999D01*
G01X1152378Y600037D02*
X1152428Y599051D01*
G01X1150787Y594341D02*
X1150737Y595327D01*
G01X1150735Y594365D02*
X1150785Y593379D01*
G01X1158928Y589937D02*
X1158938Y589984D01*
G01X1154996D02*
X1154987Y589937D01*
G01X1156043Y604394D02*
X1156053Y604441D01*
G01X1151054Y589937D02*
X1151064Y589984D01*
G01X1152111Y604441D02*
X1152101Y604394D01*
G01X1158720Y588640D02*
X1158974Y589010D01*
G01X1158928Y589937D02*
X1158709Y589618D01*
G01X1154779Y588640D02*
X1155032Y589010D01*
G01X1154765Y589615D02*
X1154987Y589937D01*
G01X1150846Y588640D02*
X1151100Y589010D01*
G01X1151054Y589937D02*
X1150835Y589618D01*
G01X1156274Y604763D02*
X1156053Y604441D01*
G01X1156261Y605738D02*
X1156007Y605368D01*
G01X1152111Y604441D02*
X1152331Y604760D01*
G01X1152319Y605738D02*
X1152065Y605368D01*
G01X1160205Y605754D02*
Y605751D01*
G01X1160206Y605756D02*
X1160205Y605754D01*
G01X1160206Y605757D02*
Y605756D01*
G01X1168079Y605754D02*
Y605751D01*
G01X1168080Y605756D02*
X1168079Y605754D01*
G01X1168080Y605757D02*
Y605756D01*
G01X1175953Y605754D02*
Y605751D01*
G01X1175954Y605756D02*
X1175953Y605754D01*
G01X1175954Y605757D02*
Y605756D01*
G01X1175953Y604768D02*
Y604763D01*
G01X1175954Y604771D02*
X1175953Y604768D01*
G01X1175954Y604772D02*
Y604771D01*
G01X1174456Y589610D02*
Y589615D01*
G01X1174455Y589607D02*
X1174456Y589610D01*
G01X1174455Y589606D02*
Y589607D01*
G01X1166582Y588624D02*
X1166583Y588627D01*
G01X1166582Y588622D02*
Y588624D01*
G01X1166581Y588621D02*
X1166582Y588622D01*
G01X1174456Y588624D02*
X1174457Y588627D01*
G01X1174456Y588622D02*
Y588624D01*
G01X1174455Y588621D02*
X1174456Y588622D01*
G01X1182330Y588624D02*
X1182331Y588627D01*
G01X1182330Y588622D02*
Y588624D01*
G01X1182329Y588621D02*
X1182330Y588622D01*
G01X1160215Y605608D02*
X1160206Y605757D01*
G01X1160222Y605193D02*
X1160215Y605608D01*
G01X1160227Y604573D02*
X1160222Y605193D01*
G01X1160228Y603826D02*
X1160227Y604573D01*
G01X1160211Y589680D02*
X1160206Y589606D01*
G01X1160214Y589887D02*
X1160211Y589680D01*
G01X1160216Y590197D02*
X1160214Y589887D01*
G01X1160217Y590571D02*
X1160216Y590197D01*
G01X1160227Y589804D02*
X1160228Y590552D01*
G01X1160222Y589184D02*
X1160227Y589804D01*
G01X1160215Y588770D02*
X1160222Y589184D01*
G01X1160206Y588621D02*
X1160215Y588770D01*
G01X1166561Y604573D02*
X1166559Y603826D01*
G01X1166566Y605193D02*
X1166561Y604573D01*
G01X1166573Y605608D02*
X1166566Y605193D01*
G01X1166581Y605757D02*
X1166573Y605608D01*
G01X1168101Y589804D02*
X1168102Y590552D01*
G01X1168096Y589184D02*
X1168101Y589804D01*
G01X1168089Y588770D02*
X1168096Y589184D01*
G01X1168080Y588621D02*
X1168089Y588770D01*
G01X1160206Y604771D02*
Y604772D01*
G01X1160205Y604768D02*
X1160206Y604771D01*
G01X1160205Y604761D02*
Y604768D01*
G01X1166581Y589607D02*
Y589606D01*
G01X1166582Y589610D02*
X1166581Y589607D01*
G01X1166583Y589617D02*
X1166582Y589610D01*
G01X1168080Y604771D02*
Y604772D01*
G01X1168079Y604768D02*
X1168080Y604771D01*
G01X1168079Y604761D02*
Y604768D01*
G01X1160471Y605413D02*
X1160467Y605261D01*
G01X1160476Y605511D02*
X1160471Y605413D01*
G01X1160480Y605553D02*
X1160476Y605511D01*
G01X1162374Y588965D02*
X1162379Y589117D01*
G01X1162370Y588867D02*
X1162374Y588965D01*
G01X1162365Y588825D02*
X1162370Y588867D01*
G01X1164413Y605413D02*
X1164409Y605261D01*
G01X1164417Y605511D02*
X1164413Y605413D01*
G01X1164422Y605553D02*
X1164417Y605511D01*
G01X1166316Y588965D02*
X1166320Y589117D01*
G01X1166312Y588867D02*
X1166316Y588965D01*
G01X1166307Y588825D02*
X1166312Y588867D01*
G01X1168345Y605413D02*
X1168341Y605261D01*
G01X1168350Y605511D02*
X1168345Y605413D01*
G01X1168354Y605553D02*
X1168350Y605511D01*
G01X1170248Y588965D02*
X1170253Y589117D01*
G01X1170244Y588867D02*
X1170248Y588965D01*
G01X1170239Y588825D02*
X1170244Y588867D01*
G01X1172287Y605413D02*
X1172283Y605261D01*
G01X1172291Y605511D02*
X1172287Y605413D01*
G01X1172296Y605553D02*
X1172291Y605511D01*
G01X1174190Y588965D02*
X1174194Y589117D01*
G01X1174186Y588867D02*
X1174190Y588965D01*
G01X1174181Y588825D02*
X1174186Y588867D01*
G01X1176219Y605413D02*
X1176215Y605261D01*
G01X1176224Y605511D02*
X1176219Y605413D01*
G01X1176228Y605553D02*
X1176224Y605511D01*
G01X1160468Y606353D02*
X1160462Y606147D01*
G01X1160474Y606485D02*
X1160468Y606353D01*
G01X1160480Y606538D02*
X1160474Y606485D01*
G01X1164410Y606353D02*
X1164404Y606147D01*
G01X1164416Y606485D02*
X1164410Y606353D01*
G01X1164422Y606538D02*
X1164416Y606485D01*
G01X1162378Y588025D02*
X1162383Y588231D01*
G01X1162372Y587893D02*
X1162378Y588025D01*
G01X1162365Y587840D02*
X1162372Y587893D01*
G01X1168342Y606353D02*
X1168336Y606147D01*
G01X1168348Y606485D02*
X1168342Y606353D01*
G01X1168354Y606538D02*
X1168348Y606485D01*
G01X1166319Y588025D02*
X1166325Y588231D01*
G01X1166313Y587893D02*
X1166319Y588025D01*
G01X1166307Y587840D02*
X1166313Y587893D01*
G01X1172284Y606353D02*
X1172278Y606147D01*
G01X1172290Y606485D02*
X1172284Y606353D01*
G01X1172296Y606538D02*
X1172290Y606485D01*
G01X1170252Y588025D02*
X1170257Y588231D01*
G01X1170246Y587893D02*
X1170252Y588025D01*
G01X1170239Y587840D02*
X1170246Y587893D01*
G01X1176216Y606353D02*
X1176210Y606147D01*
G01X1176222Y606485D02*
X1176216Y606353D01*
G01X1176228Y606538D02*
X1176222Y606485D01*
G01X1174193Y588025D02*
X1174199Y588231D01*
G01X1174187Y587893D02*
X1174193Y588025D01*
G01X1174181Y587840D02*
X1174187Y587893D01*
G01X1162639Y604209D02*
X1162638Y603807D01*
G01X1162642Y604537D02*
X1162639Y604209D01*
G01X1162646Y604733D02*
X1162642Y604537D01*
G01X1162650Y604763D02*
X1162646Y604733D01*
G01X1164149Y590169D02*
X1164150Y590571D01*
G01X1164146Y589841D02*
X1164149Y590169D01*
G01X1164142Y589645D02*
X1164146Y589841D01*
G01X1164137Y589615D02*
X1164142Y589645D01*
G01X1170513Y604209D02*
X1170512Y603807D01*
G01X1170516Y604537D02*
X1170513Y604209D01*
G01X1170520Y604733D02*
X1170516Y604537D01*
G01X1170524Y604763D02*
X1170520Y604733D01*
G01X1172023Y590169D02*
X1172024Y590571D01*
G01X1172020Y589841D02*
X1172023Y590169D01*
G01X1172016Y589645D02*
X1172020Y589841D01*
G01X1172011Y589615D02*
X1172016Y589645D01*
G01X1178387Y604209D02*
X1178386Y603807D01*
G01X1178390Y604537D02*
X1178387Y604209D01*
G01X1178394Y604733D02*
X1178390Y604537D01*
G01X1178398Y604763D02*
X1178394Y604733D01*
G01X1179897Y590169D02*
X1179898Y590571D01*
G01X1179894Y589841D02*
X1179897Y590169D01*
G01X1179890Y589645D02*
X1179894Y589841D01*
G01X1179885Y589615D02*
X1179890Y589645D01*
G01X1182330Y589610D02*
X1182331Y589615D01*
G01X1182330Y589607D02*
Y589610D01*
G01X1182329Y589606D02*
X1182330Y589607D01*
G01X1160216Y604181D02*
X1160217Y603807D01*
G01X1160214Y604491D02*
X1160216Y604181D01*
G01X1160211Y604698D02*
X1160214Y604491D01*
G01X1160206Y604772D02*
X1160211Y604698D01*
G01X1166571Y590197D02*
X1166570Y590571D01*
G01X1166573Y589887D02*
X1166571Y590197D01*
G01X1166577Y589680D02*
X1166573Y589887D01*
G01X1166581Y589606D02*
X1166577Y589680D01*
G01X1168091Y604181D02*
Y603807D01*
G01X1168088Y604491D02*
X1168091Y604181D01*
G01X1168085Y604698D02*
X1168088Y604491D01*
G01X1168080Y604772D02*
X1168085Y604698D01*
G01X1160474Y587893D02*
X1160480Y587840D01*
G01X1160468Y588025D02*
X1160474Y587893D01*
G01X1160462Y588231D02*
X1160468Y588025D01*
G01X1162381Y606485D02*
X1162375Y606538D01*
G01X1162387Y606353D02*
X1162381Y606485D01*
G01X1162393Y606147D02*
X1162387Y606353D01*
G01X1164406Y587893D02*
X1164413Y587840D01*
G01X1164400Y588025D02*
X1164406Y587893D01*
G01X1164395Y588231D02*
X1164400Y588025D01*
G01X1166313Y606485D02*
X1166307Y606538D01*
G01X1166319Y606353D02*
X1166313Y606485D01*
G01X1166325Y606147D02*
X1166319Y606353D01*
G01X1168348Y587893D02*
X1168354Y587840D01*
G01X1168342Y588025D02*
X1168348Y587893D01*
G01X1168336Y588231D02*
X1168342Y588025D01*
G01X1170255Y606485D02*
X1170249Y606538D01*
G01X1170261Y606353D02*
X1170255Y606485D01*
G01X1170267Y606147D02*
X1170261Y606353D01*
G01X1172280Y587893D02*
X1172287Y587840D01*
G01X1172274Y588025D02*
X1172280Y587893D01*
G01X1172269Y588231D02*
X1172274Y588025D01*
G01X1174187Y606485D02*
X1174181Y606538D01*
G01X1174193Y606353D02*
X1174187Y606485D01*
G01X1174199Y606147D02*
X1174193Y606353D01*
G01X1176222Y587893D02*
X1176228Y587840D01*
G01X1176216Y588025D02*
X1176222Y587893D01*
G01X1176210Y588231D02*
X1176216Y588025D01*
G01X1178129Y606485D02*
X1178123Y606538D01*
G01X1178135Y606353D02*
X1178129Y606485D01*
G01X1178141Y606147D02*
X1178135Y606353D01*
G01X1180154Y587893D02*
X1180161Y587840D01*
G01X1180148Y588025D02*
X1180154Y587893D01*
G01X1180143Y588231D02*
X1180148Y588025D01*
G01X1182061Y606485D02*
X1182055Y606538D01*
G01X1182067Y606353D02*
X1182061Y606485D01*
G01X1182073Y606147D02*
X1182067Y606353D01*
G01X1160476Y588867D02*
X1160480Y588825D01*
G01X1160471Y588965D02*
X1160476Y588867D01*
G01X1160467Y589117D02*
X1160471Y588965D01*
G01X1162379Y605511D02*
X1162375Y605553D01*
G01X1162384Y605413D02*
X1162379Y605511D01*
G01X1162388Y605261D02*
X1162384Y605413D01*
G01X1164408Y588867D02*
X1164413Y588825D01*
G01X1164404Y588965D02*
X1164408Y588867D01*
G01X1164399Y589117D02*
X1164404Y588965D01*
G01X1166312Y605511D02*
X1166307Y605553D01*
G01X1166316Y605413D02*
X1166312Y605511D01*
G01X1166320Y605261D02*
X1166316Y605413D01*
G01X1168350Y588867D02*
X1168354Y588825D01*
G01X1168345Y588965D02*
X1168350Y588867D01*
G01X1168341Y589117D02*
X1168345Y588965D01*
G01X1170253Y605511D02*
X1170249Y605553D01*
G01X1170258Y605413D02*
X1170253Y605511D01*
G01X1170262Y605261D02*
X1170258Y605413D01*
G01X1172282Y588867D02*
X1172287Y588825D01*
G01X1172278Y588965D02*
X1172282Y588867D01*
G01X1172273Y589117D02*
X1172278Y588965D01*
G01X1174186Y605511D02*
X1174181Y605553D01*
G01X1174190Y605413D02*
X1174186Y605511D01*
G01X1174194Y605261D02*
X1174190Y605413D01*
G01X1176224Y588867D02*
X1176228Y588825D01*
G01X1176219Y588965D02*
X1176224Y588867D01*
G01X1176215Y589117D02*
X1176219Y588965D01*
G01X1178127Y605511D02*
X1178123Y605553D01*
G01X1178132Y605413D02*
X1178127Y605511D01*
G01X1178136Y605261D02*
X1178132Y605413D01*
G01X1180156Y588867D02*
X1180161Y588825D01*
G01X1180152Y588965D02*
X1180156Y588867D01*
G01X1180147Y589117D02*
X1180152Y588965D01*
G01X1182060Y605511D02*
X1182055Y605553D01*
G01X1182064Y605413D02*
X1182060Y605511D01*
G01X1182068Y605261D02*
X1182064Y605413D01*
G01X1162636Y589645D02*
X1162641Y589615D01*
G01X1162632Y589841D02*
X1162636Y589645D01*
G01X1162629Y590169D02*
X1162632Y589841D01*
G01X1162628Y590571D02*
X1162629Y590169D01*
G01X1164151Y604733D02*
X1164147Y604763D01*
G01X1164155Y604537D02*
X1164151Y604733D01*
G01X1164158Y604209D02*
X1164155Y604537D01*
G01X1164159Y603807D02*
X1164158Y604209D01*
G01X1170510Y589645D02*
X1170515Y589615D01*
G01X1170506Y589841D02*
X1170510Y589645D01*
G01X1170503Y590169D02*
X1170506Y589841D01*
G01X1170502Y590571D02*
X1170503Y590169D01*
G01X1172025Y604733D02*
X1172021Y604763D01*
G01X1172029Y604537D02*
X1172025Y604733D01*
G01X1172032Y604209D02*
X1172029Y604537D01*
G01X1172033Y603807D02*
X1172032Y604209D01*
G01X1178384Y589645D02*
X1178389Y589615D01*
G01X1178380Y589841D02*
X1178384Y589645D01*
G01X1178377Y590169D02*
X1178380Y589841D01*
G01X1178376Y590571D02*
X1178377Y590169D01*
G01X1179899Y604733D02*
X1179895Y604763D01*
G01X1179903Y604537D02*
X1179899Y604733D01*
G01X1179906Y604209D02*
X1179903Y604537D01*
G01X1179907Y603807D02*
X1179906Y604209D01*
G01X1166573Y588770D02*
X1166581Y588621D01*
G01X1166566Y589184D02*
X1166573Y588770D01*
G01X1166561Y589804D02*
X1166566Y589184D01*
G01X1166559Y590552D02*
X1166561Y589804D01*
G01X1168089Y605608D02*
X1168080Y605757D01*
G01X1168096Y605193D02*
X1168089Y605608D01*
G01X1168101Y604573D02*
X1168096Y605193D01*
G01X1168102Y603826D02*
X1168101Y604573D01*
G01X1174447Y588770D02*
X1174455Y588621D01*
G01X1174440Y589184D02*
X1174447Y588770D01*
G01X1174435Y589804D02*
X1174440Y589184D01*
G01X1174433Y590552D02*
X1174435Y589804D01*
G01X1174451Y589679D02*
X1174455Y589606D01*
G01X1174447Y589887D02*
X1174451Y589679D01*
G01X1174445Y590200D02*
X1174447Y589887D01*
G01X1174444Y590571D02*
X1174445Y590200D01*
G01X1175959Y604699D02*
X1175954Y604772D01*
G01X1175962Y604491D02*
X1175959Y604699D01*
G01X1175965Y604178D02*
X1175962Y604491D01*
G01X1175965Y603807D02*
Y604178D01*
G01X1175963Y605608D02*
X1175954Y605757D01*
G01X1175970Y605193D02*
X1175963Y605608D01*
G01X1175975Y604573D02*
X1175970Y605193D01*
G01X1175976Y603826D02*
X1175975Y604573D01*
G01X1182321Y588770D02*
X1182329Y588621D01*
G01X1182314Y589184D02*
X1182321Y588770D01*
G01X1182309Y589804D02*
X1182314Y589184D01*
G01X1182307Y590552D02*
X1182309Y589804D01*
G01X1182325Y589679D02*
X1182329Y589606D01*
G01X1182321Y589887D02*
X1182325Y589679D01*
G01X1182319Y590200D02*
X1182321Y589887D01*
G01X1182318Y590571D02*
X1182319Y590200D01*
G01X1166577Y604698D02*
X1166581Y604772D01*
G01X1166573Y604491D02*
X1166577Y604698D01*
G01X1166571Y604181D02*
X1166573Y604491D01*
G01X1166570Y603807D02*
X1166571Y604181D01*
G01X1168085Y589680D02*
X1168080Y589606D01*
G01X1168088Y589887D02*
X1168085Y589680D01*
G01X1168091Y590197D02*
X1168088Y589887D01*
G01X1168091Y590571D02*
Y590197D01*
G01X1174435Y604573D02*
X1174433Y603826D01*
G01X1174440Y605193D02*
X1174435Y604573D01*
G01X1174447Y605608D02*
X1174440Y605193D01*
G01X1174455Y605757D02*
X1174447Y605608D01*
G01X1175975Y589804D02*
X1175976Y590552D01*
G01X1175970Y589184D02*
X1175975Y589804D01*
G01X1175963Y588770D02*
X1175970Y589184D01*
G01X1175954Y588621D02*
X1175963Y588770D01*
G01X1182309Y604573D02*
X1182307Y603826D01*
G01X1182314Y605193D02*
X1182309Y604573D01*
G01X1182321Y605608D02*
X1182314Y605193D01*
G01X1182329Y605757D02*
X1182321Y605608D01*
G01X1174445Y604178D02*
X1174444Y603807D01*
G01X1174447Y604491D02*
X1174445Y604178D01*
G01X1174451Y604699D02*
X1174447Y604491D01*
G01X1174455Y604772D02*
X1174451Y604699D01*
G01X1175965Y590200D02*
Y590571D01*
G01X1175962Y589887D02*
X1175965Y590200D01*
G01X1175959Y589679D02*
X1175962Y589887D01*
G01X1175954Y589606D02*
X1175959Y589679D01*
G01X1182319Y604178D02*
X1182318Y603807D01*
G01X1182321Y604491D02*
X1182319Y604178D01*
G01X1182325Y604699D02*
X1182321Y604491D01*
G01X1182329Y604772D02*
X1182325Y604699D01*
G01X1178122Y588965D02*
X1178127Y589117D01*
G01X1178118Y588867D02*
X1178122Y588965D01*
G01X1178113Y588825D02*
X1178118Y588867D01*
G01X1180161Y605413D02*
X1180157Y605261D01*
G01X1180165Y605511D02*
X1180161Y605413D01*
G01X1180170Y605553D02*
X1180165Y605511D01*
G01X1182064Y588965D02*
X1182068Y589117D01*
G01X1182060Y588867D02*
X1182064Y588965D01*
G01X1182055Y588825D02*
X1182060Y588867D01*
G01X1180158Y606353D02*
X1180152Y606147D01*
G01X1180164Y606485D02*
X1180158Y606353D01*
G01X1180170Y606538D02*
X1180164Y606485D01*
G01X1178126Y588025D02*
X1178131Y588231D01*
G01X1178120Y587893D02*
X1178126Y588025D01*
G01X1178113Y587840D02*
X1178120Y587893D01*
G01X1182067Y588025D02*
X1182073Y588231D01*
G01X1182061Y587893D02*
X1182067Y588025D01*
G01X1182055Y587840D02*
X1182061Y587893D01*
G01X1160206Y588622D02*
Y588621D01*
G01X1160205Y588624D02*
X1160206Y588622D01*
G01X1160205Y588627D02*
Y588624D01*
G01X1174455Y604771D02*
Y604772D01*
G01X1174456Y604768D02*
X1174455Y604771D01*
G01X1174456Y604763D02*
Y604768D01*
G01X1175954Y589607D02*
Y589606D01*
G01X1175953Y589610D02*
X1175954Y589607D01*
G01X1175953Y589615D02*
Y589610D01*
G01X1182330Y604771D02*
X1182329Y604772D01*
G01X1182330Y604768D02*
Y604771D01*
G01X1182331Y604763D02*
X1182330Y604768D01*
G01X1168080Y588622D02*
Y588621D01*
G01X1168079Y588624D02*
X1168080Y588622D01*
G01X1168079Y588627D02*
Y588624D01*
G01X1166582Y605756D02*
X1166581Y605757D01*
G01X1166582Y605754D02*
Y605756D01*
G01X1166583Y605751D02*
X1166582Y605754D01*
G01X1175954Y588622D02*
Y588621D01*
G01X1175953Y588624D02*
X1175954Y588622D01*
G01X1175953Y588627D02*
Y588624D01*
G01X1174456Y605756D02*
X1174455Y605757D01*
G01X1174456Y605754D02*
Y605756D01*
G01X1174457Y605751D02*
X1174456Y605754D01*
G01X1182330Y605756D02*
X1182329Y605757D01*
G01X1182330Y605754D02*
Y605756D01*
G01X1182331Y605751D02*
X1182330Y605754D01*
G01X1160205Y589610D02*
Y589617D01*
G01X1160206Y589607D02*
X1160205Y589610D01*
G01X1160206Y589606D02*
Y589607D01*
G01X1168079Y589610D02*
Y589617D01*
G01X1168080Y589607D02*
X1168079Y589610D01*
G01X1168080Y589606D02*
Y589607D01*
G01X1166582Y604768D02*
X1166583Y604761D01*
G01X1166581Y604771D02*
X1166582Y604768D01*
G01X1166581Y604772D02*
Y604771D01*
G01X1164443Y588823D02*
X1164458D01*
G01X1164428Y588824D02*
X1164443Y588823D01*
G01X1164413Y588825D02*
X1164428Y588824D01*
G01X1182025Y588823D02*
X1182010D01*
G01X1182040Y588824D02*
X1182025Y588823D01*
G01X1182055Y588825D02*
X1182040Y588824D01*
G01X1178083Y588823D02*
X1178068D01*
G01X1178098Y588824D02*
X1178083Y588823D01*
G01X1178113Y588825D02*
X1178098Y588824D01*
G01X1174151Y588823D02*
X1174136D01*
G01X1174166Y588824D02*
X1174151Y588823D01*
G01X1174181Y588825D02*
X1174166Y588824D01*
G01X1170209Y588823D02*
X1170194D01*
G01X1170224Y588824D02*
X1170209Y588823D01*
G01X1170239Y588825D02*
X1170224Y588824D01*
G01X1166277Y588823D02*
X1166262D01*
G01X1166292Y588824D02*
X1166277Y588823D01*
G01X1166307Y588825D02*
X1166292Y588824D01*
G01X1182025Y587839D02*
X1182010D01*
G01X1182040D02*
X1182025D01*
G01X1182055Y587840D02*
X1182040Y587839D01*
G01X1178083D02*
X1178068D01*
G01X1178098D02*
X1178083D01*
G01X1178113Y587840D02*
X1178098Y587839D01*
G01X1174151D02*
X1174136D01*
G01X1174166D02*
X1174151D01*
G01X1174181Y587840D02*
X1174166Y587839D01*
G01X1170209D02*
X1170194D01*
G01X1170224D02*
X1170209D01*
G01X1170239Y587840D02*
X1170224Y587839D01*
G01X1162335D02*
X1162320D01*
G01X1162350D02*
X1162335D01*
G01X1162365Y587840D02*
X1162350Y587839D01*
G01X1160495D02*
X1160480Y587840D01*
G01X1160510Y587839D02*
X1160495D01*
G01X1160525D02*
X1160510D01*
G01X1164428D02*
X1164413Y587840D01*
G01X1164443Y587839D02*
X1164428D01*
G01X1164458D02*
X1164443D01*
G01X1168369D02*
X1168354Y587840D01*
G01X1168384Y587839D02*
X1168369D01*
G01X1168399D02*
X1168384D01*
G01X1172302D02*
X1172287Y587840D01*
G01X1172317Y587839D02*
X1172302D01*
G01X1172332D02*
X1172317D01*
G01X1176243D02*
X1176228Y587840D01*
G01X1176258Y587839D02*
X1176243D01*
G01X1176273D02*
X1176258D01*
G01X1180176D02*
X1180161Y587840D01*
G01X1180191Y587839D02*
X1180176D01*
G01X1180206D02*
X1180191D01*
G01X1162360Y606539D02*
X1162375Y606538D01*
G01X1162345Y606539D02*
X1162360D01*
G01X1162330D02*
X1162345D01*
G01X1166292D02*
X1166307Y606538D01*
G01X1166277Y606539D02*
X1166292D01*
G01X1166262D02*
X1166277D01*
G01X1170234D02*
X1170249Y606538D01*
G01X1170219Y606539D02*
X1170234D01*
G01X1170204D02*
X1170219D01*
G01X1174166D02*
X1174181Y606538D01*
G01X1174151Y606539D02*
X1174166D01*
G01X1174136D02*
X1174151D01*
G01X1178108D02*
X1178123Y606538D01*
G01X1178093Y606539D02*
X1178108D01*
G01X1178078D02*
X1178093D01*
G01X1182040D02*
X1182055Y606538D01*
G01X1182025Y606539D02*
X1182040D01*
G01X1182010D02*
X1182025D01*
G01X1160495Y588824D02*
X1160480Y588825D01*
G01X1160510Y588823D02*
X1160495Y588824D01*
G01X1160525Y588823D02*
X1160510D01*
G01X1168369Y588824D02*
X1168354Y588825D01*
G01X1168384Y588823D02*
X1168369Y588824D01*
G01X1168399Y588823D02*
X1168384D01*
G01X1172302Y588824D02*
X1172287Y588825D01*
G01X1172317Y588823D02*
X1172302Y588824D01*
G01X1172332Y588823D02*
X1172317D01*
G01X1176243Y588824D02*
X1176228Y588825D01*
G01X1176258Y588823D02*
X1176243Y588824D01*
G01X1176273Y588823D02*
X1176258D01*
G01X1180176Y588824D02*
X1180161Y588825D01*
G01X1180191Y588823D02*
X1180176Y588824D01*
G01X1180206Y588823D02*
X1180191D01*
G01X1162360Y605554D02*
X1162375Y605553D01*
G01X1162345Y605555D02*
X1162360Y605554D01*
G01X1162330Y605555D02*
X1162345D01*
G01X1166292Y605554D02*
X1166307Y605553D01*
G01X1166277Y605555D02*
X1166292Y605554D01*
G01X1166262Y605555D02*
X1166277D01*
G01X1170234Y605554D02*
X1170249Y605553D01*
G01X1170219Y605555D02*
X1170234Y605554D01*
G01X1170204Y605555D02*
X1170219D01*
G01X1174166Y605554D02*
X1174181Y605553D01*
G01X1174151Y605555D02*
X1174166Y605554D01*
G01X1174136Y605555D02*
X1174151D01*
G01X1178108Y605554D02*
X1178123Y605553D01*
G01X1178093Y605555D02*
X1178108Y605554D01*
G01X1178078Y605555D02*
X1178093D01*
G01X1182040Y605554D02*
X1182055Y605553D01*
G01X1182025Y605555D02*
X1182040Y605554D01*
G01X1182010Y605555D02*
X1182025D01*
G01X1176258D02*
X1176273D01*
G01X1176243Y605554D02*
X1176258Y605555D01*
G01X1176228Y605553D02*
X1176243Y605554D01*
G01X1168384Y605555D02*
X1168399D01*
G01X1168369Y605554D02*
X1168384Y605555D01*
G01X1168354Y605553D02*
X1168369Y605554D01*
G01X1164452Y605555D02*
X1164467D01*
G01X1164437Y605554D02*
X1164452Y605555D01*
G01X1164422Y605553D02*
X1164437Y605554D01*
G01X1160510Y605555D02*
X1160525D01*
G01X1160495Y605554D02*
X1160510Y605555D01*
G01X1160480Y605553D02*
X1160495Y605554D01*
G01X1180200Y606539D02*
X1180215D01*
G01X1180185D02*
X1180200D01*
G01X1180170Y606538D02*
X1180185Y606539D01*
G01X1176258D02*
X1176273D01*
G01X1176243D02*
X1176258D01*
G01X1176228Y606538D02*
X1176243Y606539D01*
G01X1172326D02*
X1172341D01*
G01X1172311D02*
X1172326D01*
G01X1172296Y606538D02*
X1172311Y606539D01*
G01X1164575Y610476D02*
X1162213D01*
G01X1168512D02*
X1166150D01*
G01X1172449D02*
X1170087D01*
G01X1176386D02*
X1174024D01*
G01X1180323D02*
X1177961D01*
G01X1184260D02*
X1181898D01*
G01X1168000Y609492D02*
X1166661D01*
G01X1175874D02*
X1174535D01*
G01X1182252Y609394D02*
X1183906D01*
G01X1174378D02*
X1176031D01*
G01X1166504D02*
X1168157D01*
G01X1164575Y609295D02*
X1162213D01*
G01X1168512D02*
X1166150D01*
G01X1172449D02*
X1170087D01*
G01X1176386D02*
X1174024D01*
G01X1180323D02*
X1177961D01*
G01X1184260D02*
X1181898D01*
G01X1168157Y608902D02*
X1166504D01*
G01X1176031D02*
X1174378D01*
G01X1183906D02*
X1182252D01*
G01X1164811Y608035D02*
X1161976D01*
G01X1168748D02*
X1165913D01*
G01X1172685D02*
X1169850D01*
G01X1176622D02*
X1173787D01*
G01X1180559D02*
X1177724D01*
G01X1184496D02*
X1181661D01*
G01X1168157Y607130D02*
X1166504D01*
G01X1176031D02*
X1174378D01*
G01X1183906D02*
X1182252D01*
G01Y606638D02*
X1183906D01*
G01X1174378D02*
X1176031D01*
G01X1166504D02*
X1168157D01*
G01X1164811Y606539D02*
X1161976D01*
G01X1168748D02*
X1165913D01*
G01X1172685D02*
X1169850D01*
G01X1176622D02*
X1173787D01*
G01X1180559D02*
X1177724D01*
G01X1184496D02*
X1181661D01*
G01Y606382D02*
X1182252D01*
G01X1179968D02*
X1180559D01*
G01X1177724D02*
X1178315D01*
G01X1176031D02*
X1176622D01*
G01X1173787D02*
X1174378D01*
G01X1172094D02*
X1172685D01*
G01X1169850D02*
X1170441D01*
G01X1168157D02*
X1168748D01*
G01X1165913D02*
X1166504D01*
G01X1164220D02*
X1164811D01*
G01X1161976D02*
X1162567D01*
G01X1160283D02*
X1160874D01*
G01X1182073Y606147D02*
X1184084D01*
G01X1178141D02*
X1180152D01*
G01X1174199D02*
X1176210D01*
G01X1170267D02*
X1172278D01*
G01X1166325D02*
X1168336D01*
G01X1162393D02*
X1164404D01*
G01X1164148Y605757D02*
X1162649D01*
G01X1168080D02*
X1166581D01*
G01X1172022D02*
X1170523D01*
G01X1175954D02*
X1174455D01*
G01X1179896D02*
X1178397D01*
G01X1183828D02*
X1182329D01*
G01X1182342Y605738D02*
X1183815D01*
G01X1178410D02*
X1179883D01*
G01X1174468D02*
X1175941D01*
G01X1170536D02*
X1172009D01*
G01X1166594D02*
X1168067D01*
G01X1162662D02*
X1164135D01*
G01X1160874Y605713D02*
X1160283D01*
G01X1162567D02*
X1161976D01*
G01X1164811D02*
X1164220D01*
G01X1166504D02*
X1165913D01*
G01X1168748D02*
X1168157D01*
G01X1170441D02*
X1169850D01*
G01X1172685D02*
X1172094D01*
G01X1174378D02*
X1173787D01*
G01X1176622D02*
X1176031D01*
G01X1178315D02*
X1177724D01*
G01X1180559D02*
X1179968D01*
G01X1182252D02*
X1181661D01*
G01Y605555D02*
X1184496D01*
G01X1177724D02*
X1180559D01*
G01X1173787D02*
X1176622D01*
G01X1169850D02*
X1172685D01*
G01X1165913D02*
X1168748D01*
G01X1161976D02*
X1164811D01*
G01X1164220Y605457D02*
X1162567D01*
G01X1172094D02*
X1170441D01*
G01X1179968D02*
X1178315D01*
G01X1163881Y605368D02*
X1162916D01*
G01X1167813D02*
X1166848D01*
G01X1171755D02*
X1170790D01*
G01X1175687D02*
X1174722D01*
G01X1179629D02*
X1178664D01*
G01X1181661Y605358D02*
X1181976D01*
G01X1177724D02*
X1178039D01*
G01X1173787D02*
X1174102D01*
G01X1169850D02*
X1170165D01*
G01X1161976D02*
X1162291D01*
G01X1160874D02*
X1160559D01*
G01X1164811D02*
X1164496D01*
G01X1166228D02*
X1165913D01*
G01X1168748D02*
X1168433D01*
G01X1172685D02*
X1172370D01*
G01X1176622D02*
X1176307D01*
G01X1180559D02*
X1180244D01*
G01X1164409Y605261D02*
X1162388D01*
G01X1168341D02*
X1166320D01*
G01X1172283D02*
X1170262D01*
G01X1176215D02*
X1174194D01*
G01X1180157D02*
X1178136D01*
G01X1184089D02*
X1182068D01*
G01X1178315Y604965D02*
X1179968D01*
G01X1170441D02*
X1172094D01*
G01X1162567D02*
X1164220D01*
G01X1164148Y604772D02*
X1162649D01*
G01X1168080D02*
X1166581D01*
G01X1172022D02*
X1170523D01*
G01X1175954D02*
X1174455D01*
G01X1179896D02*
X1178397D01*
G01X1183828D02*
X1182329D01*
G01X1164147Y604763D02*
X1162650D01*
G01X1168079D02*
X1166582D01*
G01X1172021D02*
X1170524D01*
G01X1175953D02*
X1174456D01*
G01X1179895D02*
X1178398D01*
G01X1183827D02*
X1182331D01*
G01X1178618Y604441D02*
X1179675D01*
G01X1174676D02*
X1175733D01*
G01X1170744D02*
X1171801D01*
G01X1166802D02*
X1167859D01*
G01X1162870D02*
X1163927D01*
G01X1166150Y604394D02*
X1168512D01*
G01X1162213D02*
X1164575D01*
G01X1172449D02*
X1170087D01*
G01X1176386D02*
X1174024D01*
G01X1180323D02*
X1177961D01*
G01X1184260D02*
X1181898D01*
G01X1181661Y603862D02*
X1181976D01*
G01X1180244D02*
X1180559D01*
G01X1177724D02*
X1178039D01*
G01X1176307D02*
X1176622D01*
G01X1172370D02*
X1172685D01*
G01X1173787D02*
X1174102D01*
G01X1169850D02*
X1170165D01*
G01X1168433D02*
X1168748D01*
G01X1165913D02*
X1166228D01*
G01X1164496D02*
X1164811D01*
G01X1161976D02*
X1162291D01*
G01X1160559D02*
X1160874D01*
G01X1182307Y603826D02*
X1183850D01*
G01X1178375D02*
X1179918D01*
G01X1174433D02*
X1175976D01*
G01X1170501D02*
X1172044D01*
G01X1166559D02*
X1168102D01*
G01X1162627D02*
X1164170D01*
G01X1182318Y603807D02*
X1183839D01*
G01X1178386D02*
X1179907D01*
G01X1174444D02*
X1175965D01*
G01X1170512D02*
X1172033D01*
G01X1166570D02*
X1168091D01*
G01X1162638D02*
X1164159D01*
G01X1178315Y603193D02*
X1179968D01*
G01X1170441D02*
X1172094D01*
G01X1162567D02*
X1164220D01*
G01Y602701D02*
X1162567D01*
G01X1172094D02*
X1170441D01*
G01X1179968D02*
X1178315D01*
G01X1164063Y602602D02*
X1162724D01*
G01X1171937D02*
X1170598D01*
G01X1179811D02*
X1178472D01*
G01Y601618D02*
X1179811D01*
G01X1170598D02*
X1171937D01*
G01X1162724D02*
X1164063D01*
G01X1164196Y600999D02*
X1162601D01*
G01X1168128D02*
X1166533D01*
G01X1172070D02*
X1170475D01*
G01X1176002D02*
X1174407D01*
G01X1179944D02*
X1178349D01*
G01X1183876D02*
X1182281D01*
G01X1164496Y600890D02*
X1162291D01*
G01X1168433D02*
X1166228D01*
G01X1172370D02*
X1170165D01*
G01X1176307D02*
X1174102D01*
G01X1180244D02*
X1178039D01*
G01X1184181D02*
X1181976D01*
G01X1164268Y600239D02*
X1162529D01*
G01X1168200D02*
X1166461D01*
G01X1172142D02*
X1170403D01*
G01X1176074D02*
X1174335D01*
G01X1180016D02*
X1178277D01*
G01X1183948D02*
X1182209D01*
G01X1182283Y600037D02*
X1183874D01*
G01X1178351D02*
X1179942D01*
G01X1174409D02*
X1176000D01*
G01X1170477D02*
X1172068D01*
G01X1166535D02*
X1168126D01*
G01X1162603D02*
X1164194D01*
G01X1182231Y600013D02*
X1183927D01*
G01X1178298D02*
X1179994D01*
G01X1174357D02*
X1176053D01*
G01X1170424D02*
X1172120D01*
G01X1166483D02*
X1168179D01*
G01X1162550D02*
X1164246D01*
G01X1164253Y599945D02*
X1162543D01*
G01X1168186D02*
X1166476D01*
G01X1172127D02*
X1170417D01*
G01X1176060D02*
X1174350D01*
G01X1180001D02*
X1178291D01*
G01X1183934D02*
X1182224D01*
G01X1182205Y599353D02*
X1183953D01*
G01X1178272D02*
X1180021D01*
G01X1174331D02*
X1176079D01*
G01X1170398D02*
X1172147D01*
G01X1166457D02*
X1168205D01*
G01X1162524D02*
X1164273D01*
G01X1164244Y599051D02*
X1162553D01*
G01X1168176D02*
X1166485D01*
G01X1172118D02*
X1170427D01*
G01X1176050D02*
X1174359D01*
G01X1179992D02*
X1178301D01*
G01X1183924D02*
X1182233D01*
G01X1164253Y598961D02*
X1162543D01*
G01X1168186D02*
X1166476D01*
G01X1172127D02*
X1170417D01*
G01X1176060D02*
X1174350D01*
G01X1180001D02*
X1178291D01*
G01X1183934D02*
X1182224D01*
G01X1181976Y598635D02*
X1184181D01*
G01X1178039D02*
X1180244D01*
G01X1174102D02*
X1176307D01*
G01X1170165D02*
X1172370D01*
G01X1166228D02*
X1168433D01*
G01X1162291D02*
X1164496D01*
G01X1181976Y598468D02*
X1184181D01*
G01X1178039D02*
X1180244D01*
G01X1174102D02*
X1176307D01*
G01X1170165D02*
X1172370D01*
G01X1166228D02*
X1168433D01*
G01X1162291D02*
X1164496D01*
G01Y595910D02*
X1162291D01*
G01X1168433D02*
X1166228D01*
G01X1172370D02*
X1170165D01*
G01X1176307D02*
X1174102D01*
G01X1180244D02*
X1178039D01*
G01X1184181D02*
X1181976D01*
G01X1164496Y595743D02*
X1162291D01*
G01X1168433D02*
X1166228D01*
G01X1172370D02*
X1170165D01*
G01X1176307D02*
X1174102D01*
G01X1180244D02*
X1178039D01*
G01X1184181D02*
X1181976D01*
G01X1182224Y595417D02*
X1183934D01*
G01X1178282D02*
X1179992D01*
G01X1174350D02*
X1176060D01*
G01X1170408D02*
X1172118D01*
G01X1166476D02*
X1168186D01*
G01X1162534D02*
X1164244D01*
G01X1182233Y595327D02*
X1183924D01*
G01X1178291D02*
X1179983D01*
G01X1174359D02*
X1176050D01*
G01X1170417D02*
X1172109D01*
G01X1166485D02*
X1168176D01*
G01X1162543D02*
X1164235D01*
G01X1164263Y595025D02*
X1162515D01*
G01X1168205D02*
X1166457D01*
G01X1172137D02*
X1170389D01*
G01X1176079D02*
X1174331D01*
G01X1180011D02*
X1178263D01*
G01X1183953D02*
X1182205D01*
G01X1182224Y594433D02*
X1183934D01*
G01X1178282D02*
X1179992D01*
G01X1174350D02*
X1176060D01*
G01X1170408D02*
X1172118D01*
G01X1166476D02*
X1168186D01*
G01X1162534D02*
X1164244D01*
G01X1164237Y594365D02*
X1162541D01*
G01X1168179D02*
X1166483D01*
G01X1172111D02*
X1170415D01*
G01X1176053D02*
X1174357D01*
G01X1179985D02*
X1178289D01*
G01X1183927D02*
X1182231D01*
G01X1164184Y594341D02*
X1162594D01*
G01X1168126D02*
X1166535D01*
G01X1172058D02*
X1170468D01*
G01X1176000D02*
X1174409D01*
G01X1179932D02*
X1178342D01*
G01X1183874D02*
X1182283D01*
G01X1182209Y594139D02*
X1183948D01*
G01X1178268D02*
X1180006D01*
G01X1174335D02*
X1176074D01*
G01X1170394D02*
X1172132D01*
G01X1166461D02*
X1168200D01*
G01X1162520D02*
X1164258D01*
G01X1181976Y593488D02*
X1184181D01*
G01X1178039D02*
X1180244D01*
G01X1174102D02*
X1176307D01*
G01X1170165D02*
X1172370D01*
G01X1166228D02*
X1168433D01*
G01X1162291D02*
X1164496D01*
G01X1182281Y593379D02*
X1183876D01*
G01X1178339D02*
X1179935D01*
G01X1174407D02*
X1176002D01*
G01X1170465D02*
X1172061D01*
G01X1166533D02*
X1168128D01*
G01X1162591D02*
X1164187D01*
G01X1164063Y592760D02*
X1162724D01*
G01X1171937D02*
X1170598D01*
G01X1179811D02*
X1178472D01*
G01X1164063Y591776D02*
X1162724D01*
G01X1171937D02*
X1170598D01*
G01X1179811D02*
X1178472D01*
G01X1178315Y591677D02*
X1179968D01*
G01X1170441D02*
X1172094D01*
G01X1162567D02*
X1164220D01*
G01Y591185D02*
X1162567D01*
G01X1172094D02*
X1170441D01*
G01X1179968D02*
X1178315D01*
G01X1164150Y590571D02*
X1162628D01*
G01X1168091D02*
X1166570D01*
G01X1172024D02*
X1170502D01*
G01X1175965D02*
X1174444D01*
G01X1179898D02*
X1178376D01*
G01X1183839D02*
X1182318D01*
G01X1164161Y590552D02*
X1162617D01*
G01X1168102D02*
X1166559D01*
G01X1172035D02*
X1170491D01*
G01X1175976D02*
X1174433D01*
G01X1179909D02*
X1178365D01*
G01X1183850D02*
X1182307D01*
G01X1160874Y590516D02*
X1160559D01*
G01X1162291D02*
X1161976D01*
G01X1164811D02*
X1164496D01*
G01X1166228D02*
X1165913D01*
G01X1168748D02*
X1168433D01*
G01X1170165D02*
X1169850D01*
G01X1172685D02*
X1172370D01*
G01X1174102D02*
X1173787D01*
G01X1176622D02*
X1176307D01*
G01X1178039D02*
X1177724D01*
G01X1180559D02*
X1180244D01*
G01X1181976D02*
X1181661D01*
G01X1164575Y589984D02*
X1162213D01*
G01X1168512D02*
X1166150D01*
G01X1172449D02*
X1170087D01*
G01X1176386D02*
X1174024D01*
G01X1180323D02*
X1177961D01*
G01X1184260D02*
X1181898D01*
G01X1163917Y589937D02*
X1162861D01*
G01X1167859D02*
X1166802D01*
G01X1171791D02*
X1170735D01*
G01X1175733D02*
X1174676D01*
G01X1179665D02*
X1178609D01*
G01X1182331Y589615D02*
X1183827D01*
G01X1178389D02*
X1179885D01*
G01X1174456D02*
X1175953D01*
G01X1170515D02*
X1172011D01*
G01X1166582D02*
X1168079D01*
G01X1162641D02*
X1164137D01*
G01X1182329Y589606D02*
X1183828D01*
G01X1178387D02*
X1179887D01*
G01X1174455D02*
X1175954D01*
G01X1170513D02*
X1172013D01*
G01X1166581D02*
X1168080D01*
G01X1162639D02*
X1164139D01*
G01X1164220Y589413D02*
X1162567D01*
G01X1172094D02*
X1170441D01*
G01X1179968D02*
X1178315D01*
G01X1182068Y589117D02*
X1184089D01*
G01X1178127D02*
X1180147D01*
G01X1174194D02*
X1176215D01*
G01X1170253D02*
X1172273D01*
G01X1166320D02*
X1168341D01*
G01X1162379D02*
X1164399D01*
G01X1180244Y589020D02*
X1180559D01*
G01X1176307D02*
X1176622D01*
G01X1172370D02*
X1172685D01*
G01X1164496D02*
X1164811D01*
G01X1160874D02*
X1160559D01*
G01X1162291D02*
X1161976D01*
G01X1166228D02*
X1165913D01*
G01X1168748D02*
X1168433D01*
G01X1170165D02*
X1169850D01*
G01X1174102D02*
X1173787D01*
G01X1178039D02*
X1177724D01*
G01X1181976D02*
X1181661D01*
G01X1178654Y589010D02*
X1179620D01*
G01X1174722D02*
X1175687D01*
G01X1170780D02*
X1171746D01*
G01X1166848D02*
X1167813D01*
G01X1162906D02*
X1163872D01*
G01X1178315Y588921D02*
X1179968D01*
G01X1170441D02*
X1172094D01*
G01X1162567D02*
X1164220D01*
G01X1181661Y588823D02*
X1184496D01*
G01X1177724D02*
X1180559D01*
G01X1173787D02*
X1176622D01*
G01X1169850D02*
X1172685D01*
G01X1165913D02*
X1168748D01*
G01X1161976D02*
X1164811D01*
G01X1181661Y588665D02*
X1182252D01*
G01X1179968D02*
X1180559D01*
G01X1177724D02*
X1178315D01*
G01X1176031D02*
X1176622D01*
G01X1173787D02*
X1174378D01*
G01X1172094D02*
X1172685D01*
G01X1169850D02*
X1170441D01*
G01X1168157D02*
X1168748D01*
G01X1165913D02*
X1166504D01*
G01X1164220D02*
X1164811D01*
G01X1161976D02*
X1162567D01*
G01X1160283D02*
X1160874D01*
G01X1164126Y588640D02*
X1162653D01*
G01X1168067D02*
X1166594D01*
G01X1172000D02*
X1170527D01*
G01X1175941D02*
X1174468D01*
G01X1179874D02*
X1178401D01*
G01X1183815D02*
X1182342D01*
G01X1182329Y588621D02*
X1183828D01*
G01X1178387D02*
X1179887D01*
G01X1174455D02*
X1175954D01*
G01X1170513D02*
X1172013D01*
G01X1166581D02*
X1168080D01*
G01X1162639D02*
X1164139D01*
G01X1164395Y588231D02*
X1162383D01*
G01X1168336D02*
X1166325D01*
G01X1172269D02*
X1170257D01*
G01X1176210D02*
X1174199D01*
G01X1180143D02*
X1178131D01*
G01X1184084D02*
X1182073D01*
G01X1160874Y587996D02*
X1160283D01*
G01X1162567D02*
X1161976D01*
G01X1164811D02*
X1164220D01*
G01X1166504D02*
X1165913D01*
G01X1168748D02*
X1168157D01*
G01X1170441D02*
X1169850D01*
G01X1172685D02*
X1172094D01*
G01X1174378D02*
X1173787D01*
G01X1176622D02*
X1176031D01*
G01X1178315D02*
X1177724D01*
G01X1180559D02*
X1179968D01*
G01X1182252D02*
X1181661D01*
G01X1164811Y587839D02*
X1161976D01*
G01X1168748D02*
X1165913D01*
G01X1172685D02*
X1169850D01*
G01X1176622D02*
X1173787D01*
G01X1180559D02*
X1177724D01*
G01X1184496D02*
X1181661D01*
G01X1168157Y587740D02*
X1166504D01*
G01X1176031D02*
X1174378D01*
G01X1183906D02*
X1182252D01*
G01Y587248D02*
X1183906D01*
G01X1174378D02*
X1176031D01*
G01X1166504D02*
X1168157D01*
G01X1181661Y586343D02*
X1184496D01*
G01X1177724D02*
X1180559D01*
G01X1173787D02*
X1176622D01*
G01X1169850D02*
X1172685D01*
G01X1165913D02*
X1168748D01*
G01X1161976D02*
X1164811D01*
G01X1182252Y585476D02*
X1183906D01*
G01X1174378D02*
X1176031D01*
G01X1166504D02*
X1168157D01*
G01X1166150Y585083D02*
X1168512D01*
G01X1162213D02*
X1164575D01*
G01X1172449D02*
X1170087D01*
G01X1176386D02*
X1174024D01*
G01X1180323D02*
X1177961D01*
G01X1184260D02*
X1181898D01*
G01X1168157Y584984D02*
X1166504D01*
G01X1176031D02*
X1174378D01*
G01X1183906D02*
X1182252D01*
G01X1168000Y584886D02*
X1166661D01*
G01X1175874D02*
X1174535D01*
G01X1181898Y583902D02*
X1184260D01*
G01X1177961D02*
X1180323D01*
G01X1174024D02*
X1176386D01*
G01X1170087D02*
X1172449D01*
G01X1166150D02*
X1168512D01*
G01X1162213D02*
X1164575D01*
G01X1182342Y605738D02*
X1182596Y605368D01*
G01X1182550Y604441D02*
X1182329Y604763D01*
G01X1178410Y605738D02*
X1178664Y605368D01*
G01X1178618Y604441D02*
X1178397Y604763D01*
G01X1174468Y605738D02*
X1174722Y605368D01*
G01X1174676Y604441D02*
X1174455Y604763D01*
G01X1170536Y605738D02*
X1170790Y605368D01*
G01X1170744Y604441D02*
X1170523Y604763D01*
G01X1179665Y589937D02*
X1179887Y589615D01*
G01X1179874Y588640D02*
X1179620Y589010D01*
G01X1166848Y605368D02*
X1166594Y605738D01*
G01X1166583Y604760D02*
X1166802Y604441D01*
G01X1175733Y589937D02*
X1175954Y589615D01*
G01X1175941Y588640D02*
X1175687Y589010D01*
G01X1162916Y605368D02*
X1162662Y605738D01*
G01X1162870Y604441D02*
X1162649Y604763D01*
G01X1171791Y589937D02*
X1172013Y589615D01*
G01X1172000Y588640D02*
X1171746Y589010D01*
G01X1168079Y589618D02*
X1167859Y589937D01*
G01X1167813Y589010D02*
X1168067Y588640D01*
G01X1163917Y589937D02*
X1164139Y589615D01*
G01X1163872Y589010D02*
X1164126Y588640D01*
G01X1160205Y589618D02*
X1159985Y589937D01*
G01X1159939Y589010D02*
X1160193Y588640D01*
G01X1178618Y604441D02*
X1178628Y604394D01*
G01X1179665Y589937D02*
X1179656Y589984D01*
G01X1174676Y604441D02*
X1174686Y604394D01*
G01X1175733Y589937D02*
X1175723Y589984D01*
G01X1170744Y604441D02*
X1170754Y604394D01*
G01X1171791Y589937D02*
X1171782Y589984D01*
G01X1166812Y604394D02*
X1166802Y604441D01*
G01X1167849Y589984D02*
X1167859Y589937D01*
G01X1162870Y604441D02*
X1162880Y604394D01*
G01X1163917Y589937D02*
X1163908Y589984D01*
G01X1159975D02*
X1159985Y589937D01*
G01X1182283Y594341D02*
X1182233Y595327D01*
G01X1182231Y594365D02*
X1182281Y593379D01*
G01X1179994Y600013D02*
X1179944Y600999D01*
G01X1179942Y600037D02*
X1179992Y599051D01*
G01X1182233D02*
X1182283Y600037D01*
G01X1182281Y600999D02*
X1182231Y600013D01*
G01X1179935Y593379D02*
X1179985Y594365D01*
G01X1179983Y595327D02*
X1179932Y594341D01*
G01X1178301Y599051D02*
X1178351Y600037D01*
G01X1178349Y600999D02*
X1178298Y600013D01*
G01X1176002Y593379D02*
X1176053Y594365D01*
G01X1176050Y595327D02*
X1176000Y594341D01*
G01X1174359Y599051D02*
X1174409Y600037D01*
G01X1174407Y600999D02*
X1174357Y600013D01*
G01X1172061Y593379D02*
X1172111Y594365D01*
G01X1172109Y595327D02*
X1172058Y594341D01*
G01X1170427Y599051D02*
X1170477Y600037D01*
G01X1170475Y600999D02*
X1170424Y600013D01*
G01X1182073Y588231D02*
X1182209Y594139D01*
G01X1182205Y595025D02*
X1182068Y589117D01*
G01X1180021Y599353D02*
X1180157Y605261D01*
G01X1180152Y606147D02*
X1180016Y600239D01*
G01X1178131Y588231D02*
X1178268Y594139D01*
G01X1178263Y595025D02*
X1178127Y589117D01*
G01X1176079Y599353D02*
X1176215Y605261D01*
G01X1176210Y606147D02*
X1176074Y600239D01*
G01X1174199Y588231D02*
X1174335Y594139D01*
G01X1174331Y595025D02*
X1174194Y589117D01*
G01X1172147Y599353D02*
X1172283Y605261D01*
G01X1172278Y606147D02*
X1172142Y600239D01*
G01X1170257Y588231D02*
X1170394Y594139D01*
G01X1170389Y595025D02*
X1170253Y589117D01*
G01X1168205Y599353D02*
X1168341Y605261D01*
G01X1168336Y606147D02*
X1168200Y600239D01*
G01X1166325Y588231D02*
X1166461Y594139D01*
G01X1166457Y595025D02*
X1166320Y589117D01*
G01X1179633Y589984D02*
X1179620Y589010D01*
G01X1178651Y604394D02*
X1178664Y605368D01*
G01X1175701Y589984D02*
X1175687Y589010D01*
G01X1174709Y604394D02*
X1174722Y605368D01*
G01X1171759Y589984D02*
X1171746Y589010D01*
G01X1170777Y604394D02*
X1170790Y605368D01*
G01X1167827Y589984D02*
X1167813Y589010D01*
G01X1166835Y604394D02*
X1166848Y605368D01*
G01X1163885Y589984D02*
X1163872Y589010D01*
G01X1182331Y589618D02*
Y588627D01*
G01Y605751D02*
Y604760D01*
G01X1182252Y605555D02*
Y610396D01*
G01Y583982D02*
Y588823D01*
G01X1182055Y587840D02*
Y588825D01*
G01Y605553D02*
Y606538D01*
G01X1181976Y606539D02*
Y587839D01*
G01X1181898Y589984D02*
Y583902D01*
G01Y610476D02*
Y604394D01*
G01X1181701Y588823D02*
Y587839D01*
G01Y606539D02*
Y605555D01*
G01X1181696Y606539D02*
Y605555D01*
G01X1181661Y590516D02*
Y586343D01*
G01Y608035D02*
Y603862D01*
G01X1180559D02*
Y608035D01*
G01Y586343D02*
Y590516D01*
G01X1180524Y606539D02*
Y605555D01*
G01X1180520Y588823D02*
Y587839D01*
G01X1180515Y588823D02*
Y587839D01*
G01X1180323Y589984D02*
Y583902D01*
G01Y610476D02*
Y604394D01*
G01X1180244Y587839D02*
Y606539D01*
G01X1180170Y606538D02*
Y605553D01*
G01X1180161Y588825D02*
Y587840D01*
G01X1179968Y601698D02*
Y606539D01*
G01Y587839D02*
Y592680D01*
G01X1179894Y604760D02*
Y605751D01*
G01X1179885Y588627D02*
Y589618D01*
G01X1179811Y592760D02*
Y591696D01*
G01Y602681D02*
Y601618D01*
G01X1179535D02*
Y602602D01*
G01Y592760D02*
Y591776D01*
G01X1178748Y601618D02*
Y602602D01*
G01Y591776D02*
Y592760D01*
G01X1178472D02*
Y591696D01*
G01Y602682D02*
Y601618D01*
G01X1178398Y605751D02*
Y604760D01*
G01X1178389Y589618D02*
Y588627D01*
G01X1178315Y601698D02*
Y606539D01*
G01Y587839D02*
Y592680D01*
G01X1178123Y605553D02*
Y606538D01*
G01X1178113Y587840D02*
Y588825D01*
G01X1178039Y606539D02*
Y587839D01*
G01X1177961Y589984D02*
Y583902D01*
G01Y610476D02*
Y604394D01*
G01X1177768Y606539D02*
Y605555D01*
G01X1177764Y606539D02*
Y605555D01*
G01X1177759Y588823D02*
Y587839D01*
G01X1177724Y590516D02*
Y586343D01*
G01Y608035D02*
Y603862D01*
G01X1176622D02*
Y608035D01*
G01Y586343D02*
Y590516D01*
G01X1176587Y588823D02*
Y587839D01*
G01X1176583Y588823D02*
Y587839D01*
G01Y606539D02*
Y605555D01*
G01X1176386Y589984D02*
Y583902D01*
G01Y610476D02*
Y604394D01*
G01X1176307Y587839D02*
Y606539D01*
G01X1176228Y588825D02*
Y587840D01*
G01Y606538D02*
Y605553D01*
G01X1176031Y605555D02*
Y610396D01*
G01Y583982D02*
Y588823D01*
G01X1175953Y604760D02*
Y605751D01*
G01Y588627D02*
Y589618D01*
G01X1175874Y584965D02*
Y583902D01*
G01Y610476D02*
Y609413D01*
G01X1175598Y584886D02*
Y583902D01*
G01Y610476D02*
Y609492D01*
G01X1174811D02*
Y610476D01*
G01Y584886D02*
Y583902D01*
G01X1174535Y584965D02*
Y583902D01*
G01Y610476D02*
Y609413D01*
G01X1174457Y589618D02*
Y588627D01*
G01Y605751D02*
Y604760D01*
G01X1174378Y605555D02*
Y610396D01*
G01Y583982D02*
Y588823D01*
G01X1174181Y605553D02*
Y606538D01*
G01Y587840D02*
Y588825D01*
G01X1174102Y606539D02*
Y587839D01*
G01X1174024Y589984D02*
Y583902D01*
G01Y610476D02*
Y604394D01*
G01X1173827Y588823D02*
Y587839D01*
G01Y606539D02*
Y605555D01*
G01X1173822Y606539D02*
Y605555D01*
G01X1173787Y590516D02*
Y586343D01*
G01Y608035D02*
Y603862D01*
G01X1172685D02*
Y608035D01*
G01Y586343D02*
Y590516D01*
G01X1172650Y606539D02*
Y605555D01*
G01X1172646Y588823D02*
Y587839D01*
G01X1172641Y588823D02*
Y587839D01*
G01X1172449Y589984D02*
Y583902D01*
G01Y610476D02*
Y604394D01*
G01X1172370Y587839D02*
Y606539D01*
G01X1172296Y606538D02*
Y605553D01*
G01X1172287Y588825D02*
Y587840D01*
G01X1172094Y601698D02*
Y606539D01*
G01Y587839D02*
Y592680D01*
G01X1172020Y604760D02*
Y605751D01*
G01X1172011Y588627D02*
Y589618D01*
G01X1171937Y592760D02*
Y591696D01*
G01Y602681D02*
Y601618D01*
G01X1171661D02*
Y602602D01*
G01Y592760D02*
Y591776D01*
G01X1170874Y601618D02*
Y602602D01*
G01Y591776D02*
Y592760D01*
G01X1170598D02*
Y591696D01*
G01Y602682D02*
Y601618D01*
G01X1170524Y605751D02*
Y604760D01*
G01X1170515Y589618D02*
Y588627D01*
G01X1170441Y601698D02*
Y606539D01*
G01Y587839D02*
Y592680D01*
G01X1170249Y605553D02*
Y606538D01*
G01X1170239Y587840D02*
Y588825D01*
G01X1170165Y606539D02*
Y587839D01*
G01X1170087Y589984D02*
Y583902D01*
G01Y610476D02*
Y604394D01*
G01X1169894Y606539D02*
Y605555D01*
G01X1169890Y606539D02*
Y605555D01*
G01X1169885Y588823D02*
Y587839D01*
G01X1169850Y590516D02*
Y586343D01*
G01Y608035D02*
Y603862D01*
G01X1168748D02*
Y608035D01*
G01Y586343D02*
Y590516D01*
G01X1168713Y588823D02*
Y587839D01*
G01X1168709Y588823D02*
Y587839D01*
G01Y606539D02*
Y605555D01*
G01X1168512Y589984D02*
Y583902D01*
G01Y610476D02*
Y604394D01*
G01X1168433Y587839D02*
Y606539D01*
G01X1168354Y588825D02*
Y587840D01*
G01Y606538D02*
Y605553D01*
G01X1168157Y605555D02*
Y610396D01*
G01Y583982D02*
Y588823D01*
G01X1168079Y604760D02*
Y605751D01*
G01Y588627D02*
Y589618D01*
G01X1168000Y584965D02*
Y583902D01*
G01Y610476D02*
Y609413D01*
G01X1167724Y583902D02*
Y584886D01*
G01Y610476D02*
Y609492D01*
G01X1166937Y584886D02*
Y583902D01*
G01Y610476D02*
Y609492D01*
G01X1166661Y584965D02*
Y583902D01*
G01Y610476D02*
Y609413D01*
G01X1166583Y589618D02*
Y588627D01*
G01Y605751D02*
Y604760D01*
G01X1166504Y605555D02*
Y610396D01*
G01Y583982D02*
Y588823D01*
G01X1166307Y605553D02*
Y606538D01*
G01Y587840D02*
Y588825D01*
G01X1166228Y606539D02*
Y587839D01*
G01X1166150Y589984D02*
Y583902D01*
G01Y610476D02*
Y604394D01*
G01X1165953Y588823D02*
Y587839D01*
G01Y606539D02*
Y605555D01*
G01X1165948Y606539D02*
Y605555D01*
G01X1165913Y590516D02*
Y586343D01*
G01Y608035D02*
Y603862D01*
G01X1164811D02*
Y608035D01*
G01Y586343D02*
Y590516D01*
G01X1164776Y606539D02*
Y605555D01*
G01X1164772Y588823D02*
Y587839D01*
G01X1164767Y588823D02*
Y587839D01*
G01X1164575Y589984D02*
Y583902D01*
G01Y610476D02*
Y604394D01*
G01X1164496Y587839D02*
Y606539D01*
G01X1164422Y606538D02*
Y605553D01*
G01X1164413Y588825D02*
Y587840D01*
G01X1164220Y601698D02*
Y606539D01*
G01Y587839D02*
Y592680D01*
G01X1164146Y604760D02*
Y605751D01*
G01X1164137Y588627D02*
Y589618D01*
G01X1164063Y592760D02*
Y591696D01*
G01Y602681D02*
Y601618D01*
G01X1163787D02*
Y602602D01*
G01Y592760D02*
Y591776D01*
G01X1163000Y601618D02*
Y602602D01*
G01Y592760D02*
Y591776D01*
G01X1162724Y592760D02*
Y591696D01*
G01Y602682D02*
Y601618D01*
G01X1162650Y605751D02*
Y604760D01*
G01X1162641Y589618D02*
Y588627D01*
G01X1162567Y601698D02*
Y606539D01*
G01Y587839D02*
Y592680D01*
G01X1162375Y605553D02*
Y606538D01*
G01X1162365Y587840D02*
Y588825D01*
G01X1162291Y606539D02*
Y587839D01*
G01X1162213Y589984D02*
Y583902D01*
G01Y610476D02*
Y604394D01*
G01X1162020Y606539D02*
Y605555D01*
G01X1162016Y606539D02*
Y605555D01*
G01X1162011Y588823D02*
Y587839D01*
G01X1161976Y590516D02*
Y586343D01*
G01Y608035D02*
Y603862D01*
G01X1179629Y605368D02*
X1179642Y604394D01*
G01X1178654Y589010D02*
X1178641Y589984D01*
G01X1175687Y605368D02*
X1175701Y604394D01*
G01X1174722Y589010D02*
X1174709Y589984D01*
G01X1171755Y605368D02*
X1171768Y604394D01*
G01X1170780Y589010D02*
X1170767Y589984D01*
G01X1167813Y605368D02*
X1167827Y604394D01*
G01X1166848Y589010D02*
X1166835Y589984D01*
G01X1163881Y605368D02*
X1163894Y604394D01*
G01X1162906Y589010D02*
X1162893Y589984D01*
G01X1159939Y605368D02*
X1159952Y604394D01*
G01X1182209Y600239D02*
X1182073Y606147D01*
G01X1182068Y605261D02*
X1182205Y599353D01*
G01X1180147Y589117D02*
X1180011Y595025D01*
G01X1180006Y594139D02*
X1180143Y588231D01*
G01X1178277Y600239D02*
X1178141Y606147D01*
G01X1178136Y605261D02*
X1178272Y599353D01*
G01X1176215Y589117D02*
X1176079Y595025D01*
G01X1176074Y594139D02*
X1176210Y588231D01*
G01X1174335Y600239D02*
X1174199Y606147D01*
G01X1174194Y605261D02*
X1174331Y599353D01*
G01X1172273Y589117D02*
X1172137Y595025D01*
G01X1172132Y594139D02*
X1172269Y588231D01*
G01X1170403Y600239D02*
X1170267Y606147D01*
G01X1170262Y605261D02*
X1170398Y599353D01*
G01X1168341Y589117D02*
X1168205Y595025D01*
G01X1168200Y594139D02*
X1168336Y588231D01*
G01X1166461Y600239D02*
X1166325Y606147D01*
G01X1166320Y605261D02*
X1166457Y599353D01*
G01X1164399Y589117D02*
X1164263Y595025D01*
G01X1164258Y594139D02*
X1164395Y588231D01*
G01X1162529Y600239D02*
X1162393Y606147D01*
G01X1162388Y605261D02*
X1162524Y599353D01*
G01X1160467Y589117D02*
X1160331Y595025D01*
G01X1160326Y594139D02*
X1160462Y588231D01*
G01X1178342Y594341D02*
X1178291Y595327D01*
G01X1178289Y594365D02*
X1178339Y593379D01*
G01X1176053Y600013D02*
X1176002Y600999D01*
G01X1176000Y600037D02*
X1176050Y599051D01*
G01X1174409Y594341D02*
X1174359Y595327D01*
G01X1174357Y594365D02*
X1174407Y593379D01*
G01X1172120Y600013D02*
X1172070Y600999D01*
G01X1172068Y600037D02*
X1172118Y599051D01*
G01X1170468Y594341D02*
X1170417Y595327D01*
G01X1170415Y594365D02*
X1170465Y593379D01*
G01X1168179Y600013D02*
X1168128Y600999D01*
G01X1168126Y600037D02*
X1168176Y599051D01*
G01X1166535Y594341D02*
X1166485Y595327D01*
G01X1166483Y594365D02*
X1166533Y593379D01*
G01X1164246Y600013D02*
X1164196Y600999D01*
G01X1164194Y600037D02*
X1164244Y599051D01*
G01X1162594Y594341D02*
X1162543Y595327D01*
G01X1162541Y594365D02*
X1162591Y593379D01*
G01X1160305Y600013D02*
X1160254Y600999D01*
G01X1160252Y600037D02*
X1160302Y599051D01*
G01X1178618Y589984D02*
X1178609Y589937D01*
G01X1179665Y604394D02*
X1179675Y604441D01*
G01X1174686Y589984D02*
X1174676Y589937D01*
G01X1175723Y604394D02*
X1175733Y604441D01*
G01X1170744Y589984D02*
X1170735Y589937D01*
G01X1171791Y604394D02*
X1171801Y604441D01*
G01X1166802Y589937D02*
X1166812Y589984D01*
G01X1167859Y604441D02*
X1167849Y604394D01*
G01X1162870Y589984D02*
X1162861Y589937D01*
G01X1163917Y604394D02*
X1163927Y604441D01*
G01X1168128Y593379D02*
X1168179Y594365D01*
G01X1168176Y595327D02*
X1168126Y594341D01*
G01X1166485Y599051D02*
X1166535Y600037D01*
G01X1166533Y600999D02*
X1166483Y600013D01*
G01X1164187Y593379D02*
X1164237Y594365D01*
G01X1164235Y595327D02*
X1164184Y594341D01*
G01X1162553Y599051D02*
X1162603Y600037D01*
G01X1162601Y600999D02*
X1162550Y600013D01*
G01X1160254Y593379D02*
X1160305Y594365D01*
G01X1160302Y595327D02*
X1160252Y594341D01*
G01X1164273Y599353D02*
X1164409Y605261D01*
G01X1164404Y606147D02*
X1164268Y600239D01*
G01X1162383Y588231D02*
X1162520Y594139D01*
G01X1162515Y595025D02*
X1162379Y589117D01*
G01X1160331Y599353D02*
X1160467Y605261D01*
G01X1160462Y606147D02*
X1160326Y600239D01*
G01X1162903Y604394D02*
X1162916Y605368D01*
G01X1159952Y589984D02*
X1159939Y589010D01*
G01X1160874Y603862D02*
Y608035D01*
G01Y586343D02*
Y590516D01*
G01X1160839Y588823D02*
Y587839D01*
G01X1160835Y588823D02*
Y587839D01*
G01Y606539D02*
Y605555D01*
G01X1160638Y589984D02*
Y583902D01*
G01Y610476D02*
Y604394D01*
G01X1160559Y587839D02*
Y606539D01*
G01X1160480Y588825D02*
Y587840D01*
G01Y606538D02*
Y605553D01*
G01X1160283Y605555D02*
Y610396D01*
G01Y583982D02*
Y588823D01*
G01X1160205Y604760D02*
Y605751D01*
G01Y588627D02*
Y589618D01*
G01X1160126Y584965D02*
Y583902D01*
G01Y610476D02*
Y609413D01*
G01X1159850Y583902D02*
Y584886D01*
G01Y610476D02*
Y609492D01*
G01X1159063Y584886D02*
Y583902D01*
G01Y610476D02*
Y609492D01*
G01X1182342Y588640D02*
X1182596Y589010D01*
G01X1182329Y589615D02*
X1182550Y589937D01*
G01X1178401Y588640D02*
X1178654Y589010D01*
G01X1178387Y589615D02*
X1178609Y589937D01*
G01X1174468Y588640D02*
X1174722Y589010D01*
G01X1174455Y589615D02*
X1174676Y589937D01*
G01X1170527Y588640D02*
X1170780Y589010D01*
G01X1170513Y589615D02*
X1170735Y589937D01*
G01X1179896Y604763D02*
X1179675Y604441D01*
G01X1179883Y605738D02*
X1179629Y605368D01*
G01X1166594Y588640D02*
X1166848Y589010D01*
G01X1166802Y589937D02*
X1166583Y589618D01*
G01X1175954Y604763D02*
X1175733Y604441D01*
G01X1175941Y605738D02*
X1175687Y605368D01*
G01X1162653Y588640D02*
X1162906Y589010D01*
G01X1162639Y589615D02*
X1162861Y589937D01*
G01X1172022Y604763D02*
X1171801Y604441D01*
G01X1159985D02*
X1159975Y604394D01*
G01X1172009Y605738D02*
X1171755Y605368D01*
G01X1167859Y604441D02*
X1168079Y604760D01*
G01X1168067Y605738D02*
X1167813Y605368D01*
G01X1164148Y604763D02*
X1163927Y604441D01*
G01X1164135Y605738D02*
X1163881Y605368D01*
G01X1159985Y604441D02*
X1160205Y604760D01*
G01X1160193Y605738D02*
X1159939Y605368D01*
G01X1183827Y604768D02*
Y604763D01*
G01X1183828Y604771D02*
X1183827Y604768D01*
G01X1183828Y604772D02*
Y604771D01*
G01X1183827Y605754D02*
Y605751D01*
G01X1183828Y605756D02*
X1183827Y605754D01*
G01X1183828Y605757D02*
Y605756D01*
G01X1191701Y605754D02*
Y605751D01*
G01X1191702Y605756D02*
X1191701Y605754D01*
G01X1191702Y605757D02*
Y605756D01*
G01X1199575Y605754D02*
Y605751D01*
G01X1199576Y605756D02*
X1199575Y605754D01*
G01X1199577Y605757D02*
X1199576Y605756D01*
G01X1190204Y588624D02*
X1190205Y588627D01*
G01X1190204Y588622D02*
Y588624D01*
G01X1190203Y588621D02*
X1190204Y588622D01*
G01X1207449Y605754D02*
Y605751D01*
G01X1207450Y605756D02*
X1207449Y605754D01*
G01X1207451Y605757D02*
X1207450Y605756D01*
G01X1191701Y604768D02*
Y604763D01*
G01X1191702Y604771D02*
X1191701Y604768D01*
G01X1191702Y604772D02*
Y604771D01*
G01X1190204Y589610D02*
X1190205Y589615D01*
G01X1190204Y589607D02*
Y589610D01*
G01X1190203Y589606D02*
X1190204Y589607D01*
G01X1199575Y604768D02*
Y604763D01*
G01X1199576Y604771D02*
X1199575Y604768D01*
G01X1199577Y604772D02*
X1199576Y604771D01*
G01X1198078Y589610D02*
X1198079Y589615D01*
G01X1198078Y589607D02*
Y589610D01*
G01X1198077Y589606D02*
X1198078Y589607D01*
G01X1207450Y604768D02*
X1207449Y604763D01*
G01X1207450Y604771D02*
Y604768D01*
G01X1207451Y604772D02*
X1207450Y604771D01*
G01X1205952Y589610D02*
X1205953Y589615D01*
G01X1205952Y589607D02*
Y589610D01*
G01X1205951Y589606D02*
X1205952Y589607D01*
G01X1215324Y604768D02*
X1215323Y604763D01*
G01X1215324Y604771D02*
Y604768D01*
G01X1215325Y604772D02*
X1215324Y604771D01*
G01X1198078Y588624D02*
X1198079Y588627D01*
G01X1198078Y588622D02*
Y588624D01*
G01X1198077Y588621D02*
X1198078Y588622D01*
G01X1215323Y605754D02*
Y605751D01*
G01X1215324Y605756D02*
X1215323Y605754D01*
G01X1215325Y605757D02*
X1215324Y605756D01*
G01X1205952Y588624D02*
X1205953Y588627D01*
G01X1205952Y588622D02*
Y588624D01*
G01X1205951Y588621D02*
X1205952Y588622D01*
G01X1223197Y605754D02*
Y605751D01*
G01X1223198Y605756D02*
X1223197Y605754D01*
G01X1223199Y605757D02*
X1223198Y605756D01*
G01X1213826Y588624D02*
X1213827Y588627D01*
G01X1213826Y588622D02*
Y588624D01*
G01X1213825Y588621D02*
X1213826Y588622D01*
G01X1221700Y588624D02*
X1221701Y588627D01*
G01X1221700Y588622D02*
Y588624D01*
G01X1221699Y588621D02*
X1221700Y588622D01*
G01X1183833Y604699D02*
X1183828Y604772D01*
G01X1183836Y604491D02*
X1183833Y604699D01*
G01X1183839Y604178D02*
X1183836Y604491D01*
G01X1183839Y603807D02*
Y604178D01*
G01X1183837Y605608D02*
X1183828Y605757D01*
G01X1183844Y605193D02*
X1183837Y605608D01*
G01X1183849Y604573D02*
X1183844Y605193D01*
G01X1183850Y603826D02*
X1183849Y604573D01*
G01Y589804D02*
X1183850Y590552D01*
G01X1183844Y589184D02*
X1183849Y589804D01*
G01X1183837Y588770D02*
X1183844Y589184D01*
G01X1183828Y588621D02*
X1183837Y588770D01*
G01X1190183Y604573D02*
X1190181Y603826D01*
G01X1190188Y605193D02*
X1190183Y604573D01*
G01X1190195Y605608D02*
X1190188Y605193D01*
G01X1190203Y605757D02*
X1190195Y605608D01*
G01X1191723Y589804D02*
X1191724Y590552D01*
G01X1191718Y589184D02*
X1191723Y589804D01*
G01X1191711Y588770D02*
X1191718Y589184D01*
G01X1191702Y588621D02*
X1191711Y588770D01*
G01X1183839Y590200D02*
Y590571D01*
G01X1183836Y589887D02*
X1183839Y590200D01*
G01X1183833Y589679D02*
X1183836Y589887D01*
G01X1183828Y589606D02*
X1183833Y589679D01*
G01X1190193Y604178D02*
X1190192Y603807D01*
G01X1190195Y604491D02*
X1190193Y604178D01*
G01X1190199Y604699D02*
X1190195Y604491D01*
G01X1190203Y604772D02*
X1190199Y604699D01*
G01X1191713Y590200D02*
Y590571D01*
G01X1191710Y589887D02*
X1191713Y590200D01*
G01X1191707Y589679D02*
X1191710Y589887D01*
G01X1191702Y589606D02*
X1191707Y589679D01*
G01X1184093Y605413D02*
X1184089Y605261D01*
G01X1184098Y605511D02*
X1184093Y605413D01*
G01X1184102Y605553D02*
X1184098Y605511D01*
G01X1185996Y588965D02*
X1186001Y589117D01*
G01X1185992Y588867D02*
X1185996Y588965D01*
G01X1185987Y588825D02*
X1185992Y588867D01*
G01X1188035Y605413D02*
X1188031Y605261D01*
G01X1188040Y605511D02*
X1188035Y605413D01*
G01X1188044Y605553D02*
X1188040Y605511D01*
G01X1189938Y588965D02*
X1189942Y589117D01*
G01X1189934Y588867D02*
X1189938Y588965D01*
G01X1189929Y588825D02*
X1189934Y588867D01*
G01X1191967Y605413D02*
X1191963Y605261D01*
G01X1191972Y605511D02*
X1191967Y605413D01*
G01X1191976Y605553D02*
X1191972Y605511D01*
G01X1193870Y588965D02*
X1193875Y589117D01*
G01X1193866Y588867D02*
X1193870Y588965D01*
G01X1193861Y588825D02*
X1193866Y588867D01*
G01X1195909Y605413D02*
X1195905Y605261D01*
G01X1195914Y605511D02*
X1195909Y605413D01*
G01X1195918Y605553D02*
X1195914Y605511D01*
G01X1197812Y588965D02*
X1197816Y589117D01*
G01X1197808Y588867D02*
X1197812Y588965D01*
G01X1197803Y588825D02*
X1197808Y588867D01*
G01X1199841Y605413D02*
X1199837Y605261D01*
G01X1199846Y605511D02*
X1199841Y605413D01*
G01X1199850Y605553D02*
X1199846Y605511D01*
G01X1184090Y606353D02*
X1184084Y606147D01*
G01X1184096Y606485D02*
X1184090Y606353D01*
G01X1184102Y606538D02*
X1184096Y606485D01*
G01X1188032Y606353D02*
X1188026Y606147D01*
G01X1188038Y606485D02*
X1188032Y606353D01*
G01X1188044Y606538D02*
X1188038Y606485D01*
G01X1186000Y588025D02*
X1186005Y588231D01*
G01X1185994Y587893D02*
X1186000Y588025D01*
G01X1185987Y587840D02*
X1185994Y587893D01*
G01X1191964Y606353D02*
X1191958Y606147D01*
G01X1191970Y606485D02*
X1191964Y606353D01*
G01X1191976Y606538D02*
X1191970Y606485D01*
G01X1189941Y588025D02*
X1189947Y588231D01*
G01X1189935Y587893D02*
X1189941Y588025D01*
G01X1189929Y587840D02*
X1189935Y587893D01*
G01X1195906Y606353D02*
X1195900Y606147D01*
G01X1195912Y606485D02*
X1195906Y606353D01*
G01X1195918Y606538D02*
X1195912Y606485D01*
G01X1193874Y588025D02*
X1193879Y588231D01*
G01X1193868Y587893D02*
X1193874Y588025D01*
G01X1193861Y587840D02*
X1193868Y587893D01*
G01X1199838Y606353D02*
X1199832Y606147D01*
G01X1199844Y606485D02*
X1199838Y606353D01*
G01X1199850Y606538D02*
X1199844Y606485D01*
G01X1197815Y588025D02*
X1197821Y588231D01*
G01X1197809Y587893D02*
X1197815Y588025D01*
G01X1197803Y587840D02*
X1197809Y587893D01*
G01X1186261Y604209D02*
X1186260Y603807D01*
G01X1186264Y604537D02*
X1186261Y604209D01*
G01X1186268Y604733D02*
X1186264Y604537D01*
G01X1186272Y604763D02*
X1186268Y604733D01*
G01X1187771Y590169D02*
X1187772Y590571D01*
G01X1187768Y589841D02*
X1187771Y590169D01*
G01X1187764Y589645D02*
X1187768Y589841D01*
G01X1187759Y589615D02*
X1187764Y589645D01*
G01X1194135Y604209D02*
X1194134Y603807D01*
G01X1194138Y604537D02*
X1194135Y604209D01*
G01X1194142Y604733D02*
X1194138Y604537D01*
G01X1194146Y604763D02*
X1194142Y604733D01*
G01X1195645Y590169D02*
X1195646Y590571D01*
G01X1195642Y589841D02*
X1195645Y590169D01*
G01X1195638Y589645D02*
X1195642Y589841D01*
G01X1195633Y589615D02*
X1195638Y589645D01*
G01X1202009Y604209D02*
X1202008Y603807D01*
G01X1202012Y604537D02*
X1202009Y604209D01*
G01X1202016Y604733D02*
X1202012Y604537D01*
G01X1202020Y604763D02*
X1202016Y604733D01*
G01X1203519Y590169D02*
X1203520Y590571D01*
G01X1203516Y589841D02*
X1203519Y590169D01*
G01X1203512Y589645D02*
X1203516Y589841D01*
G01X1203507Y589615D02*
X1203512Y589645D01*
G01X1213826Y589610D02*
X1213827Y589615D01*
G01X1213826Y589607D02*
Y589610D01*
G01X1213825Y589606D02*
X1213826Y589607D01*
G01X1223198Y604768D02*
X1223197Y604763D01*
G01X1223198Y604771D02*
Y604768D01*
G01X1223199Y604772D02*
X1223198Y604771D01*
G01X1221700Y589610D02*
X1221701Y589615D01*
G01X1221700Y589607D02*
Y589610D01*
G01X1221699Y589606D02*
X1221700Y589607D01*
G01X1183828D02*
Y589606D01*
G01X1183827Y589610D02*
X1183828Y589607D01*
G01X1183827Y589615D02*
Y589610D01*
G01X1190204Y604771D02*
X1190203Y604772D01*
G01X1190204Y604768D02*
Y604771D01*
G01X1190205Y604763D02*
X1190204Y604768D01*
G01X1191702Y589607D02*
Y589606D01*
G01X1191701Y589610D02*
X1191702Y589607D01*
G01X1191701Y589615D02*
Y589610D01*
G01X1184096Y587893D02*
X1184102Y587840D01*
G01X1184090Y588025D02*
X1184096Y587893D01*
G01X1184084Y588231D02*
X1184090Y588025D01*
G01X1186003Y606485D02*
X1185997Y606538D01*
G01X1186009Y606353D02*
X1186003Y606485D01*
G01X1186015Y606147D02*
X1186009Y606353D01*
G01X1188029Y587893D02*
X1188035Y587840D01*
G01X1188022Y588025D02*
X1188029Y587893D01*
G01X1188017Y588231D02*
X1188022Y588025D01*
G01X1189935Y606485D02*
X1189929Y606538D01*
G01X1189941Y606353D02*
X1189935Y606485D01*
G01X1189947Y606147D02*
X1189941Y606353D01*
G01X1191970Y587893D02*
X1191976Y587840D01*
G01X1191964Y588025D02*
X1191970Y587893D01*
G01X1191958Y588231D02*
X1191964Y588025D01*
G01X1193877Y606485D02*
X1193871Y606538D01*
G01X1193883Y606353D02*
X1193877Y606485D01*
G01X1193889Y606147D02*
X1193883Y606353D01*
G01X1195903Y587893D02*
X1195909Y587840D01*
G01X1195896Y588025D02*
X1195903Y587893D01*
G01X1195891Y588231D02*
X1195896Y588025D01*
G01X1197809Y606485D02*
X1197803Y606538D01*
G01X1197815Y606353D02*
X1197809Y606485D01*
G01X1197821Y606147D02*
X1197815Y606353D01*
G01X1199844Y587893D02*
X1199850Y587840D01*
G01X1199838Y588025D02*
X1199844Y587893D01*
G01X1199832Y588231D02*
X1199838Y588025D01*
G01X1201751Y606485D02*
X1201745Y606538D01*
G01X1201757Y606353D02*
X1201751Y606485D01*
G01X1201763Y606147D02*
X1201757Y606353D01*
G01X1203777Y587893D02*
X1203783Y587840D01*
G01X1203771Y588025D02*
X1203777Y587893D01*
G01X1203765Y588231D02*
X1203771Y588025D01*
G01X1205683Y606485D02*
X1205677Y606538D01*
G01X1205689Y606353D02*
X1205683Y606485D01*
G01X1205695Y606147D02*
X1205689Y606353D01*
G01X1184098Y588867D02*
X1184102Y588825D01*
G01X1184093Y588965D02*
X1184098Y588867D01*
G01X1184089Y589117D02*
X1184093Y588965D01*
G01X1186001Y605511D02*
X1185997Y605553D01*
G01X1186006Y605413D02*
X1186001Y605511D01*
G01X1186010Y605261D02*
X1186006Y605413D01*
G01X1188030Y588867D02*
X1188035Y588825D01*
G01X1188026Y588965D02*
X1188030Y588867D01*
G01X1188021Y589117D02*
X1188026Y588965D01*
G01X1189934Y605511D02*
X1189929Y605553D01*
G01X1189938Y605413D02*
X1189934Y605511D01*
G01X1189942Y605261D02*
X1189938Y605413D01*
G01X1191972Y588867D02*
X1191976Y588825D01*
G01X1191967Y588965D02*
X1191972Y588867D01*
G01X1191963Y589117D02*
X1191967Y588965D01*
G01X1193875Y605511D02*
X1193871Y605553D01*
G01X1193880Y605413D02*
X1193875Y605511D01*
G01X1193884Y605261D02*
X1193880Y605413D01*
G01X1195904Y588867D02*
X1195909Y588825D01*
G01X1195900Y588965D02*
X1195904Y588867D01*
G01X1195896Y589117D02*
X1195900Y588965D01*
G01X1197808Y605511D02*
X1197803Y605553D01*
G01X1197812Y605413D02*
X1197808Y605511D01*
G01X1197816Y605261D02*
X1197812Y605413D01*
G01X1199846Y588867D02*
X1199850Y588825D01*
G01X1199841Y588965D02*
X1199846Y588867D01*
G01X1199837Y589117D02*
X1199841Y588965D01*
G01X1201749Y605511D02*
X1201745Y605553D01*
G01X1201754Y605413D02*
X1201749Y605511D01*
G01X1201758Y605261D02*
X1201754Y605413D01*
G01X1203778Y588867D02*
X1203783Y588825D01*
G01X1203774Y588965D02*
X1203778Y588867D01*
G01X1203770Y589117D02*
X1203774Y588965D01*
G01X1205682Y605511D02*
X1205677Y605553D01*
G01X1205686Y605413D02*
X1205682Y605511D01*
G01X1205690Y605261D02*
X1205686Y605413D01*
G01X1186258Y589645D02*
X1186263Y589615D01*
G01X1186254Y589841D02*
X1186258Y589645D01*
G01X1186251Y590169D02*
X1186254Y589841D01*
G01X1186250Y590571D02*
X1186251Y590169D01*
G01X1187773Y604733D02*
X1187769Y604763D01*
G01X1187777Y604537D02*
X1187773Y604733D01*
G01X1187780Y604209D02*
X1187777Y604537D01*
G01X1187781Y603807D02*
X1187780Y604209D01*
G01X1194132Y589645D02*
X1194137Y589615D01*
G01X1194128Y589841D02*
X1194132Y589645D01*
G01X1194125Y590169D02*
X1194128Y589841D01*
G01X1194124Y590571D02*
X1194125Y590169D01*
G01X1195647Y604733D02*
X1195643Y604763D01*
G01X1195651Y604537D02*
X1195647Y604733D01*
G01X1195654Y604209D02*
X1195651Y604537D01*
G01X1195655Y603807D02*
X1195654Y604209D01*
G01X1202006Y589645D02*
X1202011Y589615D01*
G01X1202002Y589841D02*
X1202006Y589645D01*
G01X1201999Y590169D02*
X1202002Y589841D01*
G01X1201998Y590571D02*
X1201999Y590169D01*
G01X1203521Y604733D02*
X1203517Y604763D01*
G01X1203525Y604537D02*
X1203521Y604733D01*
G01X1203528Y604209D02*
X1203525Y604537D01*
G01X1203529Y603807D02*
X1203528Y604209D01*
G01X1209880Y589645D02*
X1209885Y589615D01*
G01X1209876Y589841D02*
X1209880Y589645D01*
G01X1209873Y590169D02*
X1209876Y589841D01*
G01X1209872Y590571D02*
X1209873Y590169D01*
G01X1190195Y588770D02*
X1190203Y588621D01*
G01X1190188Y589184D02*
X1190195Y588770D01*
G01X1190183Y589804D02*
X1190188Y589184D01*
G01X1190181Y590552D02*
X1190183Y589804D01*
G01X1190199Y589679D02*
X1190203Y589606D01*
G01X1190195Y589887D02*
X1190199Y589679D01*
G01X1190193Y590200D02*
X1190195Y589887D01*
G01X1190192Y590571D02*
X1190193Y590200D01*
G01X1191707Y604699D02*
X1191702Y604772D01*
G01X1191710Y604491D02*
X1191707Y604699D01*
G01X1191713Y604178D02*
X1191710Y604491D01*
G01X1191713Y603807D02*
Y604178D01*
G01X1191711Y605608D02*
X1191702Y605757D01*
G01X1191718Y605193D02*
X1191711Y605608D01*
G01X1191723Y604573D02*
X1191718Y605193D01*
G01X1191724Y603826D02*
X1191723Y604573D01*
G01X1198069Y588770D02*
X1198077Y588621D01*
G01X1198062Y589184D02*
X1198069Y588770D01*
G01X1198057Y589804D02*
X1198062Y589184D01*
G01X1198055Y590552D02*
X1198057Y589804D01*
G01X1198073Y589679D02*
X1198077Y589606D01*
G01X1198069Y589887D02*
X1198073Y589679D01*
G01X1198067Y590200D02*
X1198069Y589887D01*
G01X1198066Y590571D02*
X1198067Y590200D01*
G01X1199581Y604699D02*
X1199577Y604772D01*
G01X1199584Y604491D02*
X1199581Y604699D01*
G01X1199587Y604178D02*
X1199584Y604491D01*
G01X1199587Y603807D02*
Y604178D01*
G01X1199585Y605608D02*
X1199577Y605757D01*
G01X1199592Y605193D02*
X1199585Y605608D01*
G01X1199597Y604573D02*
X1199592Y605193D01*
G01X1199598Y603826D02*
X1199597Y604573D01*
G01X1205943Y588770D02*
X1205951Y588621D01*
G01X1205936Y589184D02*
X1205943Y588770D01*
G01X1205931Y589804D02*
X1205936Y589184D01*
G01X1205929Y590552D02*
X1205931Y589804D01*
G01X1205947Y589679D02*
X1205951Y589606D01*
G01X1205943Y589887D02*
X1205947Y589679D01*
G01X1205941Y590200D02*
X1205943Y589887D01*
G01X1205940Y590571D02*
X1205941Y590200D01*
G01X1207455Y604699D02*
X1207451Y604772D01*
G01X1207458Y604491D02*
X1207455Y604699D01*
G01X1207461Y604178D02*
X1207458Y604491D01*
G01X1207461Y603807D02*
Y604178D01*
G01X1207459Y605608D02*
X1207451Y605757D01*
G01X1207466Y605193D02*
X1207459Y605608D01*
G01X1207471Y604573D02*
X1207466Y605193D01*
G01X1207472Y603826D02*
X1207471Y604573D01*
G01X1198057D02*
X1198055Y603826D01*
G01X1198062Y605193D02*
X1198057Y604573D01*
G01X1198069Y605608D02*
X1198062Y605193D01*
G01X1198077Y605757D02*
X1198069Y605608D01*
G01X1199597Y589804D02*
X1199598Y590552D01*
G01X1199592Y589184D02*
X1199597Y589804D01*
G01X1199585Y588770D02*
X1199592Y589184D01*
G01X1199577Y588621D02*
X1199585Y588770D01*
G01X1205931Y604573D02*
X1205929Y603826D01*
G01X1205936Y605193D02*
X1205931Y604573D01*
G01X1205943Y605608D02*
X1205936Y605193D01*
G01X1205951Y605757D02*
X1205943Y605608D01*
G01X1207471Y589804D02*
X1207472Y590552D01*
G01X1207466Y589184D02*
X1207471Y589804D01*
G01X1207459Y588770D02*
X1207466Y589184D01*
G01X1207451Y588621D02*
X1207459Y588770D01*
G01X1213805Y604573D02*
X1213803Y603826D01*
G01X1213810Y605193D02*
X1213805Y604573D01*
G01X1213817Y605608D02*
X1213810Y605193D01*
G01X1213825Y605757D02*
X1213817Y605608D01*
G01X1215345Y589804D02*
X1215346Y590552D01*
G01X1215340Y589184D02*
X1215345Y589804D01*
G01X1215333Y588770D02*
X1215340Y589184D01*
G01X1215325Y588621D02*
X1215333Y588770D01*
G01X1198067Y604178D02*
X1198066Y603807D01*
G01X1198069Y604491D02*
X1198067Y604178D01*
G01X1198073Y604699D02*
X1198069Y604491D01*
G01X1198077Y604772D02*
X1198073Y604699D01*
G01X1199587Y590200D02*
Y590571D01*
G01X1199584Y589887D02*
X1199587Y590200D01*
G01X1199581Y589679D02*
X1199584Y589887D01*
G01X1199577Y589606D02*
X1199581Y589679D01*
G01X1205941Y604178D02*
X1205940Y603807D01*
G01X1205943Y604491D02*
X1205941Y604178D01*
G01X1205947Y604699D02*
X1205943Y604491D01*
G01X1205951Y604772D02*
X1205947Y604699D01*
G01X1207461Y590200D02*
Y590571D01*
G01X1207458Y589887D02*
X1207461Y590200D01*
G01X1207455Y589679D02*
X1207458Y589887D01*
G01X1207451Y589606D02*
X1207455Y589679D01*
G01X1213815Y604178D02*
X1213814Y603807D01*
G01X1213817Y604491D02*
X1213815Y604178D01*
G01X1213821Y604699D02*
X1213817Y604491D01*
G01X1213825Y604772D02*
X1213821Y604699D01*
G01X1215335Y590200D02*
X1215336Y590571D01*
G01X1215332Y589887D02*
X1215335Y590200D01*
G01X1215329Y589679D02*
X1215332Y589887D01*
G01X1215325Y589606D02*
X1215329Y589679D01*
G01X1201744Y588965D02*
X1201749Y589117D01*
G01X1201740Y588867D02*
X1201744Y588965D01*
G01X1201735Y588825D02*
X1201740Y588867D01*
G01X1203783Y605413D02*
X1203779Y605261D01*
G01X1203788Y605511D02*
X1203783Y605413D01*
G01X1203792Y605553D02*
X1203788Y605511D01*
G01X1205686Y588965D02*
X1205690Y589117D01*
G01X1205682Y588867D02*
X1205686Y588965D01*
G01X1205677Y588825D02*
X1205682Y588867D01*
G01X1207715Y605413D02*
X1207711Y605261D01*
G01X1207720Y605511D02*
X1207715Y605413D01*
G01X1207724Y605553D02*
X1207720Y605511D01*
G01X1209618Y588965D02*
X1209623Y589117D01*
G01X1209614Y588867D02*
X1209618Y588965D01*
G01X1209610Y588825D02*
X1209614Y588867D01*
G01X1211657Y605413D02*
X1211653Y605261D01*
G01X1211662Y605511D02*
X1211657Y605413D01*
G01X1211666Y605553D02*
X1211662Y605511D01*
G01X1213560Y588965D02*
X1213564Y589117D01*
G01X1213556Y588867D02*
X1213560Y588965D01*
G01X1213551Y588825D02*
X1213556Y588867D01*
G01X1215589Y605413D02*
X1215585Y605261D01*
G01X1215594Y605511D02*
X1215589Y605413D01*
G01X1215598Y605553D02*
X1215594Y605511D01*
G01X1217492Y588965D02*
X1217497Y589117D01*
G01X1217488Y588867D02*
X1217492Y588965D01*
G01X1217484Y588825D02*
X1217488Y588867D01*
G01X1219531Y605413D02*
X1219527Y605261D01*
G01X1219536Y605511D02*
X1219531Y605413D01*
G01X1219540Y605553D02*
X1219536Y605511D01*
G01X1221434Y588965D02*
X1221438Y589117D01*
G01X1221430Y588867D02*
X1221434Y588965D01*
G01X1221425Y588825D02*
X1221430Y588867D01*
G01X1223463Y605413D02*
X1223459Y605261D01*
G01X1223468Y605511D02*
X1223463Y605413D01*
G01X1223472Y605553D02*
X1223468Y605511D01*
G01X1203780Y606353D02*
X1203774Y606147D01*
G01X1203786Y606485D02*
X1203780Y606353D01*
G01X1203792Y606538D02*
X1203786Y606485D01*
G01X1201748Y588025D02*
X1201753Y588231D01*
G01X1201742Y587893D02*
X1201748Y588025D01*
G01X1201735Y587840D02*
X1201742Y587893D01*
G01X1207712Y606353D02*
X1207706Y606147D01*
G01X1207718Y606485D02*
X1207712Y606353D01*
G01X1207724Y606538D02*
X1207718Y606485D01*
G01X1205689Y588025D02*
X1205695Y588231D01*
G01X1205683Y587893D02*
X1205689Y588025D01*
G01X1205677Y587840D02*
X1205683Y587893D01*
G01X1211654Y606353D02*
X1211648Y606147D01*
G01X1211660Y606485D02*
X1211654Y606353D01*
G01X1211666Y606538D02*
X1211660Y606485D01*
G01X1209622Y588025D02*
X1209627Y588231D01*
G01X1209616Y587893D02*
X1209622Y588025D01*
G01X1209610Y587840D02*
X1209616Y587893D01*
G01X1215586Y606353D02*
X1215580Y606147D01*
G01X1215592Y606485D02*
X1215586Y606353D01*
G01X1215598Y606538D02*
X1215592Y606485D01*
G01X1213563Y588025D02*
X1213569Y588231D01*
G01X1213557Y587893D02*
X1213563Y588025D01*
G01X1213551Y587840D02*
X1213557Y587893D01*
G01X1219528Y606353D02*
X1219522Y606147D01*
G01X1219534Y606485D02*
X1219528Y606353D01*
G01X1219540Y606538D02*
X1219534Y606485D01*
G01X1217496Y588025D02*
X1217502Y588231D01*
G01X1217490Y587893D02*
X1217496Y588025D01*
G01X1217484Y587840D02*
X1217490Y587893D01*
G01X1223460Y606353D02*
X1223454Y606147D01*
G01X1223466Y606485D02*
X1223460Y606353D01*
G01X1223472Y606538D02*
X1223466Y606485D01*
G01X1221437Y588025D02*
X1221443Y588231D01*
G01X1221431Y587893D02*
X1221437Y588025D01*
G01X1221425Y587840D02*
X1221431Y587893D01*
G01X1209883Y604209D02*
X1209882Y603807D01*
G01X1209886Y604537D02*
X1209883Y604209D01*
G01X1209890Y604733D02*
X1209886Y604537D01*
G01X1209894Y604763D02*
X1209890Y604733D01*
G01X1211393Y590169D02*
X1211394Y590571D01*
G01X1211390Y589841D02*
X1211393Y590169D01*
G01X1211386Y589645D02*
X1211390Y589841D01*
G01X1211381Y589615D02*
X1211386Y589645D01*
G01X1217757Y604209D02*
X1217756Y603807D01*
G01X1217760Y604537D02*
X1217757Y604209D01*
G01X1217764Y604733D02*
X1217760Y604537D01*
G01X1217768Y604763D02*
X1217764Y604733D01*
G01X1219267Y590169D02*
X1219268Y590571D01*
G01X1219264Y589841D02*
X1219267Y590169D01*
G01X1219260Y589645D02*
X1219264Y589841D01*
G01X1219255Y589615D02*
X1219260Y589645D01*
G01X1225631Y604209D02*
X1225630Y603807D01*
G01X1225634Y604537D02*
X1225631Y604209D01*
G01X1225638Y604733D02*
X1225634Y604537D01*
G01X1225642Y604763D02*
X1225638Y604733D01*
G01X1227141Y590169D02*
X1227142Y590571D01*
G01X1227138Y589841D02*
X1227141Y590169D01*
G01X1227134Y589645D02*
X1227138Y589841D01*
G01X1227129Y589615D02*
X1227134Y589645D01*
G01X1183828Y588622D02*
Y588621D01*
G01X1183827Y588624D02*
X1183828Y588622D01*
G01X1183827Y588627D02*
Y588624D01*
G01X1198078Y604771D02*
X1198077Y604772D01*
G01X1198078Y604768D02*
Y604771D01*
G01X1198079Y604763D02*
X1198078Y604768D01*
G01X1199576Y589607D02*
X1199577Y589606D01*
G01X1199575Y589610D02*
X1199576Y589607D01*
G01X1199575Y589615D02*
Y589610D01*
G01X1205952Y604771D02*
X1205951Y604772D01*
G01X1205952Y604768D02*
Y604771D01*
G01X1205953Y604763D02*
X1205952Y604768D01*
G01X1207450Y589607D02*
X1207451Y589606D01*
G01X1207450Y589610D02*
Y589607D01*
G01X1207449Y589615D02*
X1207450Y589610D01*
G01X1213826Y604771D02*
X1213825Y604772D01*
G01X1213826Y604768D02*
Y604771D01*
G01X1213827Y604763D02*
X1213826Y604768D01*
G01X1215324Y589607D02*
X1215325Y589606D01*
G01X1215324Y589610D02*
Y589607D01*
G01X1215323Y589615D02*
X1215324Y589610D01*
G01X1207718Y587893D02*
X1207724Y587840D01*
G01X1207712Y588025D02*
X1207718Y587893D01*
G01X1207706Y588231D02*
X1207712Y588025D01*
G01X1209625Y606485D02*
X1209619Y606538D01*
G01X1209631Y606353D02*
X1209625Y606485D01*
G01X1209637Y606147D02*
X1209631Y606353D01*
G01X1211651Y587893D02*
X1211657Y587840D01*
G01X1211645Y588025D02*
X1211651Y587893D01*
G01X1211639Y588231D02*
X1211645Y588025D01*
G01X1213557Y606485D02*
X1213551Y606538D01*
G01X1213563Y606353D02*
X1213557Y606485D01*
G01X1213569Y606147D02*
X1213563Y606353D01*
G01X1215592Y587893D02*
X1215598Y587840D01*
G01X1215586Y588025D02*
X1215592Y587893D01*
G01X1215580Y588231D02*
X1215586Y588025D01*
G01X1217499Y606485D02*
X1217493Y606538D01*
G01X1217505Y606353D02*
X1217499Y606485D01*
G01X1217511Y606147D02*
X1217505Y606353D01*
G01X1219525Y587893D02*
X1219531Y587840D01*
G01X1219519Y588025D02*
X1219525Y587893D01*
G01X1219513Y588231D02*
X1219519Y588025D01*
G01X1221431Y606485D02*
X1221425Y606538D01*
G01X1221437Y606353D02*
X1221431Y606485D01*
G01X1221443Y606147D02*
X1221437Y606353D01*
G01X1223466Y587893D02*
X1223472Y587840D01*
G01X1223460Y588025D02*
X1223466Y587893D01*
G01X1223454Y588231D02*
X1223460Y588025D01*
G01X1225373Y606485D02*
X1225367Y606538D01*
G01X1225379Y606353D02*
X1225373Y606485D01*
G01X1225385Y606147D02*
X1225379Y606353D01*
G01X1227399Y587893D02*
X1227405Y587840D01*
G01X1227393Y588025D02*
X1227399Y587893D01*
G01X1227387Y588231D02*
X1227393Y588025D01*
G01X1207720Y588867D02*
X1207724Y588825D01*
G01X1207715Y588965D02*
X1207720Y588867D01*
G01X1207711Y589117D02*
X1207715Y588965D01*
G01X1209623Y605511D02*
X1209619Y605553D01*
G01X1209628Y605413D02*
X1209623Y605511D01*
G01X1209632Y605261D02*
X1209628Y605413D01*
G01X1211652Y588867D02*
X1211657Y588825D01*
G01X1211648Y588965D02*
X1211652Y588867D01*
G01X1211644Y589117D02*
X1211648Y588965D01*
G01X1213556Y605511D02*
X1213551Y605553D01*
G01X1213560Y605413D02*
X1213556Y605511D01*
G01X1213564Y605261D02*
X1213560Y605413D01*
G01X1215594Y588867D02*
X1215598Y588825D01*
G01X1215589Y588965D02*
X1215594Y588867D01*
G01X1215585Y589117D02*
X1215589Y588965D01*
G01X1217497Y605511D02*
X1217493Y605553D01*
G01X1217502Y605413D02*
X1217497Y605511D01*
G01X1217506Y605261D02*
X1217502Y605413D01*
G01X1219526Y588867D02*
X1219531Y588825D01*
G01X1219522Y588965D02*
X1219526Y588867D01*
G01X1219518Y589117D02*
X1219522Y588965D01*
G01X1221430Y605511D02*
X1221425Y605553D01*
G01X1221434Y605413D02*
X1221430Y605511D01*
G01X1221438Y605261D02*
X1221434Y605413D01*
G01X1223468Y588867D02*
X1223472Y588825D01*
G01X1223463Y588965D02*
X1223468Y588867D01*
G01X1223459Y589117D02*
X1223463Y588965D01*
G01X1225371Y605511D02*
X1225367Y605553D01*
G01X1225376Y605413D02*
X1225371Y605511D01*
G01X1225380Y605261D02*
X1225376Y605413D01*
G01X1227400Y588867D02*
X1227405Y588825D01*
G01X1227396Y588965D02*
X1227400Y588867D01*
G01X1227392Y589117D02*
X1227396Y588965D01*
G01X1211395Y604733D02*
X1211391Y604763D01*
G01X1211399Y604537D02*
X1211395Y604733D01*
G01X1211402Y604209D02*
X1211399Y604537D01*
G01X1211403Y603807D02*
X1211402Y604209D01*
G01X1217754Y589645D02*
X1217759Y589615D01*
G01X1217750Y589841D02*
X1217754Y589645D01*
G01X1217747Y590169D02*
X1217750Y589841D01*
G01X1217746Y590571D02*
X1217747Y590169D01*
G01X1219269Y604733D02*
X1219265Y604763D01*
G01X1219273Y604537D02*
X1219269Y604733D01*
G01X1219276Y604209D02*
X1219273Y604537D01*
G01X1219277Y603807D02*
X1219276Y604209D01*
G01X1225628Y589645D02*
X1225633Y589615D01*
G01X1225624Y589841D02*
X1225628Y589645D01*
G01X1225621Y590169D02*
X1225624Y589841D01*
G01X1225620Y590571D02*
X1225621Y590169D01*
G01X1227143Y604733D02*
X1227139Y604763D01*
G01X1227147Y604537D02*
X1227143Y604733D01*
G01X1227150Y604209D02*
X1227147Y604537D01*
G01X1227151Y603807D02*
X1227150Y604209D01*
G01X1213817Y588770D02*
X1213825Y588621D01*
G01X1213810Y589184D02*
X1213817Y588770D01*
G01X1213805Y589804D02*
X1213810Y589184D01*
G01X1213803Y590552D02*
X1213805Y589804D01*
G01X1213821Y589679D02*
X1213825Y589606D01*
G01X1213817Y589887D02*
X1213821Y589679D01*
G01X1213815Y590200D02*
X1213817Y589887D01*
G01X1213814Y590571D02*
X1213815Y590200D01*
G01X1215329Y604699D02*
X1215325Y604772D01*
G01X1215332Y604491D02*
X1215329Y604699D01*
G01X1215335Y604178D02*
X1215332Y604491D01*
G01X1215336Y603807D02*
X1215335Y604178D01*
G01X1215333Y605608D02*
X1215325Y605757D01*
G01X1215340Y605193D02*
X1215333Y605608D01*
G01X1215345Y604573D02*
X1215340Y605193D01*
G01X1215346Y603826D02*
X1215345Y604573D01*
G01X1221691Y588770D02*
X1221699Y588621D01*
G01X1221684Y589184D02*
X1221691Y588770D01*
G01X1221679Y589804D02*
X1221684Y589184D01*
G01X1221677Y590552D02*
X1221679Y589804D01*
G01X1221695Y589679D02*
X1221699Y589606D01*
G01X1221691Y589887D02*
X1221695Y589679D01*
G01X1221689Y590200D02*
X1221691Y589887D01*
G01X1221688Y590571D02*
X1221689Y590200D01*
G01X1223203Y604699D02*
X1223199Y604772D01*
G01X1223206Y604491D02*
X1223203Y604699D01*
G01X1223209Y604178D02*
X1223206Y604491D01*
G01X1223210Y603807D02*
X1223209Y604178D01*
G01X1223207Y605608D02*
X1223199Y605757D01*
G01X1223214Y605193D02*
X1223207Y605608D01*
G01X1223219Y604573D02*
X1223214Y605193D01*
G01X1223220Y603826D02*
X1223219Y604573D01*
G01X1221679D02*
X1221677Y603826D01*
G01X1221684Y605193D02*
X1221679Y604573D01*
G01X1221691Y605608D02*
X1221684Y605193D01*
G01X1221699Y605757D02*
X1221691Y605608D01*
G01X1223219Y589804D02*
X1223220Y590552D01*
G01X1223214Y589184D02*
X1223219Y589804D01*
G01X1223207Y588770D02*
X1223214Y589184D01*
G01X1223199Y588621D02*
X1223207Y588770D01*
G01X1221689Y604178D02*
X1221688Y603807D01*
G01X1221691Y604491D02*
X1221689Y604178D01*
G01X1221695Y604699D02*
X1221691Y604491D01*
G01X1221699Y604772D02*
X1221695Y604699D01*
G01X1223209Y590200D02*
X1223210Y590571D01*
G01X1223206Y589887D02*
X1223209Y590200D01*
G01X1223203Y589679D02*
X1223206Y589887D01*
G01X1223199Y589606D02*
X1223203Y589679D01*
G01X1225366Y588965D02*
X1225371Y589117D01*
G01X1225362Y588867D02*
X1225366Y588965D01*
G01X1225358Y588825D02*
X1225362Y588867D01*
G01X1227405Y605413D02*
X1227401Y605261D01*
G01X1227410Y605511D02*
X1227405Y605413D01*
G01X1227414Y605553D02*
X1227410Y605511D01*
G01X1227402Y606353D02*
X1227396Y606147D01*
G01X1227408Y606485D02*
X1227402Y606353D01*
G01X1227414Y606538D02*
X1227408Y606485D01*
G01X1225370Y588025D02*
X1225376Y588231D01*
G01X1225364Y587893D02*
X1225370Y588025D01*
G01X1225358Y587840D02*
X1225364Y587893D01*
G01X1191702Y588622D02*
Y588621D01*
G01X1191701Y588624D02*
X1191702Y588622D01*
G01X1191701Y588627D02*
Y588624D01*
G01X1190204Y605756D02*
X1190203Y605757D01*
G01X1190204Y605754D02*
Y605756D01*
G01X1190205Y605751D02*
X1190204Y605754D01*
G01X1199576Y588622D02*
X1199577Y588621D01*
G01X1199575Y588624D02*
X1199576Y588622D01*
G01X1199575Y588627D02*
Y588624D01*
G01X1198078Y605756D02*
X1198077Y605757D01*
G01X1198078Y605754D02*
Y605756D01*
G01X1198079Y605751D02*
X1198078Y605754D01*
G01X1207450Y588622D02*
X1207451Y588621D01*
G01X1207449Y588624D02*
X1207450Y588622D01*
G01X1207449Y588627D02*
Y588624D01*
G01X1205952Y605756D02*
X1205951Y605757D01*
G01X1205952Y605754D02*
Y605756D01*
G01X1205953Y605751D02*
X1205952Y605754D01*
G01X1221700Y604771D02*
X1221699Y604772D01*
G01X1221700Y604768D02*
Y604771D01*
G01X1221701Y604763D02*
X1221700Y604768D01*
G01X1223198Y589607D02*
X1223199Y589606D01*
G01X1223198Y589610D02*
Y589607D01*
G01X1223197Y589615D02*
X1223198Y589610D01*
G01X1215324Y588622D02*
X1215325Y588621D01*
G01X1215323Y588624D02*
X1215324Y588622D01*
G01X1215323Y588627D02*
Y588624D01*
G01X1213826Y605756D02*
X1213825Y605757D01*
G01X1213826Y605754D02*
Y605756D01*
G01X1213827Y605751D02*
X1213826Y605754D01*
G01X1223198Y588622D02*
X1223199Y588621D01*
G01X1223197Y588624D02*
X1223198Y588622D01*
G01X1223197Y588627D02*
Y588624D01*
G01X1221700Y605756D02*
X1221699Y605757D01*
G01X1221700Y605754D02*
Y605756D01*
G01X1221701Y605751D02*
X1221700Y605754D01*
G01X1227435Y588823D02*
X1227450D01*
G01X1227420Y588824D02*
X1227435Y588823D01*
G01X1227405Y588825D02*
X1227420Y588824D01*
G01X1221395Y588823D02*
X1221380D01*
G01X1221410Y588824D02*
X1221395Y588823D01*
G01X1221425Y588825D02*
X1221410Y588824D01*
G01X1217454Y588823D02*
X1217438D01*
G01X1217469Y588824D02*
X1217454Y588823D01*
G01X1217484Y588825D02*
X1217469Y588824D01*
G01X1213521Y588823D02*
X1213506D01*
G01X1213536Y588824D02*
X1213521Y588823D01*
G01X1213551Y588825D02*
X1213536Y588824D01*
G01X1209579Y588823D02*
X1209564D01*
G01X1209594Y588824D02*
X1209579Y588823D01*
G01X1209610Y588825D02*
X1209594Y588824D01*
G01X1205647Y588823D02*
X1205632D01*
G01X1205662Y588824D02*
X1205647Y588823D01*
G01X1205677Y588825D02*
X1205662Y588824D01*
G01X1201705Y588823D02*
X1201690D01*
G01X1201720Y588824D02*
X1201705Y588823D01*
G01X1201735Y588825D02*
X1201720Y588824D01*
G01X1197773Y588823D02*
X1197758D01*
G01X1197788Y588824D02*
X1197773Y588823D01*
G01X1197803Y588825D02*
X1197788Y588824D01*
G01X1193831Y588823D02*
X1193816D01*
G01X1193846Y588824D02*
X1193831Y588823D01*
G01X1193861Y588825D02*
X1193846Y588824D01*
G01X1189899Y588823D02*
X1189884D01*
G01X1189914Y588824D02*
X1189899Y588823D01*
G01X1189929Y588825D02*
X1189914Y588824D01*
G01X1185957Y588823D02*
X1185942D01*
G01X1185972Y588824D02*
X1185957Y588823D01*
G01X1185987Y588825D02*
X1185972Y588824D01*
G01X1225328Y587839D02*
X1225313D01*
G01X1225343D02*
X1225328D01*
G01X1225358Y587840D02*
X1225343Y587839D01*
G01X1221395D02*
X1221380D01*
G01X1221410D02*
X1221395D01*
G01X1221425Y587840D02*
X1221410Y587839D01*
G01X1217454D02*
X1217438D01*
G01X1217469D02*
X1217454D01*
G01X1217484Y587840D02*
X1217469Y587839D01*
G01X1213521D02*
X1213506D01*
G01X1213536D02*
X1213521D01*
G01X1213551Y587840D02*
X1213536Y587839D01*
G01X1209579D02*
X1209564D01*
G01X1209594D02*
X1209579D01*
G01X1209610Y587840D02*
X1209594Y587839D01*
G01X1205647D02*
X1205632D01*
G01X1205662D02*
X1205647D01*
G01X1205677Y587840D02*
X1205662Y587839D01*
G01X1201705D02*
X1201690D01*
G01X1201720D02*
X1201705D01*
G01X1201735Y587840D02*
X1201720Y587839D01*
G01X1197773D02*
X1197758D01*
G01X1197788D02*
X1197773D01*
G01X1197803Y587840D02*
X1197788Y587839D01*
G01X1193831D02*
X1193816D01*
G01X1193846D02*
X1193831D01*
G01X1193861Y587840D02*
X1193846Y587839D01*
G01X1189899D02*
X1189884D01*
G01X1189914D02*
X1189899D01*
G01X1189929Y587840D02*
X1189914Y587839D01*
G01X1185957D02*
X1185942D01*
G01X1185972D02*
X1185957D01*
G01X1185987Y587840D02*
X1185972Y587839D01*
G01X1184117D02*
X1184102Y587840D01*
G01X1184132Y587839D02*
X1184117D01*
G01X1184147D02*
X1184132D01*
G01X1188050D02*
X1188035Y587840D01*
G01X1188065Y587839D02*
X1188050D01*
G01X1188080D02*
X1188065D01*
G01X1191991D02*
X1191976Y587840D01*
G01X1192006Y587839D02*
X1191991D01*
G01X1192021D02*
X1192006D01*
G01X1195924D02*
X1195909Y587840D01*
G01X1195939Y587839D02*
X1195924D01*
G01X1195954D02*
X1195939D01*
G01X1199865D02*
X1199850Y587840D01*
G01X1199880Y587839D02*
X1199865D01*
G01X1199895D02*
X1199880D01*
G01X1203798D02*
X1203783Y587840D01*
G01X1203813Y587839D02*
X1203798D01*
G01X1203828D02*
X1203813D01*
G01X1207739D02*
X1207724Y587840D01*
G01X1207754Y587839D02*
X1207739D01*
G01X1207769D02*
X1207754D01*
G01X1211672D02*
X1211657Y587840D01*
G01X1211687Y587839D02*
X1211672D01*
G01X1211702D02*
X1211687D01*
G01X1215613D02*
X1215598Y587840D01*
G01X1215628Y587839D02*
X1215613D01*
G01X1215643D02*
X1215628D01*
G01X1219546D02*
X1219531Y587840D01*
G01X1219561Y587839D02*
X1219546D01*
G01X1219576D02*
X1219561D01*
G01X1223487D02*
X1223472Y587840D01*
G01X1223502Y587839D02*
X1223487D01*
G01X1223517D02*
X1223502D01*
G01X1227420D02*
X1227405Y587840D01*
G01X1227435Y587839D02*
X1227420D01*
G01X1227450D02*
X1227435D01*
G01X1185982Y606539D02*
X1185997Y606538D01*
G01X1185967Y606539D02*
X1185982D01*
G01X1185952D02*
X1185967D01*
G01X1189914D02*
X1189929Y606538D01*
G01X1189899Y606539D02*
X1189914D01*
G01X1189884D02*
X1189899D01*
G01X1193856D02*
X1193871Y606538D01*
G01X1193841Y606539D02*
X1193856D01*
G01X1193826D02*
X1193841D01*
G01X1197788D02*
X1197803Y606538D01*
G01X1197773Y606539D02*
X1197788D01*
G01X1197758D02*
X1197773D01*
G01X1201730D02*
X1201745Y606538D01*
G01X1201715Y606539D02*
X1201730D01*
G01X1201700D02*
X1201715D01*
G01X1205662D02*
X1205677Y606538D01*
G01X1205647Y606539D02*
X1205662D01*
G01X1205632D02*
X1205647D01*
G01X1209604D02*
X1209619Y606538D01*
G01X1209589Y606539D02*
X1209604D01*
G01X1209574D02*
X1209589D01*
G01X1213536D02*
X1213551Y606538D01*
G01X1213521Y606539D02*
X1213536D01*
G01X1213506D02*
X1213521D01*
G01X1217478D02*
X1217493Y606538D01*
G01X1217463Y606539D02*
X1217478D01*
G01X1217448D02*
X1217463D01*
G01X1221410D02*
X1221425Y606538D01*
G01X1221395Y606539D02*
X1221410D01*
G01X1221380D02*
X1221395D01*
G01X1225352D02*
X1225367Y606538D01*
G01X1225337Y606539D02*
X1225352D01*
G01X1225322D02*
X1225337D01*
G01X1184117Y588824D02*
X1184102Y588825D01*
G01X1184132Y588823D02*
X1184117Y588824D01*
G01X1184147Y588823D02*
X1184132D01*
G01X1188050Y588824D02*
X1188035Y588825D01*
G01X1188065Y588823D02*
X1188050Y588824D01*
G01X1188080Y588823D02*
X1188065D01*
G01X1191991Y588824D02*
X1191976Y588825D01*
G01X1192006Y588823D02*
X1191991Y588824D01*
G01X1192021Y588823D02*
X1192006D01*
G01X1195924Y588824D02*
X1195909Y588825D01*
G01X1195939Y588823D02*
X1195924Y588824D01*
G01X1195954Y588823D02*
X1195939D01*
G01X1199865Y588824D02*
X1199850Y588825D01*
G01X1199880Y588823D02*
X1199865Y588824D01*
G01X1199895Y588823D02*
X1199880D01*
G01X1203798Y588824D02*
X1203783Y588825D01*
G01X1203813Y588823D02*
X1203798Y588824D01*
G01X1203828Y588823D02*
X1203813D01*
G01X1207739Y588824D02*
X1207724Y588825D01*
G01X1207754Y588823D02*
X1207739Y588824D01*
G01X1207769Y588823D02*
X1207754D01*
G01X1211672Y588824D02*
X1211657Y588825D01*
G01X1211687Y588823D02*
X1211672Y588824D01*
G01X1211702Y588823D02*
X1211687D01*
G01X1215613Y588824D02*
X1215598Y588825D01*
G01X1215628Y588823D02*
X1215613Y588824D01*
G01X1215643Y588823D02*
X1215628D01*
G01X1219546Y588824D02*
X1219531Y588825D01*
G01X1219561Y588823D02*
X1219546Y588824D01*
G01X1219576Y588823D02*
X1219561D01*
G01X1223487Y588824D02*
X1223472Y588825D01*
G01X1223502Y588823D02*
X1223487Y588824D01*
G01X1223517Y588823D02*
X1223502D01*
G01X1189914Y605554D02*
X1189929Y605553D01*
G01X1189899Y605555D02*
X1189914Y605554D01*
G01X1189884Y605555D02*
X1189899D01*
G01X1197788Y605554D02*
X1197803Y605553D01*
G01X1197773Y605555D02*
X1197788Y605554D01*
G01X1197758Y605555D02*
X1197773D01*
G01X1201730Y605554D02*
X1201745Y605553D01*
G01X1201715Y605555D02*
X1201730Y605554D01*
G01X1201700Y605555D02*
X1201715D01*
G01X1205662Y605554D02*
X1205677Y605553D01*
G01X1205647Y605555D02*
X1205662Y605554D01*
G01X1205632Y605555D02*
X1205647D01*
G01X1209604Y605554D02*
X1209619Y605553D01*
G01X1209589Y605555D02*
X1209604Y605554D01*
G01X1209574Y605555D02*
X1209589D01*
G01X1213536Y605554D02*
X1213551Y605553D01*
G01X1213521Y605555D02*
X1213536Y605554D01*
G01X1213506Y605555D02*
X1213521D01*
G01X1221410Y605554D02*
X1221425Y605553D01*
G01X1221395Y605555D02*
X1221410Y605554D01*
G01X1221380Y605555D02*
X1221395D01*
G01X1225352Y605554D02*
X1225367Y605553D01*
G01X1225337Y605555D02*
X1225352Y605554D01*
G01X1225322Y605555D02*
X1225337D01*
G01X1185967D02*
X1185952D01*
G01X1185982Y605554D02*
X1185967Y605555D01*
G01X1185997Y605553D02*
X1185982Y605554D01*
G01X1193841Y605555D02*
X1193826D01*
G01X1193856Y605554D02*
X1193841Y605555D01*
G01X1193871Y605553D02*
X1193856Y605554D01*
G01X1217463Y605555D02*
X1217448D01*
G01X1217478Y605554D02*
X1217463Y605555D01*
G01X1217493Y605553D02*
X1217478Y605554D01*
G01X1227444Y605555D02*
X1227459D01*
G01X1227429Y605554D02*
X1227444Y605555D01*
G01X1227414Y605553D02*
X1227429Y605554D01*
G01X1223502Y605555D02*
X1223517D01*
G01X1223487Y605554D02*
X1223502Y605555D01*
G01X1223472Y605553D02*
X1223487Y605554D01*
G01X1219570Y605555D02*
X1219585D01*
G01X1219555Y605554D02*
X1219570Y605555D01*
G01X1219540Y605553D02*
X1219555Y605554D01*
G01X1215628Y605555D02*
X1215643D01*
G01X1215613Y605554D02*
X1215628Y605555D01*
G01X1215598Y605553D02*
X1215613Y605554D01*
G01X1207754Y605555D02*
X1207769D01*
G01X1207739Y605554D02*
X1207754Y605555D01*
G01X1207724Y605553D02*
X1207739Y605554D01*
G01X1199880Y605555D02*
X1199895D01*
G01X1199865Y605554D02*
X1199880Y605555D01*
G01X1199850Y605553D02*
X1199865Y605554D01*
G01X1195948Y605555D02*
X1195963D01*
G01X1195933Y605554D02*
X1195948Y605555D01*
G01X1195918Y605553D02*
X1195933Y605554D01*
G01X1192006Y605555D02*
X1192021D01*
G01X1191991Y605554D02*
X1192006Y605555D01*
G01X1191976Y605553D02*
X1191991Y605554D01*
G01X1188074Y605555D02*
X1188089D01*
G01X1188059Y605554D02*
X1188074Y605555D01*
G01X1188044Y605553D02*
X1188059Y605554D01*
G01X1184132Y605555D02*
X1184147D01*
G01X1184117Y605554D02*
X1184132Y605555D01*
G01X1184102Y605553D02*
X1184117Y605554D01*
G01X1227444Y606539D02*
X1227459D01*
G01X1227429D02*
X1227444D01*
G01X1227414Y606538D02*
X1227429Y606539D01*
G01X1223502D02*
X1223517D01*
G01X1223487D02*
X1223502D01*
G01X1223472Y606538D02*
X1223487Y606539D01*
G01X1219570D02*
X1219585D01*
G01X1219555D02*
X1219570D01*
G01X1219540Y606538D02*
X1219555Y606539D01*
G01X1215628D02*
X1215643D01*
G01X1215613D02*
X1215628D01*
G01X1215598Y606538D02*
X1215613Y606539D01*
G01X1211696D02*
X1211711D01*
G01X1211681D02*
X1211696D01*
G01X1211666Y606538D02*
X1211681Y606539D01*
G01X1207754D02*
X1207769D01*
G01X1207739D02*
X1207754D01*
G01X1207724Y606538D02*
X1207739Y606539D01*
G01X1203822D02*
X1203837D01*
G01X1203807D02*
X1203822D01*
G01X1203792Y606538D02*
X1203807Y606539D01*
G01X1199880D02*
X1199895D01*
G01X1199865D02*
X1199880D01*
G01X1199850Y606538D02*
X1199865Y606539D01*
G01X1195948D02*
X1195963D01*
G01X1195933D02*
X1195948D01*
G01X1195918Y606538D02*
X1195933Y606539D01*
G01X1192006D02*
X1192021D01*
G01X1191991D02*
X1192006D01*
G01X1191976Y606538D02*
X1191991Y606539D01*
G01X1188074D02*
X1188089D01*
G01X1188059D02*
X1188074D01*
G01X1188044Y606538D02*
X1188059Y606539D01*
G01X1184132D02*
X1184147D01*
G01X1184117D02*
X1184132D01*
G01X1184102Y606538D02*
X1184117Y606539D01*
G01X1188197Y610476D02*
X1185835D01*
G01X1192134D02*
X1189772D01*
G01X1196071D02*
X1193709D01*
G01X1200008D02*
X1197646D01*
G01X1203945D02*
X1201583D01*
G01X1207882D02*
X1205520D01*
G01X1211819D02*
X1209457D01*
G01X1215756D02*
X1213394D01*
G01X1219693D02*
X1217331D01*
G01X1223630D02*
X1221268D01*
G01X1227567D02*
X1225205D01*
G01X1183748Y609492D02*
X1182409D01*
G01X1191622D02*
X1190283D01*
G01X1199496D02*
X1198157D01*
G01X1207370D02*
X1206031D01*
G01X1215244D02*
X1213906D01*
G01X1223118D02*
X1221780D01*
G01X1221622Y609394D02*
X1223276D01*
G01X1213748D02*
X1215402D01*
G01X1205874D02*
X1207528D01*
G01X1198000D02*
X1199654D01*
G01X1190126D02*
X1191780D01*
G01X1188197Y609295D02*
X1185835D01*
G01X1192134D02*
X1189772D01*
G01X1196071D02*
X1193709D01*
G01X1200008D02*
X1197646D01*
G01X1203945D02*
X1201583D01*
G01X1207882D02*
X1205520D01*
G01X1211819D02*
X1209457D01*
G01X1215756D02*
X1213394D01*
G01X1219693D02*
X1217331D01*
G01X1223630D02*
X1221268D01*
G01X1227567D02*
X1225205D01*
G01X1191780Y608902D02*
X1190126D01*
G01X1199654D02*
X1198000D01*
G01X1207528D02*
X1205874D01*
G01X1215402D02*
X1213748D01*
G01X1223276D02*
X1221622D01*
G01X1188433Y608035D02*
X1185598D01*
G01X1192370D02*
X1189535D01*
G01X1196307D02*
X1193472D01*
G01X1200244D02*
X1197409D01*
G01X1204181D02*
X1201346D01*
G01X1208118D02*
X1205283D01*
G01X1212055D02*
X1209220D01*
G01X1215992D02*
X1213157D01*
G01X1219929D02*
X1217094D01*
G01X1223866D02*
X1221031D01*
G01X1227803D02*
X1224968D01*
G01X1191780Y607130D02*
X1190126D01*
G01X1199654D02*
X1198000D01*
G01X1207528D02*
X1205874D01*
G01X1215402D02*
X1213748D01*
G01X1223276D02*
X1221622D01*
G01Y606638D02*
X1223276D01*
G01X1213748D02*
X1215402D01*
G01X1205874D02*
X1207528D01*
G01X1198000D02*
X1199654D01*
G01X1190126D02*
X1191780D01*
G01X1188433Y606539D02*
X1185598D01*
G01X1192370D02*
X1189535D01*
G01X1196307D02*
X1193472D01*
G01X1200244D02*
X1197409D01*
G01X1204181D02*
X1201346D01*
G01X1208118D02*
X1205283D01*
G01X1212055D02*
X1209220D01*
G01X1215992D02*
X1213157D01*
G01X1219929D02*
X1217094D01*
G01X1223866D02*
X1221031D01*
G01X1227803D02*
X1224968D01*
G01X1227213Y606382D02*
X1227803D01*
G01X1224968D02*
X1225559D01*
G01X1223276D02*
X1223866D01*
G01X1221031D02*
X1221622D01*
G01X1219339D02*
X1219929D01*
G01X1217094D02*
X1217685D01*
G01X1215402D02*
X1215992D01*
G01X1213157D02*
X1213748D01*
G01X1211465D02*
X1212055D01*
G01X1209220D02*
X1209811D01*
G01X1207528D02*
X1208118D01*
G01X1205283D02*
X1205874D01*
G01X1203591D02*
X1204181D01*
G01X1201346D02*
X1201937D01*
G01X1199654D02*
X1200244D01*
G01X1197409D02*
X1198000D01*
G01X1195717D02*
X1196307D01*
G01X1193472D02*
X1194063D01*
G01X1191780D02*
X1192370D01*
G01X1189535D02*
X1190126D01*
G01X1187843D02*
X1188433D01*
G01X1185598D02*
X1186189D01*
G01X1183906D02*
X1184496D01*
G01X1225385Y606147D02*
X1227396D01*
G01X1221443D02*
X1223454D01*
G01X1217511D02*
X1219522D01*
G01X1213569D02*
X1215580D01*
G01X1209637D02*
X1211648D01*
G01X1205695D02*
X1207706D01*
G01X1201763D02*
X1203774D01*
G01X1197821D02*
X1199832D01*
G01X1193889D02*
X1195900D01*
G01X1189947D02*
X1191958D01*
G01X1186015D02*
X1188026D01*
G01X1187770Y605757D02*
X1186271D01*
G01X1191702D02*
X1190203D01*
G01X1195644D02*
X1194145D01*
G01X1199577D02*
X1198077D01*
G01X1203518D02*
X1202019D01*
G01X1207451D02*
X1205951D01*
G01X1211392D02*
X1209893D01*
G01X1215325D02*
X1213825D01*
G01X1219266D02*
X1217767D01*
G01X1223199D02*
X1221699D01*
G01X1227140D02*
X1225641D01*
G01X1225654Y605738D02*
X1227127D01*
G01X1221712D02*
X1223185D01*
G01X1217780D02*
X1219253D01*
G01X1213838D02*
X1215311D01*
G01X1209906D02*
X1211379D01*
G01X1205964D02*
X1207437D01*
G01X1202032D02*
X1203505D01*
G01X1198090D02*
X1199563D01*
G01X1194158D02*
X1195631D01*
G01X1190216D02*
X1191689D01*
G01X1186284D02*
X1187757D01*
G01X1184496Y605713D02*
X1183906D01*
G01X1186189D02*
X1185598D01*
G01X1188433D02*
X1187843D01*
G01X1190126D02*
X1189535D01*
G01X1192370D02*
X1191780D01*
G01X1194063D02*
X1193472D01*
G01X1196307D02*
X1195717D01*
G01X1198000D02*
X1197409D01*
G01X1200244D02*
X1199654D01*
G01X1201937D02*
X1201346D01*
G01X1204181D02*
X1203591D01*
G01X1205874D02*
X1205283D01*
G01X1208118D02*
X1207528D01*
G01X1209811D02*
X1209220D01*
G01X1212055D02*
X1211465D01*
G01X1213748D02*
X1213157D01*
G01X1215992D02*
X1215402D01*
G01X1217685D02*
X1217094D01*
G01X1219929D02*
X1219339D01*
G01X1221622D02*
X1221031D01*
G01X1223866D02*
X1223276D01*
G01X1225559D02*
X1224968D01*
G01X1227803D02*
X1227213D01*
G01X1221031Y605555D02*
X1223866D01*
G01X1217094D02*
X1219929D01*
G01X1213157D02*
X1215992D01*
G01X1209220D02*
X1212055D01*
G01X1205283D02*
X1208118D01*
G01X1201346D02*
X1204181D01*
G01X1197409D02*
X1200244D01*
G01X1189535D02*
X1192370D01*
G01X1185598D02*
X1188433D01*
G01X1196307D02*
X1193472D01*
G01X1227803D02*
X1224968D01*
G01X1187843Y605457D02*
X1186189D01*
G01X1195717D02*
X1194063D01*
G01X1203591D02*
X1201937D01*
G01X1211465D02*
X1209811D01*
G01X1219339D02*
X1217685D01*
G01X1227213D02*
X1225559D01*
G01X1183561Y605368D02*
X1182596D01*
G01X1187503D02*
X1186538D01*
G01X1191435D02*
X1190470D01*
G01X1195377D02*
X1194412D01*
G01X1199309D02*
X1198344D01*
G01X1203251D02*
X1202286D01*
G01X1207183D02*
X1206218D01*
G01X1211125D02*
X1210160D01*
G01X1215057D02*
X1214092D01*
G01X1218999D02*
X1218034D01*
G01X1222931D02*
X1221966D01*
G01X1226873D02*
X1225908D01*
G01X1224968Y605358D02*
X1225283D01*
G01X1221031D02*
X1221346D01*
G01X1217094D02*
X1217409D01*
G01X1213157D02*
X1213472D01*
G01X1209220D02*
X1209535D01*
G01X1205283D02*
X1205598D01*
G01X1201346D02*
X1201661D01*
G01X1197409D02*
X1197724D01*
G01X1193472D02*
X1193787D01*
G01X1189535D02*
X1189850D01*
G01X1185598D02*
X1185913D01*
G01X1184496D02*
X1184181D01*
G01X1188433D02*
X1188118D01*
G01X1192370D02*
X1192055D01*
G01X1196307D02*
X1195992D01*
G01X1200244D02*
X1199929D01*
G01X1204181D02*
X1203866D01*
G01X1208118D02*
X1207803D01*
G01X1212055D02*
X1211740D01*
G01X1215992D02*
X1215677D01*
G01X1219929D02*
X1219614D01*
G01X1223866D02*
X1223551D01*
G01X1227803D02*
X1227488D01*
G01X1188031Y605261D02*
X1186010D01*
G01X1191963D02*
X1189942D01*
G01X1195905D02*
X1193884D01*
G01X1199837D02*
X1197816D01*
G01X1203779D02*
X1201758D01*
G01X1207711D02*
X1205690D01*
G01X1211653D02*
X1209632D01*
G01X1215585D02*
X1213564D01*
G01X1219527D02*
X1217506D01*
G01X1223459D02*
X1221438D01*
G01X1227401D02*
X1225380D01*
G01X1225559Y604965D02*
X1227213D01*
G01X1217685D02*
X1219339D01*
G01X1209811D02*
X1211465D01*
G01X1201937D02*
X1203591D01*
G01X1194063D02*
X1195717D01*
G01X1186189D02*
X1187843D01*
G01X1187770Y604772D02*
X1186271D01*
G01X1191702D02*
X1190203D01*
G01X1195644D02*
X1194145D01*
G01X1199577D02*
X1198077D01*
G01X1203518D02*
X1202019D01*
G01X1207451D02*
X1205951D01*
G01X1211392D02*
X1209893D01*
G01X1215325D02*
X1213825D01*
G01X1219266D02*
X1217767D01*
G01X1223199D02*
X1221699D01*
G01X1227140D02*
X1225641D01*
G01X1187769Y604763D02*
X1186272D01*
G01X1191701D02*
X1190205D01*
G01X1195643D02*
X1194146D01*
G01X1199575D02*
X1198079D01*
G01X1203517D02*
X1202020D01*
G01X1207449D02*
X1205953D01*
G01X1211391D02*
X1209894D01*
G01X1215323D02*
X1213827D01*
G01X1219265D02*
X1217768D01*
G01X1223197D02*
X1221701D01*
G01X1227139D02*
X1225642D01*
G01X1225862Y604441D02*
X1226919D01*
G01X1221921D02*
X1222977D01*
G01X1217988D02*
X1219045D01*
G01X1214047D02*
X1215103D01*
G01X1210114D02*
X1211171D01*
G01X1206172D02*
X1207229D01*
G01X1202240D02*
X1203297D01*
G01X1198298D02*
X1199355D01*
G01X1194366D02*
X1195423D01*
G01X1190424D02*
X1191481D01*
G01X1186492D02*
X1187549D01*
G01X1182550D02*
X1183607D01*
G01X1188197Y604394D02*
X1185835D01*
G01X1192134D02*
X1189772D01*
G01X1196071D02*
X1193709D01*
G01X1200008D02*
X1197646D01*
G01X1203945D02*
X1201583D01*
G01X1207882D02*
X1205520D01*
G01X1211819D02*
X1209457D01*
G01X1215756D02*
X1213394D01*
G01X1219693D02*
X1217331D01*
G01X1223630D02*
X1221268D01*
G01X1227567D02*
X1225205D01*
G01X1227488Y603862D02*
X1227803D01*
G01X1224968D02*
X1225283D01*
G01X1223551D02*
X1223866D01*
G01X1221031D02*
X1221346D01*
G01X1219614D02*
X1219929D01*
G01X1217094D02*
X1217409D01*
G01X1215677D02*
X1215992D01*
G01X1213157D02*
X1213472D01*
G01X1211740D02*
X1212055D01*
G01X1209220D02*
X1209535D01*
G01X1207803D02*
X1208118D01*
G01X1203866D02*
X1204181D01*
G01X1205283D02*
X1205598D01*
G01X1201346D02*
X1201661D01*
G01X1199929D02*
X1200244D01*
G01X1197409D02*
X1197724D01*
G01X1195992D02*
X1196307D01*
G01X1193472D02*
X1193787D01*
G01X1192055D02*
X1192370D01*
G01X1189535D02*
X1189850D01*
G01X1188118D02*
X1188433D01*
G01X1185598D02*
X1185913D01*
G01X1184181D02*
X1184496D01*
G01X1225619Y603826D02*
X1227162D01*
G01X1221677D02*
X1223220D01*
G01X1217745D02*
X1219288D01*
G01X1213803D02*
X1215346D01*
G01X1209871D02*
X1211414D01*
G01X1205929D02*
X1207472D01*
G01X1201997D02*
X1203540D01*
G01X1198055D02*
X1199598D01*
G01X1194123D02*
X1195666D01*
G01X1190181D02*
X1191724D01*
G01X1186249D02*
X1187792D01*
G01X1225630Y603807D02*
X1227151D01*
G01X1221688D02*
X1223210D01*
G01X1217756D02*
X1219277D01*
G01X1213814D02*
X1215336D01*
G01X1209882D02*
X1211403D01*
G01X1205940D02*
X1207461D01*
G01X1202008D02*
X1203529D01*
G01X1198066D02*
X1199587D01*
G01X1194134D02*
X1195655D01*
G01X1190192D02*
X1191713D01*
G01X1186260D02*
X1187781D01*
G01X1225559Y603193D02*
X1227213D01*
G01X1217685D02*
X1219339D01*
G01X1209811D02*
X1211465D01*
G01X1201937D02*
X1203591D01*
G01X1194063D02*
X1195717D01*
G01X1186189D02*
X1187843D01*
G01Y602701D02*
X1186189D01*
G01X1195717D02*
X1194063D01*
G01X1203591D02*
X1201937D01*
G01X1211465D02*
X1209811D01*
G01X1219339D02*
X1217685D01*
G01X1227213D02*
X1225559D01*
G01X1187685Y602602D02*
X1186346D01*
G01X1195559D02*
X1194220D01*
G01X1203433D02*
X1202094D01*
G01X1211307D02*
X1209968D01*
G01X1219181D02*
X1217843D01*
G01X1227055D02*
X1225717D01*
G01Y601618D02*
X1227055D01*
G01X1217843D02*
X1219181D01*
G01X1209968D02*
X1211307D01*
G01X1202094D02*
X1203433D01*
G01X1194220D02*
X1195559D01*
G01X1186346D02*
X1187685D01*
G01X1187818Y600999D02*
X1186223D01*
G01X1191750D02*
X1190155D01*
G01X1195692D02*
X1194097D01*
G01X1199624D02*
X1198029D01*
G01X1203566D02*
X1201971D01*
G01X1207498D02*
X1205903D01*
G01X1211440D02*
X1209845D01*
G01X1215372D02*
X1213777D01*
G01X1219314D02*
X1217719D01*
G01X1223246D02*
X1221651D01*
G01X1227188D02*
X1225593D01*
G01X1188118Y600890D02*
X1185913D01*
G01X1192055D02*
X1189850D01*
G01X1195992D02*
X1193787D01*
G01X1199929D02*
X1197724D01*
G01X1203866D02*
X1201661D01*
G01X1207803D02*
X1205598D01*
G01X1211740D02*
X1209535D01*
G01X1215677D02*
X1213472D01*
G01X1219614D02*
X1217409D01*
G01X1223551D02*
X1221346D01*
G01X1227488D02*
X1225283D01*
G01X1187890Y600239D02*
X1186151D01*
G01X1191822D02*
X1190083D01*
G01X1195764D02*
X1194025D01*
G01X1199696D02*
X1197957D01*
G01X1203638D02*
X1201899D01*
G01X1207570D02*
X1205831D01*
G01X1211512D02*
X1209773D01*
G01X1215444D02*
X1213705D01*
G01X1219386D02*
X1217647D01*
G01X1223318D02*
X1221579D01*
G01X1227260D02*
X1225521D01*
G01X1225595Y600037D02*
X1227186D01*
G01X1221654D02*
X1223244D01*
G01X1217721D02*
X1219312D01*
G01X1213780D02*
X1215370D01*
G01X1209847D02*
X1211438D01*
G01X1205906D02*
X1207496D01*
G01X1201973D02*
X1203564D01*
G01X1198032D02*
X1199622D01*
G01X1194099D02*
X1195690D01*
G01X1190158D02*
X1191748D01*
G01X1186225D02*
X1187816D01*
G01X1225542Y600013D02*
X1227239D01*
G01X1221601D02*
X1223297D01*
G01X1217668D02*
X1219365D01*
G01X1213727D02*
X1215423D01*
G01X1209794D02*
X1211491D01*
G01X1205853D02*
X1207549D01*
G01X1201920D02*
X1203617D01*
G01X1197979D02*
X1199675D01*
G01X1194046D02*
X1195742D01*
G01X1190105D02*
X1191801D01*
G01X1186172D02*
X1187868D01*
G01X1187876Y599945D02*
X1186165D01*
G01X1191808D02*
X1190098D01*
G01X1195750D02*
X1194039D01*
G01X1199682D02*
X1197972D01*
G01X1203624D02*
X1201913D01*
G01X1207556D02*
X1205846D01*
G01X1211498D02*
X1209787D01*
G01X1215430D02*
X1213720D01*
G01X1219372D02*
X1217661D01*
G01X1223304D02*
X1221594D01*
G01X1227246D02*
X1225535D01*
G01X1225516Y599353D02*
X1227265D01*
G01X1221575D02*
X1223323D01*
G01X1217642D02*
X1219391D01*
G01X1213701D02*
X1215449D01*
G01X1209768D02*
X1211517D01*
G01X1205827D02*
X1207575D01*
G01X1201894D02*
X1203643D01*
G01X1197953D02*
X1199701D01*
G01X1194020D02*
X1195769D01*
G01X1190079D02*
X1191827D01*
G01X1186146D02*
X1187895D01*
G01X1187866Y599051D02*
X1186175D01*
G01X1191798D02*
X1190107D01*
G01X1195740D02*
X1194049D01*
G01X1199673D02*
X1197981D01*
G01X1203614D02*
X1201923D01*
G01X1207547D02*
X1205855D01*
G01X1211488D02*
X1209797D01*
G01X1215421D02*
X1213729D01*
G01X1219362D02*
X1217671D01*
G01X1223295D02*
X1221603D01*
G01X1227236D02*
X1225545D01*
G01X1187876Y598961D02*
X1186165D01*
G01X1191808D02*
X1190098D01*
G01X1195750D02*
X1194039D01*
G01X1199682D02*
X1197972D01*
G01X1203624D02*
X1201913D01*
G01X1207556D02*
X1205846D01*
G01X1211498D02*
X1209787D01*
G01X1215430D02*
X1213720D01*
G01X1219372D02*
X1217661D01*
G01X1223304D02*
X1221594D01*
G01X1227246D02*
X1225535D01*
G01X1225283Y598635D02*
X1227488D01*
G01X1221346D02*
X1223551D01*
G01X1217409D02*
X1219614D01*
G01X1213472D02*
X1215677D01*
G01X1209535D02*
X1211740D01*
G01X1205598D02*
X1207803D01*
G01X1201661D02*
X1203866D01*
G01X1197724D02*
X1199929D01*
G01X1193787D02*
X1195992D01*
G01X1189850D02*
X1192055D01*
G01X1185913D02*
X1188118D01*
G01X1225283Y598468D02*
X1227488D01*
G01X1221346D02*
X1223551D01*
G01X1217409D02*
X1219614D01*
G01X1213472D02*
X1215677D01*
G01X1209535D02*
X1211740D01*
G01X1205598D02*
X1207803D01*
G01X1201661D02*
X1203866D01*
G01X1197724D02*
X1199929D01*
G01X1193787D02*
X1195992D01*
G01X1189850D02*
X1192055D01*
G01X1185913D02*
X1188118D01*
G01Y595910D02*
X1185913D01*
G01X1192055D02*
X1189850D01*
G01X1195992D02*
X1193787D01*
G01X1199929D02*
X1197724D01*
G01X1203866D02*
X1201661D01*
G01X1207803D02*
X1205598D01*
G01X1211740D02*
X1209535D01*
G01X1215677D02*
X1213472D01*
G01X1219614D02*
X1217409D01*
G01X1223551D02*
X1221346D01*
G01X1227488D02*
X1225283D01*
G01X1188118Y595743D02*
X1185913D01*
G01X1192055D02*
X1189850D01*
G01X1195992D02*
X1193787D01*
G01X1199929D02*
X1197724D01*
G01X1203866D02*
X1201661D01*
G01X1207803D02*
X1205598D01*
G01X1211740D02*
X1209535D01*
G01X1215677D02*
X1213472D01*
G01X1219614D02*
X1217409D01*
G01X1223551D02*
X1221346D01*
G01X1227488D02*
X1225283D01*
G01X1225526Y595417D02*
X1227236D01*
G01X1221594D02*
X1223304D01*
G01X1217652D02*
X1219362D01*
G01X1213720D02*
X1215430D01*
G01X1209778D02*
X1211488D01*
G01X1205846D02*
X1207556D01*
G01X1201904D02*
X1203614D01*
G01X1197972D02*
X1199682D01*
G01X1194030D02*
X1195740D01*
G01X1190098D02*
X1191808D01*
G01X1186156D02*
X1187866D01*
G01X1225535Y595327D02*
X1227227D01*
G01X1221603D02*
X1223295D01*
G01X1217661D02*
X1219353D01*
G01X1213729D02*
X1215421D01*
G01X1209787D02*
X1211479D01*
G01X1205855D02*
X1207547D01*
G01X1201913D02*
X1203605D01*
G01X1197981D02*
X1199673D01*
G01X1194039D02*
X1195731D01*
G01X1190107D02*
X1191798D01*
G01X1186165D02*
X1187857D01*
G01X1187885Y595025D02*
X1186137D01*
G01X1191827D02*
X1190079D01*
G01X1195759D02*
X1194011D01*
G01X1199701D02*
X1197953D01*
G01X1203633D02*
X1201885D01*
G01X1207575D02*
X1205827D01*
G01X1211507D02*
X1209759D01*
G01X1215449D02*
X1213701D01*
G01X1219381D02*
X1217633D01*
G01X1223323D02*
X1221575D01*
G01X1227255D02*
X1225507D01*
G01X1225526Y594433D02*
X1227236D01*
G01X1221594D02*
X1223304D01*
G01X1217652D02*
X1219362D01*
G01X1213720D02*
X1215430D01*
G01X1209778D02*
X1211488D01*
G01X1205846D02*
X1207556D01*
G01X1201904D02*
X1203614D01*
G01X1197972D02*
X1199682D01*
G01X1194030D02*
X1195740D01*
G01X1190098D02*
X1191808D01*
G01X1186156D02*
X1187866D01*
G01X1187859Y594365D02*
X1186163D01*
G01X1191801D02*
X1190105D01*
G01X1195733D02*
X1194037D01*
G01X1199675D02*
X1197979D01*
G01X1203607D02*
X1201911D01*
G01X1207549D02*
X1205853D01*
G01X1211481D02*
X1209785D01*
G01X1215423D02*
X1213727D01*
G01X1219355D02*
X1217659D01*
G01X1223297D02*
X1221601D01*
G01X1227229D02*
X1225533D01*
G01X1187806Y594341D02*
X1186216D01*
G01X1191748D02*
X1190158D01*
G01X1195680D02*
X1194090D01*
G01X1199622D02*
X1198032D01*
G01X1203554D02*
X1201964D01*
G01X1207496D02*
X1205906D01*
G01X1211428D02*
X1209838D01*
G01X1215370D02*
X1213780D01*
G01X1219302D02*
X1217712D01*
G01X1223244D02*
X1221654D01*
G01X1227176D02*
X1225586D01*
G01X1225512Y594139D02*
X1227251D01*
G01X1221579D02*
X1223318D01*
G01X1217638D02*
X1219377D01*
G01X1213705D02*
X1215444D01*
G01X1209764D02*
X1211503D01*
G01X1205831D02*
X1207570D01*
G01X1201890D02*
X1203629D01*
G01X1197957D02*
X1199696D01*
G01X1194016D02*
X1195754D01*
G01X1190083D02*
X1191822D01*
G01X1186142D02*
X1187880D01*
G01X1225283Y593488D02*
X1227488D01*
G01X1221346D02*
X1223551D01*
G01X1217409D02*
X1219614D01*
G01X1213472D02*
X1215677D01*
G01X1209535D02*
X1211740D01*
G01X1205598D02*
X1207803D01*
G01X1201661D02*
X1203866D01*
G01X1197724D02*
X1199929D01*
G01X1193787D02*
X1195992D01*
G01X1189850D02*
X1192055D01*
G01X1185913D02*
X1188118D01*
G01X1225584Y593379D02*
X1227179D01*
G01X1221651D02*
X1223246D01*
G01X1217710D02*
X1219305D01*
G01X1213777D02*
X1215372D01*
G01X1209836D02*
X1211431D01*
G01X1205903D02*
X1207498D01*
G01X1201962D02*
X1203557D01*
G01X1198029D02*
X1199624D01*
G01X1194088D02*
X1195683D01*
G01X1190155D02*
X1191750D01*
G01X1186213D02*
X1187809D01*
G01X1187685Y592760D02*
X1186346D01*
G01X1195559D02*
X1194220D01*
G01X1203433D02*
X1202094D01*
G01X1211307D02*
X1209968D01*
G01X1219181D02*
X1217843D01*
G01X1227055D02*
X1225717D01*
G01X1187685Y591776D02*
X1186346D01*
G01X1195559D02*
X1194220D01*
G01X1203433D02*
X1202094D01*
G01X1211307D02*
X1209968D01*
G01X1219181D02*
X1217843D01*
G01X1227055D02*
X1225717D01*
G01X1225559Y591677D02*
X1227213D01*
G01X1217685D02*
X1219339D01*
G01X1209811D02*
X1211465D01*
G01X1201937D02*
X1203591D01*
G01X1194063D02*
X1195717D01*
G01X1186189D02*
X1187843D01*
G01Y591185D02*
X1186189D01*
G01X1195717D02*
X1194063D01*
G01X1203591D02*
X1201937D01*
G01X1211465D02*
X1209811D01*
G01X1219339D02*
X1217685D01*
G01X1227213D02*
X1225559D01*
G01X1187772Y590571D02*
X1186250D01*
G01X1191713D02*
X1190192D01*
G01X1195646D02*
X1194124D01*
G01X1199587D02*
X1198066D01*
G01X1203520D02*
X1201998D01*
G01X1207461D02*
X1205940D01*
G01X1211394D02*
X1209872D01*
G01X1215336D02*
X1213814D01*
G01X1219268D02*
X1217746D01*
G01X1223210D02*
X1221688D01*
G01X1227142D02*
X1225620D01*
G01X1187783Y590552D02*
X1186239D01*
G01X1191724D02*
X1190181D01*
G01X1195657D02*
X1194113D01*
G01X1199598D02*
X1198055D01*
G01X1203531D02*
X1201987D01*
G01X1207472D02*
X1205929D01*
G01X1211405D02*
X1209861D01*
G01X1215346D02*
X1213803D01*
G01X1219279D02*
X1217735D01*
G01X1223220D02*
X1221677D01*
G01X1227153D02*
X1225609D01*
G01X1184496Y590516D02*
X1184181D01*
G01X1185913D02*
X1185598D01*
G01X1188433D02*
X1188118D01*
G01X1189850D02*
X1189535D01*
G01X1192370D02*
X1192055D01*
G01X1193787D02*
X1193472D01*
G01X1196307D02*
X1195992D01*
G01X1197724D02*
X1197409D01*
G01X1200244D02*
X1199929D01*
G01X1201661D02*
X1201346D01*
G01X1204181D02*
X1203866D01*
G01X1205598D02*
X1205283D01*
G01X1208118D02*
X1207803D01*
G01X1209535D02*
X1209220D01*
G01X1212055D02*
X1211740D01*
G01X1213472D02*
X1213157D01*
G01X1215992D02*
X1215677D01*
G01X1217409D02*
X1217094D01*
G01X1219929D02*
X1219614D01*
G01X1221346D02*
X1221031D01*
G01X1223866D02*
X1223551D01*
G01X1225283D02*
X1224968D01*
G01X1227803D02*
X1227488D01*
G01X1188197Y589984D02*
X1185835D01*
G01X1192134D02*
X1189772D01*
G01X1196071D02*
X1193709D01*
G01X1200008D02*
X1197646D01*
G01X1203945D02*
X1201583D01*
G01X1207882D02*
X1205520D01*
G01X1211819D02*
X1209457D01*
G01X1215756D02*
X1213394D01*
G01X1219693D02*
X1217331D01*
G01X1223630D02*
X1221268D01*
G01X1227567D02*
X1225205D01*
G01X1183607Y589937D02*
X1182550D01*
G01X1187539D02*
X1186483D01*
G01X1191481D02*
X1190424D01*
G01X1195413D02*
X1194357D01*
G01X1199355D02*
X1198298D01*
G01X1203287D02*
X1202231D01*
G01X1207229D02*
X1206172D01*
G01X1211161D02*
X1210105D01*
G01X1215103D02*
X1214047D01*
G01X1219035D02*
X1217979D01*
G01X1222977D02*
X1221921D01*
G01X1226909D02*
X1225853D01*
G01X1225633Y589615D02*
X1227129D01*
G01X1221701D02*
X1223197D01*
G01X1217759D02*
X1219255D01*
G01X1213827D02*
X1215323D01*
G01X1209885D02*
X1211381D01*
G01X1205953D02*
X1207449D01*
G01X1202011D02*
X1203507D01*
G01X1198079D02*
X1199575D01*
G01X1194137D02*
X1195633D01*
G01X1190205D02*
X1191701D01*
G01X1186263D02*
X1187759D01*
G01X1225631Y589606D02*
X1227131D01*
G01X1221699D02*
X1223199D01*
G01X1217757D02*
X1219257D01*
G01X1213825D02*
X1215325D01*
G01X1209883D02*
X1211383D01*
G01X1205951D02*
X1207451D01*
G01X1202009D02*
X1203509D01*
G01X1198077D02*
X1199577D01*
G01X1194135D02*
X1195635D01*
G01X1190203D02*
X1191702D01*
G01X1186261D02*
X1187761D01*
G01X1187843Y589413D02*
X1186189D01*
G01X1195717D02*
X1194063D01*
G01X1203591D02*
X1201937D01*
G01X1211465D02*
X1209811D01*
G01X1219339D02*
X1217685D01*
G01X1227213D02*
X1225559D01*
G01X1225371Y589117D02*
X1227392D01*
G01X1221438D02*
X1223459D01*
G01X1217497D02*
X1219518D01*
G01X1213564D02*
X1215585D01*
G01X1209623D02*
X1211644D01*
G01X1205690D02*
X1207711D01*
G01X1201749D02*
X1203770D01*
G01X1197816D02*
X1199837D01*
G01X1193875D02*
X1195896D01*
G01X1189942D02*
X1191963D01*
G01X1186001D02*
X1188021D01*
G01X1227488Y589020D02*
X1227803D01*
G01X1223551D02*
X1223866D01*
G01X1219614D02*
X1219929D01*
G01X1215677D02*
X1215992D01*
G01X1211740D02*
X1212055D01*
G01X1207803D02*
X1208118D01*
G01X1203866D02*
X1204181D01*
G01X1199929D02*
X1200244D01*
G01X1195992D02*
X1196307D01*
G01X1192055D02*
X1192370D01*
G01X1188118D02*
X1188433D01*
G01X1184181D02*
X1184496D01*
G01X1185913D02*
X1185598D01*
G01X1189850D02*
X1189535D01*
G01X1193787D02*
X1193472D01*
G01X1197724D02*
X1197409D01*
G01X1201661D02*
X1201346D01*
G01X1205598D02*
X1205283D01*
G01X1209535D02*
X1209220D01*
G01X1213472D02*
X1213157D01*
G01X1217409D02*
X1217094D01*
G01X1221346D02*
X1221031D01*
G01X1225283D02*
X1224968D01*
G01X1225898Y589010D02*
X1226864D01*
G01X1221966D02*
X1222931D01*
G01X1218024D02*
X1218990D01*
G01X1214092D02*
X1215057D01*
G01X1210150D02*
X1211116D01*
G01X1206218D02*
X1207183D01*
G01X1202276D02*
X1203242D01*
G01X1198344D02*
X1199309D01*
G01X1194402D02*
X1195368D01*
G01X1190470D02*
X1191435D01*
G01X1186528D02*
X1187494D01*
G01X1182596D02*
X1183561D01*
G01X1225559Y588921D02*
X1227213D01*
G01X1217685D02*
X1219339D01*
G01X1209811D02*
X1211465D01*
G01X1201937D02*
X1203591D01*
G01X1194063D02*
X1195717D01*
G01X1186189D02*
X1187843D01*
G01X1224968Y588823D02*
X1227803D01*
G01X1221031D02*
X1223866D01*
G01X1217094D02*
X1219929D01*
G01X1213157D02*
X1215992D01*
G01X1209220D02*
X1212055D01*
G01X1205283D02*
X1208118D01*
G01X1201346D02*
X1204181D01*
G01X1197409D02*
X1200244D01*
G01X1193472D02*
X1196307D01*
G01X1189535D02*
X1192370D01*
G01X1185598D02*
X1188433D01*
G01X1227213Y588665D02*
X1227803D01*
G01X1224968D02*
X1225559D01*
G01X1223276D02*
X1223866D01*
G01X1221031D02*
X1221622D01*
G01X1219339D02*
X1219929D01*
G01X1217094D02*
X1217685D01*
G01X1215402D02*
X1215992D01*
G01X1213157D02*
X1213748D01*
G01X1211465D02*
X1212055D01*
G01X1209220D02*
X1209811D01*
G01X1207528D02*
X1208118D01*
G01X1205283D02*
X1205874D01*
G01X1203591D02*
X1204181D01*
G01X1201346D02*
X1201937D01*
G01X1199654D02*
X1200244D01*
G01X1197409D02*
X1198000D01*
G01X1195717D02*
X1196307D01*
G01X1193472D02*
X1194063D01*
G01X1191780D02*
X1192370D01*
G01X1189535D02*
X1190126D01*
G01X1187843D02*
X1188433D01*
G01X1185598D02*
X1186189D01*
G01X1183906D02*
X1184496D01*
G01X1187748Y588640D02*
X1186275D01*
G01X1191689D02*
X1190216D01*
G01X1195622D02*
X1194149D01*
G01X1199563D02*
X1198090D01*
G01X1203496D02*
X1202023D01*
G01X1207437D02*
X1205964D01*
G01X1211370D02*
X1209897D01*
G01X1215311D02*
X1213838D01*
G01X1219244D02*
X1217771D01*
G01X1223185D02*
X1221712D01*
G01X1227118D02*
X1225645D01*
G01X1225631Y588621D02*
X1227131D01*
G01X1221699D02*
X1223199D01*
G01X1217757D02*
X1219257D01*
G01X1213825D02*
X1215325D01*
G01X1209883D02*
X1211383D01*
G01X1205951D02*
X1207451D01*
G01X1202009D02*
X1203509D01*
G01X1198077D02*
X1199577D01*
G01X1194135D02*
X1195635D01*
G01X1190203D02*
X1191702D01*
G01X1186261D02*
X1187761D01*
G01X1188017Y588231D02*
X1186005D01*
G01X1191958D02*
X1189947D01*
G01X1195891D02*
X1193879D01*
G01X1199832D02*
X1197821D01*
G01X1203765D02*
X1201753D01*
G01X1207706D02*
X1205695D01*
G01X1211639D02*
X1209627D01*
G01X1215580D02*
X1213569D01*
G01X1219513D02*
X1217502D01*
G01X1223454D02*
X1221443D01*
G01X1227387D02*
X1225376D01*
G01X1184496Y587996D02*
X1183906D01*
G01X1186189D02*
X1185598D01*
G01X1188433D02*
X1187843D01*
G01X1190126D02*
X1189535D01*
G01X1192370D02*
X1191780D01*
G01X1194063D02*
X1193472D01*
G01X1196307D02*
X1195717D01*
G01X1198000D02*
X1197409D01*
G01X1200244D02*
X1199654D01*
G01X1201937D02*
X1201346D01*
G01X1204181D02*
X1203591D01*
G01X1205874D02*
X1205283D01*
G01X1208118D02*
X1207528D01*
G01X1209811D02*
X1209220D01*
G01X1212055D02*
X1211465D01*
G01X1213748D02*
X1213157D01*
G01X1215992D02*
X1215402D01*
G01X1217685D02*
X1217094D01*
G01X1219929D02*
X1219339D01*
G01X1221622D02*
X1221031D01*
G01X1223866D02*
X1223276D01*
G01X1225559D02*
X1224968D01*
G01X1227803D02*
X1227213D01*
G01X1188433Y587839D02*
X1185598D01*
G01X1192370D02*
X1189535D01*
G01X1196307D02*
X1193472D01*
G01X1200244D02*
X1197409D01*
G01X1204181D02*
X1201346D01*
G01X1208118D02*
X1205283D01*
G01X1212055D02*
X1209220D01*
G01X1215992D02*
X1213157D01*
G01X1219929D02*
X1217094D01*
G01X1223866D02*
X1221031D01*
G01X1227803D02*
X1224968D01*
G01X1191780Y587740D02*
X1190126D01*
G01X1199654D02*
X1198000D01*
G01X1207528D02*
X1205874D01*
G01X1215402D02*
X1213748D01*
G01X1223276D02*
X1221622D01*
G01Y587248D02*
X1223276D01*
G01X1213748D02*
X1215402D01*
G01X1205874D02*
X1207528D01*
G01X1198000D02*
X1199654D01*
G01X1190126D02*
X1191780D01*
G01X1224968Y586343D02*
X1227803D01*
G01X1221031D02*
X1223866D01*
G01X1217094D02*
X1219929D01*
G01X1213157D02*
X1215992D01*
G01X1209220D02*
X1212055D01*
G01X1205283D02*
X1208118D01*
G01X1201346D02*
X1204181D01*
G01X1197409D02*
X1200244D01*
G01X1193472D02*
X1196307D01*
G01X1189535D02*
X1192370D01*
G01X1185598D02*
X1188433D01*
G01X1221622Y585476D02*
X1223276D01*
G01X1213748D02*
X1215402D01*
G01X1205874D02*
X1207528D01*
G01X1198000D02*
X1199654D01*
G01X1190126D02*
X1191780D01*
G01X1225205Y585083D02*
X1227567D01*
G01X1188197D02*
X1185835D01*
G01X1192134D02*
X1189772D01*
G01X1196071D02*
X1193709D01*
G01X1200008D02*
X1197646D01*
G01X1203945D02*
X1201583D01*
G01X1207882D02*
X1205520D01*
G01X1211819D02*
X1209457D01*
G01X1215756D02*
X1213394D01*
G01X1219693D02*
X1217331D01*
G01X1223630D02*
X1221268D01*
G01X1191780Y584984D02*
X1190126D01*
G01X1199654D02*
X1198000D01*
G01X1207528D02*
X1205874D01*
G01X1215402D02*
X1213748D01*
G01X1223276D02*
X1221622D01*
G01X1183748Y584886D02*
X1182409D01*
G01X1191622D02*
X1190283D01*
G01X1199496D02*
X1198157D01*
G01X1207370D02*
X1206031D01*
G01X1215244D02*
X1213906D01*
G01X1223118D02*
X1221780D01*
G01X1225205Y583902D02*
X1227567D01*
G01X1221268D02*
X1223630D01*
G01X1217331D02*
X1219693D01*
G01X1213394D02*
X1215756D01*
G01X1209457D02*
X1211819D01*
G01X1205520D02*
X1207882D01*
G01X1201583D02*
X1203945D01*
G01X1197646D02*
X1200008D01*
G01X1193709D02*
X1196071D01*
G01X1189772D02*
X1192134D01*
G01X1185835D02*
X1188197D01*
G01X1225908Y605368D02*
X1225654Y605738D01*
G01X1225862Y604441D02*
X1225641Y604763D01*
G01X1221712Y605738D02*
X1221966Y605368D01*
G01X1221921Y604441D02*
X1221699Y604763D01*
G01X1217780Y605738D02*
X1218034Y605368D01*
G01X1217988Y604441D02*
X1217767Y604763D01*
G01X1226909Y589937D02*
X1227131Y589615D01*
G01X1226864Y589010D02*
X1227118Y588640D01*
G01X1213838Y605738D02*
X1214092Y605368D01*
G01X1214047Y604441D02*
X1213825Y604763D01*
G01X1222977Y589937D02*
X1223198Y589615D01*
G01X1223185Y588640D02*
X1222931Y589010D01*
G01X1209906Y605738D02*
X1210160Y605368D01*
G01X1210114Y604441D02*
X1209893Y604763D01*
G01X1219035Y589937D02*
X1219257Y589615D01*
G01X1219244Y588640D02*
X1218990Y589010D01*
G01X1205964Y605738D02*
X1206218Y605368D01*
G01X1206172Y604441D02*
X1205951Y604763D01*
G01X1215103Y589937D02*
X1215324Y589615D01*
G01X1215311Y588640D02*
X1215057Y589010D01*
G01X1202032Y605738D02*
X1202286Y605368D01*
G01X1202240Y604441D02*
X1202019Y604763D01*
G01X1211161Y589937D02*
X1211383Y589615D01*
G01X1211370Y588640D02*
X1211116Y589010D01*
G01X1198090Y605738D02*
X1198344Y605368D01*
G01X1198298Y604441D02*
X1198077Y604763D01*
G01X1207229Y589937D02*
X1207450Y589615D01*
G01X1207437Y588640D02*
X1207183Y589010D01*
G01X1194158Y605738D02*
X1194412Y605368D01*
G01X1194366Y604441D02*
X1194145Y604763D01*
G01X1203287Y589937D02*
X1203509Y589615D01*
G01X1203496Y588640D02*
X1203242Y589010D01*
G01X1190216Y605738D02*
X1190470Y605368D01*
G01X1190424Y604441D02*
X1190203Y604763D01*
G01X1199355Y589937D02*
X1199576Y589615D01*
G01X1199563Y588640D02*
X1199309Y589010D01*
G01X1186284Y605738D02*
X1186538Y605368D01*
G01X1186492Y604441D02*
X1186271Y604763D01*
G01X1195413Y589937D02*
X1195635Y589615D01*
G01X1195622Y588640D02*
X1195368Y589010D01*
G01X1191481Y589937D02*
X1191702Y589615D01*
G01X1191689Y588640D02*
X1191435Y589010D01*
G01X1187539Y589937D02*
X1187761Y589615D01*
G01X1187748Y588640D02*
X1187494Y589010D01*
G01X1183607Y589937D02*
X1183828Y589615D01*
G01X1183815Y588640D02*
X1183561Y589010D01*
G01X1225862Y604441D02*
X1225872Y604394D01*
G01X1226909Y589937D02*
X1226900Y589984D01*
G01X1221921Y604441D02*
X1221930Y604394D01*
G01X1222977Y589937D02*
X1222968Y589984D01*
G01X1217988Y604441D02*
X1217998Y604394D01*
G01X1219035Y589937D02*
X1219026Y589984D01*
G01X1214047Y604441D02*
X1214056Y604394D01*
G01X1215103Y589937D02*
X1215093Y589984D01*
G01X1210114Y604441D02*
X1210124Y604394D01*
G01X1211161Y589937D02*
X1211152Y589984D01*
G01X1206172Y604441D02*
X1206182Y604394D01*
G01X1207229Y589937D02*
X1207219Y589984D01*
G01X1202240Y604441D02*
X1202250Y604394D01*
G01X1203287Y589937D02*
X1203278Y589984D01*
G01X1198298Y604441D02*
X1198308Y604394D01*
G01X1199355Y589937D02*
X1199345Y589984D01*
G01X1194366Y604441D02*
X1194376Y604394D01*
G01X1195413Y589937D02*
X1195404Y589984D01*
G01X1190424Y604441D02*
X1190434Y604394D01*
G01X1191481Y589937D02*
X1191471Y589984D01*
G01X1186492Y604441D02*
X1186502Y604394D01*
G01X1187539Y589937D02*
X1187530Y589984D01*
G01X1182550Y604441D02*
X1182560Y604394D01*
G01X1183607Y589937D02*
X1183597Y589984D01*
G01X1227179Y593379D02*
X1227229Y594365D01*
G01X1227227Y595327D02*
X1227176Y594341D01*
G01X1225545Y599051D02*
X1225595Y600037D01*
G01X1225593Y600999D02*
X1225542Y600013D01*
G01X1223246Y593379D02*
X1223297Y594365D01*
G01X1223295Y595327D02*
X1223244Y594341D01*
G01X1221603Y599051D02*
X1221654Y600037D01*
G01X1221651Y600999D02*
X1221601Y600013D01*
G01X1219305Y593379D02*
X1219355Y594365D01*
G01X1219353Y595327D02*
X1219302Y594341D01*
G01X1227265Y599353D02*
X1227401Y605261D01*
G01X1227396Y606147D02*
X1227260Y600239D01*
G01X1225376Y588231D02*
X1225512Y594139D01*
G01X1225507Y595025D02*
X1225371Y589117D01*
G01X1223323Y599353D02*
X1223459Y605261D01*
G01X1223454Y606147D02*
X1223318Y600239D01*
G01X1221443Y588231D02*
X1221579Y594139D01*
G01X1221575Y595025D02*
X1221438Y589117D01*
G01X1219391Y599353D02*
X1219527Y605261D01*
G01X1219522Y606147D02*
X1219386Y600239D01*
G01X1217502Y588231D02*
X1217638Y594139D01*
G01X1217633Y595025D02*
X1217497Y589117D01*
G01X1215449Y599353D02*
X1215585Y605261D01*
G01X1215580Y606147D02*
X1215444Y600239D01*
G01X1226877Y589984D02*
X1226864Y589010D01*
G01X1225895Y604394D02*
X1225908Y605368D01*
G01X1222945Y589984D02*
X1222931Y589010D01*
G01X1221953Y604394D02*
X1221966Y605368D01*
G01X1219003Y589984D02*
X1218990Y589010D01*
G01X1218021Y604394D02*
X1218034Y605368D01*
G01X1215071Y589984D02*
X1215057Y589010D01*
G01X1214079Y604394D02*
X1214092Y605368D01*
G01X1227567Y589984D02*
Y583902D01*
G01Y610476D02*
Y604394D01*
G01X1227488Y587839D02*
Y606539D01*
G01X1227414Y606538D02*
Y605553D01*
G01X1227405Y588825D02*
Y587840D01*
G01X1227213Y601698D02*
Y606539D01*
G01Y587839D02*
Y592680D01*
G01X1227139Y604760D02*
Y605751D01*
G01X1227129Y588627D02*
Y589618D01*
G01X1227055Y592760D02*
Y591696D01*
G01Y602681D02*
Y601618D01*
G01X1226780D02*
Y602602D01*
G01Y592760D02*
Y591776D01*
G01X1225992Y601618D02*
Y602602D01*
G01Y592760D02*
Y591776D01*
G01X1225717Y592760D02*
Y591696D01*
G01Y602682D02*
Y601618D01*
G01X1225642Y605751D02*
Y604760D01*
G01X1225633Y589618D02*
Y588627D01*
G01X1225559Y601698D02*
Y606539D01*
G01Y587839D02*
Y592680D01*
G01X1225367Y605553D02*
Y606538D01*
G01X1225358Y587840D02*
Y588825D01*
G01X1225283Y606539D02*
Y587839D01*
G01X1225205Y589984D02*
Y583902D01*
G01Y610476D02*
Y604394D01*
G01X1225013Y606539D02*
Y605555D01*
G01X1225008Y606539D02*
Y605555D01*
G01X1225003Y588823D02*
Y587839D01*
G01X1224968Y590516D02*
Y586343D01*
G01Y608035D02*
Y603862D01*
G01X1223866D02*
Y608035D01*
G01Y586343D02*
Y590516D01*
G01X1223831Y588823D02*
Y587839D01*
G01X1223827Y588823D02*
Y587839D01*
G01Y606539D02*
Y605555D01*
G01X1223630Y589984D02*
Y583902D01*
G01Y610476D02*
Y604394D01*
G01X1223551Y587839D02*
Y606539D01*
G01X1223472Y588825D02*
Y587840D01*
G01Y606538D02*
Y605553D01*
G01X1223276Y605555D02*
Y610396D01*
G01Y583982D02*
Y588823D01*
G01X1223197Y604760D02*
Y605751D01*
G01Y588627D02*
Y589618D01*
G01X1223118Y584965D02*
Y583902D01*
G01Y610476D02*
Y609413D01*
G01X1222843Y584886D02*
Y583902D01*
G01Y610476D02*
Y609492D01*
G01X1222055D02*
Y610476D01*
G01Y584886D02*
Y583902D01*
G01X1221780Y584965D02*
Y583902D01*
G01Y610476D02*
Y609413D01*
G01X1221701Y589618D02*
Y588627D01*
G01Y605751D02*
Y604760D01*
G01X1221622Y605555D02*
Y610396D01*
G01Y583982D02*
Y588823D01*
G01X1221425Y605553D02*
Y606538D01*
G01Y587840D02*
Y588825D01*
G01X1221346Y606539D02*
Y587839D01*
G01X1221268Y589984D02*
Y583902D01*
G01Y610476D02*
Y604394D01*
G01X1221071Y588823D02*
Y587839D01*
G01Y606539D02*
Y605555D01*
G01X1221066Y606539D02*
Y605555D01*
G01X1221031Y590516D02*
Y586343D01*
G01Y608035D02*
Y603862D01*
G01X1219929D02*
Y608035D01*
G01Y586343D02*
Y590516D01*
G01X1219894Y606539D02*
Y605555D01*
G01X1219890Y588823D02*
Y587839D01*
G01X1219885Y588823D02*
Y587839D01*
G01X1219693Y589984D02*
Y583902D01*
G01Y610476D02*
Y604394D01*
G01X1219614Y587839D02*
Y606539D01*
G01X1219540Y606538D02*
Y605553D01*
G01X1219531Y588825D02*
Y587840D01*
G01X1219339Y601698D02*
Y606539D01*
G01Y587839D02*
Y592680D01*
G01X1219265Y604760D02*
Y605751D01*
G01X1219255Y588627D02*
Y589618D01*
G01X1219181Y592760D02*
Y591696D01*
G01Y602681D02*
Y601618D01*
G01X1218906Y592760D02*
Y591776D01*
G01Y602602D02*
Y601618D01*
G01X1218118Y592760D02*
Y591776D01*
G01Y602602D02*
Y601618D01*
G01X1217843Y592760D02*
Y591696D01*
G01Y602682D02*
Y601618D01*
G01X1217768Y605751D02*
Y604760D01*
G01X1217759Y589618D02*
Y588627D01*
G01X1217685Y601698D02*
Y606539D01*
G01Y587839D02*
Y592680D01*
G01X1217493Y605553D02*
Y606538D01*
G01X1217484Y587840D02*
Y588825D01*
G01X1217409Y606539D02*
Y587839D01*
G01X1217331Y589984D02*
Y583902D01*
G01Y610476D02*
Y604394D01*
G01X1217139Y606539D02*
Y605555D01*
G01X1217134Y606539D02*
Y605555D01*
G01X1217129Y588823D02*
Y587839D01*
G01X1217094Y590516D02*
Y586343D01*
G01Y608035D02*
Y603862D01*
G01X1215992D02*
Y608035D01*
G01Y586343D02*
Y590516D01*
G01X1215957Y588823D02*
Y587839D01*
G01X1215953Y588823D02*
Y587839D01*
G01Y606539D02*
Y605555D01*
G01X1215756Y589984D02*
Y583902D01*
G01Y610476D02*
Y604394D01*
G01X1215677Y587839D02*
Y606539D01*
G01X1215598Y588825D02*
Y587840D01*
G01Y606538D02*
Y605553D01*
G01X1215402Y605555D02*
Y610396D01*
G01Y583982D02*
Y588823D01*
G01X1215323Y604760D02*
Y605751D01*
G01Y588627D02*
Y589618D01*
G01X1215244Y584965D02*
Y583902D01*
G01Y610476D02*
Y609413D01*
G01X1214968Y584886D02*
Y583902D01*
G01Y610476D02*
Y609492D01*
G01X1214181D02*
Y610476D01*
G01Y584886D02*
Y583902D01*
G01X1213906Y584965D02*
Y583902D01*
G01Y610476D02*
Y609413D01*
G01X1213827Y589618D02*
Y588627D01*
G01Y605751D02*
Y604760D01*
G01X1213748Y605555D02*
Y610396D01*
G01Y583982D02*
Y588823D01*
G01X1213551Y605553D02*
Y606538D01*
G01Y587840D02*
Y588825D01*
G01X1213472Y606539D02*
Y587839D01*
G01X1213394Y589984D02*
Y583902D01*
G01Y610476D02*
Y604394D01*
G01X1213197Y588823D02*
Y587839D01*
G01Y606539D02*
Y605555D01*
G01X1213192Y606539D02*
Y605555D01*
G01X1213157Y590516D02*
Y586343D01*
G01Y608035D02*
Y603862D01*
G01X1212055D02*
Y608035D01*
G01Y586343D02*
Y590516D01*
G01X1212020Y606539D02*
Y605555D01*
G01X1212016Y588823D02*
Y587839D01*
G01X1212011Y588823D02*
Y587839D01*
G01X1211819Y589984D02*
Y583902D01*
G01Y610476D02*
Y604394D01*
G01X1211740Y587839D02*
Y606539D01*
G01X1211666Y606538D02*
Y605553D01*
G01X1211657Y588825D02*
Y587840D01*
G01X1211465Y601698D02*
Y606539D01*
G01Y587839D02*
Y592680D01*
G01X1211390Y604760D02*
Y605751D01*
G01X1211381Y588627D02*
Y589618D01*
G01X1211307Y592760D02*
Y591696D01*
G01Y602681D02*
Y601618D01*
G01X1211031D02*
Y602602D01*
G01Y592760D02*
Y591776D01*
G01X1226873Y605368D02*
X1226886Y604394D01*
G01X1225898Y589010D02*
X1225885Y589984D01*
G01X1222931Y605368D02*
X1222945Y604394D01*
G01X1221966Y589010D02*
X1221953Y589984D01*
G01X1218999Y605368D02*
X1219012Y604394D01*
G01X1218024Y589010D02*
X1218011Y589984D01*
G01X1215057Y605368D02*
X1215071Y604394D01*
G01X1214092Y589010D02*
X1214079Y589984D01*
G01X1211125Y605368D02*
X1211138Y604394D01*
G01X1210150Y589010D02*
X1210137Y589984D01*
G01X1227392Y589117D02*
X1227255Y595025D01*
G01X1227251Y594139D02*
X1227387Y588231D01*
G01X1225521Y600239D02*
X1225385Y606147D01*
G01X1225380Y605261D02*
X1225516Y599353D01*
G01X1223459Y589117D02*
X1223323Y595025D01*
G01X1223318Y594139D02*
X1223454Y588231D01*
G01X1221579Y600239D02*
X1221443Y606147D01*
G01X1221438Y605261D02*
X1221575Y599353D01*
G01X1219518Y589117D02*
X1219381Y595025D01*
G01X1219377Y594139D02*
X1219513Y588231D01*
G01X1217647Y600239D02*
X1217511Y606147D01*
G01X1217506Y605261D02*
X1217642Y599353D01*
G01X1215585Y589117D02*
X1215449Y595025D01*
G01X1215444Y594139D02*
X1215580Y588231D01*
G01X1213705Y600239D02*
X1213569Y606147D01*
G01X1213564Y605261D02*
X1213701Y599353D01*
G01X1211644Y589117D02*
X1211507Y595025D01*
G01X1211503Y594139D02*
X1211639Y588231D01*
G01X1209773Y600239D02*
X1209637Y606147D01*
G01X1209632Y605261D02*
X1209768Y599353D01*
G01X1207711Y589117D02*
X1207575Y595025D01*
G01X1227239Y600013D02*
X1227188Y600999D01*
G01X1227186Y600037D02*
X1227236Y599051D01*
G01X1225586Y594341D02*
X1225535Y595327D01*
G01X1225533Y594365D02*
X1225584Y593379D01*
G01X1223297Y600013D02*
X1223246Y600999D01*
G01X1223244Y600037D02*
X1223295Y599051D01*
G01X1221654Y594341D02*
X1221603Y595327D01*
G01X1221601Y594365D02*
X1221651Y593379D01*
G01X1219365Y600013D02*
X1219314Y600999D01*
G01X1219312Y600037D02*
X1219362Y599051D01*
G01X1217712Y594341D02*
X1217661Y595327D01*
G01X1217659Y594365D02*
X1217710Y593379D01*
G01X1215423Y600013D02*
X1215372Y600999D01*
G01X1215370Y600037D02*
X1215421Y599051D01*
G01X1213780Y594341D02*
X1213729Y595327D01*
G01X1213727Y594365D02*
X1213777Y593379D01*
G01X1211491Y600013D02*
X1211440Y600999D01*
G01X1211438Y600037D02*
X1211488Y599051D01*
G01X1209838Y594341D02*
X1209787Y595327D01*
G01X1209785Y594365D02*
X1209836Y593379D01*
G01X1207549Y600013D02*
X1207498Y600999D01*
G01X1207496Y600037D02*
X1207547Y599051D01*
G01X1205906Y594341D02*
X1205855Y595327D01*
G01X1205853Y594365D02*
X1205903Y593379D01*
G01X1203617Y600013D02*
X1203566Y600999D01*
G01X1203564Y600037D02*
X1203614Y599051D01*
G01X1225862Y589984D02*
X1225853Y589937D01*
G01X1226909Y604394D02*
X1226919Y604441D01*
G01X1221930Y589984D02*
X1221921Y589937D01*
G01X1222968Y604394D02*
X1222977Y604441D01*
G01X1217988Y589984D02*
X1217979Y589937D01*
G01X1219035Y604394D02*
X1219045Y604441D01*
G01X1214056Y589984D02*
X1214047Y589937D01*
G01X1215093Y604394D02*
X1215103Y604441D01*
G01X1217671Y599051D02*
X1217721Y600037D01*
G01X1217719Y600999D02*
X1217668Y600013D01*
G01X1215372Y593379D02*
X1215423Y594365D01*
G01X1215421Y595327D02*
X1215370Y594341D01*
G01X1213729Y599051D02*
X1213780Y600037D01*
G01X1213777Y600999D02*
X1213727Y600013D01*
G01X1211431Y593379D02*
X1211481Y594365D01*
G01X1211479Y595327D02*
X1211428Y594341D01*
G01X1209797Y599051D02*
X1209847Y600037D01*
G01X1209845Y600999D02*
X1209794Y600013D01*
G01X1207498Y593379D02*
X1207549Y594365D01*
G01X1207547Y595327D02*
X1207496Y594341D01*
G01X1205855Y599051D02*
X1205906Y600037D01*
G01X1205903Y600999D02*
X1205853Y600013D01*
G01X1203557Y593379D02*
X1203607Y594365D01*
G01X1203605Y595327D02*
X1203554Y594341D01*
G01X1201923Y599051D02*
X1201973Y600037D01*
G01X1201971Y600999D02*
X1201920Y600013D01*
G01X1199624Y593379D02*
X1199675Y594365D01*
G01X1199673Y595327D02*
X1199622Y594341D01*
G01X1197981Y599051D02*
X1198032Y600037D01*
G01X1198029Y600999D02*
X1197979Y600013D01*
G01X1195683Y593379D02*
X1195733Y594365D01*
G01X1195731Y595327D02*
X1195680Y594341D01*
G01X1194049Y599051D02*
X1194099Y600037D01*
G01X1194097Y600999D02*
X1194046Y600013D01*
G01X1213569Y588231D02*
X1213705Y594139D01*
G01X1213701Y595025D02*
X1213564Y589117D01*
G01X1211517Y599353D02*
X1211653Y605261D01*
G01X1211648Y606147D02*
X1211512Y600239D01*
G01X1209627Y588231D02*
X1209764Y594139D01*
G01X1209759Y595025D02*
X1209623Y589117D01*
G01X1207575Y599353D02*
X1207711Y605261D01*
G01X1207706Y606147D02*
X1207570Y600239D01*
G01X1205695Y588231D02*
X1205831Y594139D01*
G01X1205827Y595025D02*
X1205690Y589117D01*
G01X1203643Y599353D02*
X1203779Y605261D01*
G01X1203774Y606147D02*
X1203638Y600239D01*
G01X1201753Y588231D02*
X1201890Y594139D01*
G01X1201885Y595025D02*
X1201749Y589117D01*
G01X1199701Y599353D02*
X1199837Y605261D01*
G01X1199832Y606147D02*
X1199696Y600239D01*
G01X1197821Y588231D02*
X1197957Y594139D01*
G01X1197953Y595025D02*
X1197816Y589117D01*
G01X1195769Y599353D02*
X1195905Y605261D01*
G01X1195900Y606147D02*
X1195764Y600239D01*
G01X1193879Y588231D02*
X1194016Y594139D01*
G01X1194011Y595025D02*
X1193875Y589117D01*
G01X1191827Y599353D02*
X1191963Y605261D01*
G01X1191958Y606147D02*
X1191822Y600239D01*
G01X1189947Y588231D02*
X1190083Y594139D01*
G01X1190079Y595025D02*
X1189942Y589117D01*
G01X1211129Y589984D02*
X1211116Y589010D01*
G01X1210147Y604394D02*
X1210160Y605368D01*
G01X1207197Y589984D02*
X1207183Y589010D01*
G01X1206205Y604394D02*
X1206218Y605368D01*
G01X1203255Y589984D02*
X1203242Y589010D01*
G01X1202273Y604394D02*
X1202286Y605368D01*
G01X1199323Y589984D02*
X1199309Y589010D01*
G01X1198331Y604394D02*
X1198344Y605368D01*
G01X1195381Y589984D02*
X1195368Y589010D01*
G01X1194399Y604394D02*
X1194412Y605368D01*
G01X1191449Y589984D02*
X1191435Y589010D01*
G01X1190457Y604394D02*
X1190470Y605368D01*
G01X1210244Y601618D02*
Y602602D01*
G01Y591776D02*
Y592760D01*
G01X1209968D02*
Y591696D01*
G01Y602682D02*
Y601618D01*
G01X1209894Y605751D02*
Y604760D01*
G01X1209885Y589618D02*
Y588627D01*
G01X1209811Y601698D02*
Y606539D01*
G01Y587839D02*
Y592680D01*
G01X1209619Y605553D02*
Y606538D01*
G01X1209610Y587840D02*
Y588825D01*
G01X1209535Y606539D02*
Y587839D01*
G01X1209457Y589984D02*
Y583902D01*
G01Y610476D02*
Y604394D01*
G01X1209265Y606539D02*
Y605555D01*
G01X1209260Y606539D02*
Y605555D01*
G01X1209255Y588823D02*
Y587839D01*
G01X1209220Y590516D02*
Y586343D01*
G01Y608035D02*
Y603862D01*
G01X1208118D02*
Y608035D01*
G01Y586343D02*
Y590516D01*
G01X1208083Y588823D02*
Y587839D01*
G01X1208079Y588823D02*
Y587839D01*
G01Y606539D02*
Y605555D01*
G01X1207882Y589984D02*
Y583902D01*
G01Y610476D02*
Y604394D01*
G01X1207803Y587839D02*
Y606539D01*
G01X1207724Y588825D02*
Y587840D01*
G01Y606538D02*
Y605553D01*
G01X1207528Y605555D02*
Y610396D01*
G01Y583982D02*
Y588823D01*
G01X1207449Y604760D02*
Y605751D01*
G01Y588627D02*
Y589618D01*
G01X1207370Y584965D02*
Y583902D01*
G01Y610476D02*
Y609413D01*
G01X1207094Y584886D02*
Y583902D01*
G01Y610476D02*
Y609492D01*
G01X1206307D02*
Y610476D01*
G01Y584886D02*
Y583902D01*
G01X1206031Y584965D02*
Y583902D01*
G01Y610476D02*
Y609413D01*
G01X1205953Y589618D02*
Y588627D01*
G01Y605751D02*
Y604760D01*
G01X1205874Y605555D02*
Y610396D01*
G01Y583982D02*
Y588823D01*
G01X1205677Y605553D02*
Y606538D01*
G01Y587840D02*
Y588825D01*
G01X1205598Y606539D02*
Y587839D01*
G01X1205520Y589984D02*
Y583902D01*
G01Y610476D02*
Y604394D01*
G01X1205323Y588823D02*
Y587839D01*
G01Y606539D02*
Y605555D01*
G01X1205318Y606539D02*
Y605555D01*
G01X1205283Y590516D02*
Y586343D01*
G01Y608035D02*
Y603862D01*
G01X1204181D02*
Y608035D01*
G01Y586343D02*
Y590516D01*
G01X1204146Y606539D02*
Y605555D01*
G01X1204142Y588823D02*
Y587839D01*
G01X1204137Y588823D02*
Y587839D01*
G01X1203945Y589984D02*
Y583902D01*
G01Y610476D02*
Y604394D01*
G01X1203866Y587839D02*
Y606539D01*
G01X1203792Y606538D02*
Y605553D01*
G01X1203783Y588825D02*
Y587840D01*
G01X1203591Y601698D02*
Y606539D01*
G01Y587839D02*
Y592680D01*
G01X1203516Y604760D02*
Y605751D01*
G01X1203507Y588627D02*
Y589618D01*
G01X1203433Y592760D02*
Y591696D01*
G01Y602681D02*
Y601618D01*
G01X1203157D02*
Y602602D01*
G01Y592760D02*
Y591776D01*
G01X1202370Y601618D02*
Y602602D01*
G01Y591776D02*
Y592760D01*
G01X1202094D02*
Y591696D01*
G01Y602682D02*
Y601618D01*
G01X1202020Y605751D02*
Y604760D01*
G01X1202011Y589618D02*
Y588627D01*
G01X1201937Y601698D02*
Y606539D01*
G01Y587839D02*
Y592680D01*
G01X1201745Y605553D02*
Y606538D01*
G01X1201735Y587840D02*
Y588825D01*
G01X1201661Y606539D02*
Y587839D01*
G01X1201583Y589984D02*
Y583902D01*
G01Y610476D02*
Y604394D01*
G01X1201390Y606539D02*
Y605555D01*
G01X1201386Y606539D02*
Y605555D01*
G01X1201381Y588823D02*
Y587839D01*
G01X1201346Y590516D02*
Y586343D01*
G01Y608035D02*
Y603862D01*
G01X1200244D02*
Y608035D01*
G01Y586343D02*
Y590516D01*
G01X1200209Y588823D02*
Y587839D01*
G01X1200205Y588823D02*
Y587839D01*
G01Y606539D02*
Y605555D01*
G01X1200008Y589984D02*
Y583902D01*
G01Y610476D02*
Y604394D01*
G01X1199929Y587839D02*
Y606539D01*
G01X1199850Y588825D02*
Y587840D01*
G01Y606538D02*
Y605553D01*
G01X1199654Y605555D02*
Y610396D01*
G01Y583982D02*
Y588823D01*
G01X1199575Y604760D02*
Y605751D01*
G01Y588627D02*
Y589618D01*
G01X1199496Y584965D02*
Y583902D01*
G01Y610476D02*
Y609413D01*
G01X1199220Y584886D02*
Y583902D01*
G01Y610476D02*
Y609492D01*
G01X1198433D02*
Y610476D01*
G01Y584886D02*
Y583902D01*
G01X1198157Y584965D02*
Y583902D01*
G01Y610476D02*
Y609413D01*
G01X1198079Y589618D02*
Y588627D01*
G01Y605751D02*
Y604760D01*
G01X1198000Y605555D02*
Y610396D01*
G01Y583982D02*
Y588823D01*
G01X1197803Y605553D02*
Y606538D01*
G01Y587840D02*
Y588825D01*
G01X1197724Y606539D02*
Y587839D01*
G01X1197646Y589984D02*
Y583902D01*
G01Y610476D02*
Y604394D01*
G01X1197449Y588823D02*
Y587839D01*
G01Y606539D02*
Y605555D01*
G01X1197444Y606539D02*
Y605555D01*
G01X1197409Y590516D02*
Y586343D01*
G01Y608035D02*
Y603862D01*
G01X1196307D02*
Y608035D01*
G01Y586343D02*
Y590516D01*
G01X1196272Y606539D02*
Y605555D01*
G01X1196268Y588823D02*
Y587839D01*
G01X1196263Y588823D02*
Y587839D01*
G01X1196071Y589984D02*
Y583902D01*
G01Y610476D02*
Y604394D01*
G01X1195992Y587839D02*
Y606539D01*
G01X1195918Y606538D02*
Y605553D01*
G01X1195909Y588825D02*
Y587840D01*
G01X1195717Y601698D02*
Y606539D01*
G01Y587839D02*
Y592680D01*
G01X1195642Y604760D02*
Y605751D01*
G01X1195633Y588627D02*
Y589618D01*
G01X1195559Y592760D02*
Y591696D01*
G01Y602681D02*
Y601618D01*
G01X1195283Y592760D02*
Y591776D01*
G01Y602602D02*
Y601618D01*
G01X1194496Y592760D02*
Y591776D01*
G01Y602602D02*
Y601618D01*
G01X1194220Y592760D02*
Y591696D01*
G01Y602682D02*
Y601618D01*
G01X1194146Y605751D02*
Y604760D01*
G01X1194137Y589618D02*
Y588627D01*
G01X1194063Y601698D02*
Y606539D01*
G01Y587839D02*
Y592680D01*
G01X1193871Y605553D02*
Y606538D01*
G01X1193861Y587840D02*
Y588825D01*
G01X1193787Y606539D02*
Y587839D01*
G01X1193709Y589984D02*
Y583902D01*
G01Y610476D02*
Y604394D01*
G01X1193516Y606539D02*
Y605555D01*
G01X1193512Y606539D02*
Y605555D01*
G01X1193507Y588823D02*
Y587839D01*
G01X1193472Y590516D02*
Y586343D01*
G01Y608035D02*
Y603862D01*
G01X1192370D02*
Y608035D01*
G01Y586343D02*
Y590516D01*
G01X1192335Y588823D02*
Y587839D01*
G01X1192331Y588823D02*
Y587839D01*
G01Y606539D02*
Y605555D01*
G01X1192134Y589984D02*
Y583902D01*
G01Y610476D02*
Y604394D01*
G01X1192055Y587839D02*
Y606539D01*
G01X1191976Y588825D02*
Y587840D01*
G01Y606538D02*
Y605553D01*
G01X1191780Y605555D02*
Y610396D01*
G01Y583982D02*
Y588823D01*
G01X1191701Y604760D02*
Y605751D01*
G01Y588627D02*
Y589618D01*
G01X1191622Y584965D02*
Y583902D01*
G01Y610476D02*
Y609413D01*
G01X1191346Y584886D02*
Y583902D01*
G01Y610476D02*
Y609492D01*
G01X1190559D02*
Y610476D01*
G01Y584886D02*
Y583902D01*
G01X1190283Y584965D02*
Y583902D01*
G01Y610476D02*
Y609413D01*
G01X1190205Y589618D02*
Y588627D01*
G01Y605751D02*
Y604760D01*
G01X1190126Y605555D02*
Y610396D01*
G01Y583982D02*
Y588823D01*
G01X1189929Y605553D02*
Y606538D01*
G01Y587840D02*
Y588825D01*
G01X1189850Y606539D02*
Y587839D01*
G01X1189772Y589984D02*
Y583902D01*
G01Y610476D02*
Y604394D01*
G01X1189575Y588823D02*
Y587839D01*
G01Y606539D02*
Y605555D01*
G01X1189570Y606539D02*
Y605555D01*
G01X1189535Y590516D02*
Y586343D01*
G01Y608035D02*
Y603862D01*
G01X1188433D02*
Y608035D01*
G01Y586343D02*
Y590516D01*
G01X1188398Y606539D02*
Y605555D01*
G01X1188394Y588823D02*
Y587839D01*
G01X1188389Y588823D02*
Y587839D01*
G01X1188197Y589984D02*
Y583902D01*
G01Y610476D02*
Y604394D01*
G01X1188118Y587839D02*
Y606539D01*
G01X1188044Y606538D02*
Y605553D01*
G01X1188035Y588825D02*
Y587840D01*
G01X1187843Y601698D02*
Y606539D01*
G01Y587839D02*
Y592680D01*
G01X1187768Y604760D02*
Y605751D01*
G01X1187759Y588627D02*
Y589618D01*
G01X1187685Y592760D02*
Y591696D01*
G01Y602681D02*
Y601618D01*
G01X1187409Y592760D02*
Y591776D01*
G01Y602602D02*
Y601618D01*
G01X1186622Y592760D02*
Y591776D01*
G01Y602602D02*
Y601618D01*
G01X1186346Y592760D02*
Y591696D01*
G01Y602682D02*
Y601618D01*
G01X1186272Y605751D02*
Y604760D01*
G01X1186263Y589618D02*
Y588627D01*
G01X1207183Y605368D02*
X1207197Y604394D01*
G01X1206218Y589010D02*
X1206205Y589984D01*
G01X1203251Y605368D02*
X1203264Y604394D01*
G01X1202276Y589010D02*
X1202263Y589984D01*
G01X1199309Y605368D02*
X1199323Y604394D01*
G01X1198344Y589010D02*
X1198331Y589984D01*
G01X1195377Y605368D02*
X1195390Y604394D01*
G01X1194402Y589010D02*
X1194389Y589984D01*
G01X1191435Y605368D02*
X1191449Y604394D01*
G01X1190470Y589010D02*
X1190457Y589984D01*
G01X1187503Y605368D02*
X1187516Y604394D01*
G01X1186528Y589010D02*
X1186515Y589984D01*
G01X1207570Y594139D02*
X1207706Y588231D01*
G01X1205831Y600239D02*
X1205695Y606147D01*
G01X1205690Y605261D02*
X1205827Y599353D01*
G01X1203770Y589117D02*
X1203633Y595025D01*
G01X1203629Y594139D02*
X1203765Y588231D01*
G01X1201899Y600239D02*
X1201763Y606147D01*
G01X1201758Y605261D02*
X1201894Y599353D01*
G01X1199837Y589117D02*
X1199701Y595025D01*
G01X1199696Y594139D02*
X1199832Y588231D01*
G01X1197957Y600239D02*
X1197821Y606147D01*
G01X1197816Y605261D02*
X1197953Y599353D01*
G01X1195896Y589117D02*
X1195759Y595025D01*
G01X1195754Y594139D02*
X1195891Y588231D01*
G01X1194025Y600239D02*
X1193889Y606147D01*
G01X1193884Y605261D02*
X1194020Y599353D01*
G01X1191963Y589117D02*
X1191827Y595025D01*
G01X1191822Y594139D02*
X1191958Y588231D01*
G01X1190083Y600239D02*
X1189947Y606147D01*
G01X1189942Y605261D02*
X1190079Y599353D01*
G01X1188021Y589117D02*
X1187885Y595025D01*
G01X1187880Y594139D02*
X1188017Y588231D01*
G01X1186151Y600239D02*
X1186015Y606147D01*
G01X1186010Y605261D02*
X1186146Y599353D01*
G01X1184089Y589117D02*
X1183953Y595025D01*
G01X1183948Y594139D02*
X1184084Y588231D01*
G01X1201964Y594341D02*
X1201913Y595327D01*
G01X1201911Y594365D02*
X1201962Y593379D01*
G01X1199675Y600013D02*
X1199624Y600999D01*
G01X1199622Y600037D02*
X1199673Y599051D01*
G01X1198032Y594341D02*
X1197981Y595327D01*
G01X1197979Y594365D02*
X1198029Y593379D01*
G01X1195742Y600013D02*
X1195692Y600999D01*
G01X1195690Y600037D02*
X1195740Y599051D01*
G01X1194090Y594341D02*
X1194039Y595327D01*
G01X1194037Y594365D02*
X1194088Y593379D01*
G01X1191801Y600013D02*
X1191750Y600999D01*
G01X1191748Y600037D02*
X1191798Y599051D01*
G01X1190158Y594341D02*
X1190107Y595327D01*
G01X1190105Y594365D02*
X1190155Y593379D01*
G01X1187868Y600013D02*
X1187818Y600999D01*
G01X1187816Y600037D02*
X1187866Y599051D01*
G01X1186216Y594341D02*
X1186165Y595327D01*
G01X1186163Y594365D02*
X1186213Y593379D01*
G01X1183927Y600013D02*
X1183876Y600999D01*
G01X1183874Y600037D02*
X1183924Y599051D01*
G01X1225645Y588640D02*
X1225898Y589010D01*
G01X1225632Y589615D02*
X1225853Y589937D01*
G01X1221712Y588640D02*
X1221966Y589010D01*
G01X1221699Y589615D02*
X1221921Y589937D01*
G01X1210114Y589984D02*
X1210105Y589937D01*
G01X1211161Y604394D02*
X1211171Y604441D01*
G01X1206182Y589984D02*
X1206172Y589937D01*
G01X1207219Y604394D02*
X1207229Y604441D01*
G01X1202240Y589984D02*
X1202231Y589937D01*
G01X1203287Y604394D02*
X1203297Y604441D01*
G01X1198308Y589984D02*
X1198298Y589937D01*
G01X1199345Y604394D02*
X1199355Y604441D01*
G01X1194366Y589984D02*
X1194357Y589937D01*
G01X1195413Y604394D02*
X1195423Y604441D01*
G01X1190434Y589984D02*
X1190424Y589937D01*
G01X1191471Y604394D02*
X1191481Y604441D01*
G01X1186492Y589984D02*
X1186483Y589937D01*
G01X1191750Y593379D02*
X1191801Y594365D01*
G01X1191798Y595327D02*
X1191748Y594341D01*
G01X1190107Y599051D02*
X1190158Y600037D01*
G01X1190155Y600999D02*
X1190105Y600013D01*
G01X1187809Y593379D02*
X1187859Y594365D01*
G01X1187857Y595327D02*
X1187806Y594341D01*
G01X1186175Y599051D02*
X1186225Y600037D01*
G01X1186223Y600999D02*
X1186172Y600013D01*
G01X1183876Y593379D02*
X1183927Y594365D01*
G01X1183924Y595327D02*
X1183874Y594341D01*
G01X1187895Y599353D02*
X1188031Y605261D01*
G01X1188026Y606147D02*
X1187890Y600239D01*
G01X1186005Y588231D02*
X1186142Y594139D01*
G01X1186137Y595025D02*
X1186001Y589117D01*
G01X1183953Y599353D02*
X1184089Y605261D01*
G01X1184084Y606147D02*
X1183948Y600239D01*
G01X1187507Y589984D02*
X1187494Y589010D01*
G01X1186525Y604394D02*
X1186538Y605368D01*
G01X1183575Y589984D02*
X1183561Y589010D01*
G01X1182583Y604394D02*
X1182596Y605368D01*
G01X1186189Y601698D02*
Y606539D01*
G01Y587839D02*
Y592680D01*
G01X1185997Y605553D02*
Y606538D01*
G01X1185987Y587840D02*
Y588825D01*
G01X1185913Y606539D02*
Y587839D01*
G01X1185835Y589984D02*
Y583902D01*
G01Y610476D02*
Y604394D01*
G01X1185642Y606539D02*
Y605555D01*
G01X1185638Y606539D02*
Y605555D01*
G01X1185633Y588823D02*
Y587839D01*
G01X1185598Y590516D02*
Y586343D01*
G01Y608035D02*
Y603862D01*
G01X1184496D02*
Y608035D01*
G01Y586343D02*
Y590516D01*
G01X1184461Y588823D02*
Y587839D01*
G01X1184457Y588823D02*
Y587839D01*
G01Y606539D02*
Y605555D01*
G01X1184260Y589984D02*
Y583902D01*
G01Y610476D02*
Y604394D01*
G01X1184181Y587839D02*
Y606539D01*
G01X1184102Y588825D02*
Y587840D01*
G01Y606538D02*
Y605553D01*
G01X1183906Y605555D02*
Y610396D01*
G01Y583982D02*
Y588823D01*
G01X1183827Y604760D02*
Y605751D01*
G01Y588627D02*
Y589618D01*
G01X1183748Y584965D02*
Y583902D01*
G01Y610476D02*
Y609413D01*
G01X1183472Y584886D02*
Y583902D01*
G01Y610476D02*
Y609492D01*
G01X1182685D02*
Y610476D01*
G01Y584886D02*
Y583902D01*
G01X1182409Y584965D02*
Y583902D01*
G01Y610476D02*
Y609413D01*
G01X1183561Y605368D02*
X1183575Y604394D01*
G01X1182596Y589010D02*
X1182583Y589984D01*
G01X1217771Y588640D02*
X1218024Y589010D01*
G01X1217758Y589615D02*
X1217979Y589937D01*
G01X1227140Y604763D02*
X1226919Y604441D01*
G01X1227127Y605738D02*
X1226873Y605368D01*
G01X1213838Y588640D02*
X1214092Y589010D01*
G01X1213825Y589615D02*
X1214047Y589937D01*
G01X1223198Y604763D02*
X1222977Y604441D01*
G01X1223185Y605738D02*
X1222931Y605368D01*
G01X1209897Y588640D02*
X1210150Y589010D01*
G01X1209883Y589615D02*
X1210105Y589937D01*
G01X1219266Y604763D02*
X1219045Y604441D01*
G01X1219253Y605738D02*
X1218999Y605368D01*
G01X1205964Y588640D02*
X1206218Y589010D01*
G01X1205951Y589615D02*
X1206172Y589937D01*
G01X1215324Y604763D02*
X1215103Y604441D01*
G01X1215311Y605738D02*
X1215057Y605368D01*
G01X1202023Y588640D02*
X1202276Y589010D01*
G01X1202009Y589615D02*
X1202231Y589937D01*
G01X1211392Y604763D02*
X1211171Y604441D01*
G01X1211379Y605738D02*
X1211125Y605368D01*
G01X1198090Y588640D02*
X1198344Y589010D01*
G01X1198077Y589615D02*
X1198298Y589937D01*
G01X1207450Y604763D02*
X1207229Y604441D01*
G01X1207437Y605738D02*
X1207183Y605368D01*
G01X1194149Y588640D02*
X1194402Y589010D01*
G01X1194135Y589615D02*
X1194357Y589937D01*
G01X1203518Y604763D02*
X1203297Y604441D01*
G01X1203505Y605738D02*
X1203251Y605368D01*
G01X1187539Y604394D02*
X1187549Y604441D01*
G01X1182560Y589984D02*
X1182550Y589937D01*
G01X1183597Y604394D02*
X1183607Y604441D01*
G01X1190216Y588640D02*
X1190470Y589010D01*
G01X1190203Y589615D02*
X1190424Y589937D01*
G01X1199576Y604763D02*
X1199355Y604441D01*
G01X1199563Y605738D02*
X1199309Y605368D01*
G01X1186275Y588640D02*
X1186528Y589010D01*
G01X1186261Y589615D02*
X1186483Y589937D01*
G01X1195644Y604763D02*
X1195423Y604441D01*
G01X1195631Y605738D02*
X1195377Y605368D01*
G01X1191702Y604763D02*
X1191481Y604441D01*
G01X1191689Y605738D02*
X1191435Y605368D01*
G01X1187770Y604763D02*
X1187549Y604441D01*
G01X1187757Y605738D02*
X1187503Y605368D01*
G01X1183828Y604763D02*
X1183607Y604441D01*
G01X1183815Y605738D02*
X1183561Y605368D01*
G01X1154215Y782204D02*
Y764881D01*
G01X1246848Y-588760D02*
X1247397Y-589285D01*
X1248023Y-589495D01*
X1248650Y-589285D01*
X1249198Y-588655D01*
X1249590Y-587710D01*
X1249747Y-586765D01*
Y-585610D01*
X1249590Y-584665D01*
X1249198Y-583825D01*
X1248728Y-583405D01*
X1248180Y-583195D01*
X1247553Y-583405D01*
X1247083Y-583825D01*
X1246770Y-584455D01*
X1246613Y-585295D01*
X1246770Y-586030D01*
X1247162Y-586765D01*
X1247632Y-587185D01*
X1248180Y-587290D01*
X1248807Y-587080D01*
X1249277Y-586555D01*
X1249747Y-585610D01*
G01X1286499Y-411970D02*
Y-502100D01*
G01X1303673Y-423583D02*
Y-444642D01*
G01X1297619Y-423583D02*
X1309727D01*
G01X1320257Y-444642D02*
Y-423583D01*
G01Y-433761D02*
X1321573Y-432007D01*
X1322890Y-430954D01*
X1324995Y-430603D01*
X1326574Y-430954D01*
X1328417Y-432358D01*
X1329207Y-434464D01*
Y-444642D01*
G01X1345791Y-430603D02*
Y-444642D01*
G01Y-424987D02*
X1345264Y-424636D01*
Y-423934D01*
X1345791Y-423583D01*
X1346318Y-423934D01*
Y-424636D01*
X1345791Y-424987D01*
G01X1371062Y-432358D02*
X1369219Y-430954D01*
X1367640Y-430603D01*
X1365534Y-431305D01*
X1363954Y-432709D01*
X1362902Y-435166D01*
X1362638Y-437623D01*
X1362902Y-440080D01*
X1363954Y-442186D01*
X1365534Y-443940D01*
X1367640Y-444642D01*
X1369482Y-443940D01*
X1371062Y-442537D01*
G01X1383434Y-444642D02*
Y-423583D01*
G01X1391857Y-430603D02*
X1383434Y-438675D01*
G01X1386856Y-435516D02*
X1392384Y-444642D01*
G01X1404493D02*
Y-430603D01*
G01Y-434113D02*
X1405546Y-432358D01*
X1407126Y-430954D01*
X1409231Y-430603D01*
X1411074Y-430954D01*
X1412653Y-432358D01*
X1413443Y-434815D01*
Y-444642D01*
G01X1426079Y-435166D02*
X1434502D01*
X1433712Y-432709D01*
X1432396Y-431305D01*
X1430554Y-430603D01*
X1428711Y-430954D01*
X1427131Y-432007D01*
X1426079Y-434464D01*
X1425552Y-436570D01*
Y-438675D01*
X1426079Y-440781D01*
X1427395Y-442887D01*
X1428974Y-444291D01*
X1430817Y-444642D01*
X1432659Y-443940D01*
X1434502Y-441835D01*
G01X1447138Y-442186D02*
X1448454Y-443589D01*
X1450296Y-444642D01*
X1451876D01*
X1453455Y-443940D01*
X1454508Y-442887D01*
X1455034Y-441484D01*
X1454771Y-439377D01*
X1453718Y-438324D01*
X1448980Y-436219D01*
X1447927Y-433761D01*
X1448454Y-432007D01*
X1449507Y-430954D01*
X1451086Y-430603D01*
X1452665Y-430954D01*
X1454245Y-432007D01*
G01X1468197Y-442186D02*
X1469513Y-443589D01*
X1471355Y-444642D01*
X1472935D01*
X1474514Y-443940D01*
X1475567Y-442887D01*
X1476093Y-441484D01*
X1475830Y-439377D01*
X1474777Y-438324D01*
X1470039Y-436219D01*
X1468986Y-433761D01*
X1469513Y-432007D01*
X1470566Y-430954D01*
X1472145Y-430603D01*
X1473724Y-430954D01*
X1475304Y-432007D01*
G01X1290167Y-457289D02*
X1703822D01*
G01X1278810Y-229732D02*
X1282707D01*
G01X1278810Y-238393D02*
Y-229732D01*
G01X1282707Y-238393D02*
X1278810D01*
G01X1275399Y-234062D02*
X1274912Y-236228D01*
G01Y-231897D02*
X1275399Y-234062D01*
G01X1274425Y-231175D02*
X1274912Y-231897D01*
G01X1273938Y-230453D02*
X1274425Y-231175D01*
G01X1272963Y-229732D02*
X1273938Y-230453D01*
G01X1271014Y-229732D02*
X1272963D01*
G01X1256885Y-238393D02*
X1255911Y-237671D01*
G01X1257860Y-238393D02*
X1256885D01*
G01X1258834Y-237671D02*
X1257860Y-238393D01*
G01X1259809Y-236228D02*
X1258834Y-237671D01*
G01X1271014Y-238393D02*
Y-229732D01*
G01X1272963Y-238393D02*
X1271014D01*
G01X1273938Y-237671D02*
X1272963Y-238393D01*
G01X1274912Y-236228D02*
X1273938Y-237671D01*
G01X1249090Y-238393D02*
X1248116Y-237671D01*
G01X1250065Y-238393D02*
X1249090D01*
G01X1251039Y-237671D02*
X1250065Y-238393D01*
G01X1251526Y-236949D02*
X1251039Y-237671D01*
G01X1251526Y-235506D02*
Y-236949D01*
G01X1251039Y-234784D02*
X1251526Y-235506D01*
G01X1250065Y-234062D02*
X1251039Y-234784D01*
G01X1249090Y-233341D02*
X1250065Y-234062D01*
G01X1248116Y-232619D02*
X1249090Y-233341D01*
G01X1247629Y-231897D02*
X1248116Y-232619D01*
G01X1247629Y-231175D02*
Y-231897D01*
G01X1248116Y-230453D02*
X1247629Y-231175D01*
G01X1249090Y-229732D02*
X1248116Y-230453D01*
G01X1250065Y-229732D02*
X1249090D01*
G01X1251039Y-230453D02*
X1250065Y-229732D01*
G01X1251526Y-231175D02*
X1251039Y-230453D01*
G01X1303657Y-238393D02*
X1302683Y-237671D01*
G01X1304632Y-238393D02*
X1303657D01*
G01X1305606Y-237671D02*
X1304632Y-238393D01*
G01X1306093Y-236949D02*
X1305606Y-237671D01*
G01X1306093Y-235506D02*
Y-236949D01*
G01X1305606Y-234784D02*
X1306093Y-235506D01*
G01X1304632Y-234062D02*
X1305606Y-234784D01*
G01X1303657Y-233341D02*
X1304632Y-234062D01*
G01X1302683Y-232619D02*
X1303657Y-233341D01*
G01X1302196Y-231897D02*
X1302683Y-232619D01*
G01X1302196Y-231175D02*
Y-231897D01*
G01X1302683Y-230453D02*
X1302196Y-231175D01*
G01X1303657Y-229732D02*
X1302683Y-230453D01*
G01X1304632Y-229732D02*
X1303657D01*
G01X1305606Y-230453D02*
X1304632Y-229732D01*
G01X1306093Y-231175D02*
X1305606Y-230453D01*
G01X1260296Y-234062D02*
X1259809Y-236228D01*
G01Y-231897D02*
X1260296Y-234062D01*
G01X1259322Y-231175D02*
X1259809Y-231897D01*
G01X1258834Y-230453D02*
X1259322Y-231175D01*
G01X1257860Y-229732D02*
X1258834Y-230453D01*
G01X1256885Y-229732D02*
X1257860D01*
G01X1255911Y-230453D02*
X1256885Y-229732D01*
G01X1255424Y-231175D02*
X1255911Y-230453D01*
G01X1254937Y-231897D02*
X1255424Y-231175D01*
G01X1254449Y-234062D02*
X1254937Y-231897D01*
G01Y-236228D02*
X1254449Y-234062D01*
G01X1255911Y-237671D02*
X1254937Y-236228D01*
G01X1263219Y-238393D02*
X1267117D01*
G01X1263219Y-229732D02*
Y-238393D01*
G01X1289041Y-234062D02*
X1286605D01*
G01X1290015Y-233341D02*
X1289041Y-234062D01*
G01X1290503Y-232619D02*
X1290015Y-233341D01*
G01X1290503Y-231175D02*
Y-232619D01*
G01X1290015Y-230453D02*
X1290503Y-231175D01*
G01X1289041Y-229732D02*
X1290015Y-230453D01*
G01X1286605Y-229732D02*
X1289041D01*
G01X1286605Y-238393D02*
Y-229732D01*
G01X1289041Y-234062D02*
X1290503Y-238393D01*
G01X1302683Y-237671D02*
X1301708Y-236228D01*
G01X1248116Y-237671D02*
X1247141Y-236228D01*
G01X1278810Y-234062D02*
X1281246D01*
G01X1237277Y-164057D02*
Y-153033D01*
G01X1235111D02*
Y-164057D01*
G01X1234127D02*
Y-153033D01*
G01X1231962D02*
Y-164057D01*
G01X1230977D02*
Y-153033D01*
G01X1228812D02*
Y-164057D01*
G01X1227828D02*
Y-153033D01*
G01X1235111Y-164057D02*
X1237277D01*
G01X1231962D02*
X1234127D01*
G01X1228812D02*
X1230977D01*
G01Y-153033D02*
X1228812D01*
G01X1234127D02*
X1231962D01*
G01X1237277D02*
X1235111D01*
G01X1307552D02*
Y-164057D01*
G01X1306568D02*
Y-153033D01*
G01X1304403D02*
Y-164057D01*
G01X1303418D02*
Y-153033D01*
G01X1301253D02*
Y-164057D01*
G01X1300269D02*
Y-153033D01*
G01X1298103D02*
Y-164057D01*
G01X1297119D02*
Y-153033D01*
G01X1294954D02*
Y-164057D01*
G01X1293969D02*
Y-153033D01*
G01X1291804D02*
Y-164057D01*
G01X1290820D02*
Y-153033D01*
G01X1288654D02*
Y-164057D01*
G01X1287670D02*
Y-153033D01*
G01X1285505D02*
Y-164057D01*
G01X1284521D02*
Y-153033D01*
G01X1282355D02*
Y-164057D01*
G01X1281371D02*
Y-153033D01*
G01X1279206D02*
Y-164057D01*
G01X1278221D02*
Y-153033D01*
G01X1276056D02*
Y-164057D01*
G01X1275072D02*
Y-153033D01*
G01X1272906D02*
Y-164057D01*
G01X1271922D02*
Y-153033D01*
G01X1269757D02*
Y-164057D01*
G01X1268773D02*
Y-153033D01*
G01X1266607D02*
Y-164057D01*
G01X1265623D02*
Y-153033D01*
G01X1263458D02*
Y-164057D01*
G01X1262473D02*
Y-153033D01*
G01X1260308D02*
Y-164057D01*
G01X1259324D02*
Y-153033D01*
G01X1257158D02*
Y-164057D01*
G01X1256174D02*
Y-153033D01*
G01X1254009D02*
Y-164057D01*
G01X1253025D02*
Y-153033D01*
G01X1250859D02*
Y-164057D01*
G01X1249875D02*
Y-153033D01*
G01X1247710D02*
Y-164057D01*
G01X1246725D02*
Y-153033D01*
G01X1244560D02*
Y-164057D01*
G01X1243576D02*
Y-153033D01*
G01X1241410D02*
Y-164057D01*
G01X1240426D02*
Y-153033D01*
G01X1238261D02*
Y-164057D01*
G01X1307552D02*
X1309717D01*
G01X1304403D02*
X1306568D01*
G01X1301253D02*
X1303418D01*
G01X1298103D02*
X1300269D01*
G01X1294954D02*
X1297119D01*
G01X1291804D02*
X1293969D01*
G01X1288654D02*
X1290820D01*
G01X1285505D02*
X1287670D01*
G01X1282355D02*
X1284521D01*
G01X1279206D02*
X1281371D01*
G01X1276056D02*
X1278221D01*
G01X1272906D02*
X1275072D01*
G01X1269757D02*
X1271922D01*
G01X1266607D02*
X1268773D01*
G01X1263458D02*
X1265623D01*
G01X1260308D02*
X1262473D01*
G01X1257158D02*
X1259324D01*
G01X1254009D02*
X1256174D01*
G01X1250859D02*
X1253025D01*
G01X1247710D02*
X1249875D01*
G01X1244560D02*
X1246725D01*
G01X1241410D02*
X1243576D01*
G01X1238261D02*
X1240426D01*
G01Y-153033D02*
X1238261D01*
G01X1243576D02*
X1241410D01*
G01X1246725D02*
X1244560D01*
G01X1249875D02*
X1247710D01*
G01X1253025D02*
X1250859D01*
G01X1256174D02*
X1254009D01*
G01X1259324D02*
X1257158D01*
G01X1262473D02*
X1260308D01*
G01X1265623D02*
X1263458D01*
G01X1268773D02*
X1266607D01*
G01X1271922D02*
X1269757D01*
G01X1275072D02*
X1272906D01*
G01X1278221D02*
X1276056D01*
G01X1281371D02*
X1279206D01*
G01X1284521D02*
X1282355D01*
G01X1287670D02*
X1285505D01*
G01X1290820D02*
X1288654D01*
G01X1293969D02*
X1291804D01*
G01X1297119D02*
X1294954D01*
G01X1300269D02*
X1298103D01*
G01X1303418D02*
X1301253D01*
G01X1306568D02*
X1304403D01*
G01X1309717D02*
X1307552D01*
G01X1234934Y-39746D02*
Y-136301D01*
G01D02*
X1310131D01*
G01X1268025Y-82909D02*
X1267532Y-83076D01*
G01X1265400Y-82909D02*
X1264908Y-83076D01*
G01X1260643Y-82909D02*
X1260151Y-83076D01*
G01X1258018Y-82909D02*
X1257526Y-83076D01*
G01X1281148Y-84249D02*
X1278851Y-85422D01*
G01X1268025Y-83746D02*
X1268353Y-83579D01*
G01X1273110Y-80563D02*
X1272454Y-80898D01*
G01X1265400Y-83746D02*
X1265728Y-83579D01*
G01X1260643Y-83746D02*
X1260971Y-83579D01*
G01X1258018Y-83746D02*
X1258346Y-83579D01*
G01X1279179Y-85924D02*
X1282296Y-84249D01*
G01X1272946Y-81736D02*
X1273438Y-81401D01*
G01X1272454Y-80898D02*
X1271798Y-81568D01*
G01X1267861Y-83914D02*
X1268025Y-83746D01*
G01X1267532Y-83076D02*
X1267040Y-83579D01*
G01X1265236Y-83914D02*
X1265400Y-83746D01*
G01X1264908Y-83076D02*
X1264580Y-83411D01*
G01X1260479Y-83914D02*
X1260643Y-83746D01*
G01X1260151Y-83076D02*
X1259658Y-83579D01*
G01X1257854Y-83914D02*
X1258018Y-83746D01*
G01X1257526Y-83076D02*
X1257198Y-83411D01*
G01X1279179Y-82574D02*
X1278851Y-83076D01*
G01X1272618Y-82239D02*
X1272946Y-81736D01*
G01X1267696Y-84249D02*
X1267861Y-83914D01*
G01X1265072Y-84249D02*
X1265236Y-83914D01*
G01X1260315Y-84249D02*
X1260479Y-83914D01*
G01X1257690Y-84249D02*
X1257854Y-83914D01*
G01X1264580Y-83411D02*
X1264252Y-84249D01*
G01X1271798Y-81568D02*
X1271633Y-82239D01*
G01X1290170Y-88270D02*
Y-80396D01*
G01X1289186Y-84584D02*
Y-88270D01*
G01Y-80396D02*
Y-83579D01*
G01X1257198Y-83411D02*
X1256870Y-84249D01*
G01X1284593Y-83579D02*
Y-80396D01*
G01Y-88270D02*
Y-84584D01*
G01X1283609Y-80396D02*
Y-88270D01*
G01X1277539D02*
Y-87432D01*
G01X1272618Y-82574D02*
Y-82239D01*
G01X1271633Y-87432D02*
Y-88270D01*
G01Y-82239D02*
Y-82574D01*
G01X1270321Y-88270D02*
Y-82909D01*
G01X1269501Y-84081D02*
Y-88270D01*
G01Y-82909D02*
Y-83411D01*
G01X1267696Y-88270D02*
Y-84249D01*
G01X1266876D02*
Y-88270D01*
G01X1265072D02*
Y-84249D01*
G01X1264252D02*
Y-88270D01*
G01X1262939D02*
Y-82909D01*
G01X1277375Y-82239D02*
X1277211Y-81568D01*
G01X1271633Y-82574D02*
X1271798Y-83244D01*
G01X1272946D02*
X1272618Y-82574D01*
G01X1262119Y-84081D02*
Y-88270D01*
G01Y-82909D02*
Y-83411D01*
G01X1260315Y-88270D02*
Y-84249D01*
G01X1259494D02*
Y-88270D01*
G01X1257690D02*
Y-84249D01*
G01X1256870D02*
Y-88270D01*
G01X1266712Y-83914D02*
X1266876Y-84249D01*
G01X1259330Y-83914D02*
X1259494Y-84249D01*
G01X1278851Y-85422D02*
X1279179Y-85924D01*
G01X1276227Y-81736D02*
X1276555Y-82239D01*
G01X1271798Y-83244D02*
X1272126Y-83746D01*
G01X1277211Y-81568D02*
X1276555Y-80898D01*
G01X1269501Y-83411D02*
X1269173Y-83076D01*
G01Y-83746D02*
X1269501Y-84081D01*
G01X1267040Y-83579D02*
X1266548Y-83076D01*
G01Y-83746D02*
X1266712Y-83914D01*
G01X1262119Y-83411D02*
X1261791Y-83076D01*
G01X1277539Y-87432D02*
X1272946Y-83244D01*
G01X1272126Y-83746D02*
X1276227Y-87432D01*
G01X1275735Y-81401D02*
X1276227Y-81736D01*
G01X1282296Y-84249D02*
X1279179Y-82574D01*
G01X1276555Y-80898D02*
X1275899Y-80563D01*
G01X1261791Y-83746D02*
X1262119Y-84081D01*
G01X1259658Y-83579D02*
X1259166Y-83076D01*
G01Y-83746D02*
X1259330Y-83914D01*
G01X1278851Y-83076D02*
X1281148Y-84249D01*
G01X1266220Y-83579D02*
X1266548Y-83746D01*
G01X1258838Y-83579D02*
X1259166Y-83746D01*
G01X1269173Y-83076D02*
X1268681Y-82909D01*
G01Y-83579D02*
X1269173Y-83746D01*
G01X1266548Y-83076D02*
X1266056Y-82909D01*
G01X1261791Y-83076D02*
X1261299Y-82909D01*
G01Y-83579D02*
X1261791Y-83746D01*
G01X1259166Y-83076D02*
X1258674Y-82909D01*
G01X1274914Y-81233D02*
X1275735Y-81401D01*
G01X1275899Y-80563D02*
X1274750Y-80396D01*
G01D02*
X1274094D01*
G01X1284593D02*
X1283609D01*
G01X1290170D02*
X1289186D01*
G01X1274258Y-81233D02*
X1274914D01*
G01X1276555Y-82239D02*
X1277375D01*
G01X1258674Y-82909D02*
X1258018D01*
G01X1261299D02*
X1260643D01*
G01X1262939D02*
X1262119D01*
G01X1266056D02*
X1265400D01*
G01X1268681D02*
X1268025D01*
G01X1270321D02*
X1269501D01*
G01X1268353Y-83579D02*
X1268681D01*
G01X1265728D02*
X1266220D01*
G01X1260971D02*
X1261299D01*
G01X1258346D02*
X1258838D01*
G01X1289186D02*
X1284593D01*
G01Y-84584D02*
X1289186D01*
G01X1276227Y-87432D02*
X1271633D01*
G01X1289186Y-88270D02*
X1290170D01*
G01X1283609D02*
X1284593D01*
G01X1271633D02*
X1277539D01*
G01X1269501D02*
X1270321D01*
G01X1266876D02*
X1267696D01*
G01X1264252D02*
X1265072D01*
G01X1262119D02*
X1262939D01*
G01X1259494D02*
X1260315D01*
G01X1256870D02*
X1257690D01*
G01X1274094Y-80396D02*
X1273110Y-80563D01*
G01X1273438Y-81401D02*
X1274258Y-81233D01*
G01X1233322Y-18841D02*
X1234524D01*
G01X1227711Y-22819D02*
X1233322D01*
G01Y-24076D02*
X1227711D01*
G01X1234524Y-28683D02*
X1233322D01*
G01X1240335Y-22191D02*
X1237530Y-23657D01*
G01X1236127D02*
X1239935Y-21563D01*
G01Y-25751D02*
X1236127Y-23657D01*
G01X1237530D02*
X1240335Y-25123D01*
G01X1234524Y-18841D02*
Y-28683D01*
G01X1233322Y-22819D02*
Y-18841D01*
G01Y-28683D02*
Y-24076D01*
G01X1227711D02*
Y-28683D01*
G01Y-18841D02*
Y-22819D01*
G01X1275804Y-22191D02*
X1276405Y-21982D01*
G01X1273198Y-22819D02*
X1272597Y-23029D01*
G01Y-22191D02*
X1273198Y-21982D01*
G01X1266786Y-22191D02*
X1267387Y-21982D01*
G01X1264181Y-22819D02*
X1263580Y-23029D01*
G01Y-22191D02*
X1264181Y-21982D01*
G01X1276204Y-22819D02*
X1275804Y-23029D01*
G01X1267187Y-22819D02*
X1266786Y-23029D01*
G01X1275804D02*
X1275603Y-23238D01*
G01X1278208Y-22610D02*
X1278609Y-23657D01*
G01X1269191Y-22610D02*
X1269592Y-23657D01*
G01X1277607D02*
X1277407Y-23238D01*
G01X1274401Y-23657D02*
X1274200Y-23238D01*
G01X1268590Y-23657D02*
X1268389Y-23238D01*
G01X1277407D02*
X1277206Y-23029D01*
G01X1268389Y-23238D02*
X1268189Y-23029D01*
G01X1277807Y-22191D02*
X1278208Y-22610D01*
G01X1274601Y-22191D02*
X1275202Y-22819D01*
G01X1274200Y-23238D02*
X1274000Y-23029D01*
G01X1268790Y-22191D02*
X1269191Y-22610D01*
G01X1277206Y-23029D02*
X1276805Y-22819D01*
G01X1274000Y-23029D02*
X1273599Y-22819D01*
G01X1268189Y-23029D02*
X1267788Y-22819D01*
G01X1258771Y-19050D02*
X1259572Y-19469D01*
G01X1264983Y-23029D02*
X1264582Y-22819D01*
G01X1277206Y-21982D02*
X1277807Y-22191D01*
G01X1274000Y-21982D02*
X1274601Y-22191D01*
G01X1268189Y-21982D02*
X1268790Y-22191D01*
G01X1264983Y-21982D02*
X1265584Y-22191D01*
G01X1258370Y-20097D02*
X1257368Y-19888D01*
G01X1246547Y-20097D02*
X1245545Y-19888D01*
G01X1257568Y-18841D02*
X1258771Y-19050D01*
G01X1246748D02*
X1245545Y-18841D01*
G01X1256767D02*
X1257568D01*
G01X1257368Y-19888D02*
X1256567D01*
G01X1254563Y-21144D02*
X1253561D01*
G01X1276405Y-21982D02*
X1277206D01*
G01X1273198D02*
X1274000D01*
G01X1271195D02*
X1272197D01*
G01X1267387D02*
X1268189D01*
G01X1264181D02*
X1264983D01*
G01X1262177D02*
X1263179D01*
G01X1264582Y-22819D02*
X1264181D01*
G01X1267788D02*
X1267187D01*
G01X1273599D02*
X1273198D01*
G01X1276805D02*
X1276204D01*
G01X1254963Y-27636D02*
X1260574D01*
G01X1250755D02*
X1251757D01*
G01Y-28683D02*
X1250755D01*
G01X1260574D02*
X1253360D01*
G01X1263179D02*
X1262177D01*
G01X1266385D02*
X1265383D01*
G01X1269592D02*
X1268590D01*
G01X1272197D02*
X1271195D01*
G01X1275403D02*
X1274401D01*
G01X1278609D02*
X1277607D01*
G01X1255364Y-19050D02*
X1256767Y-18841D01*
G01X1245545D02*
X1244343Y-19050D01*
G01X1245545Y-28683D02*
X1246748Y-28474D01*
G01X1245545Y-19888D02*
X1244543Y-20097D01*
G01X1256567Y-19888D02*
X1255565Y-20097D01*
G01X1245545Y-27636D02*
X1246547Y-27427D01*
G01X1254563Y-19469D02*
X1255364Y-19050D01*
G01X1246748Y-28474D02*
X1247750Y-27845D01*
G01X1244343Y-19050D02*
X1243341Y-19678D01*
G01X1246547Y-27427D02*
X1247148Y-27008D01*
G01X1255565Y-20097D02*
X1254963Y-20516D01*
G01X1244543Y-20097D02*
X1243942Y-20516D01*
G01X1259973Y-23029D02*
X1254963Y-27636D01*
G01X1253360D02*
X1258971Y-22401D01*
G01X1275202Y-22819D02*
X1275804Y-22191D01*
G01X1272597Y-23029D02*
X1272197Y-23448D01*
G01Y-22610D02*
X1272597Y-22191D01*
G01X1266786Y-23029D02*
X1266586Y-23238D01*
G01X1266185Y-22819D02*
X1266786Y-22191D01*
G01X1263580Y-23029D02*
X1263179Y-23448D01*
G01Y-22610D02*
X1263580Y-22191D01*
G01X1247750Y-27845D02*
X1248351Y-27217D01*
G01X1253761Y-20306D02*
X1254563Y-19469D01*
G01X1260374Y-22401D02*
X1259973Y-23029D01*
G01X1254963Y-20516D02*
X1254563Y-21144D01*
G01X1275603Y-23238D02*
X1275403Y-23657D01*
G01X1266586Y-23238D02*
X1266385Y-23657D01*
G01X1258971Y-22401D02*
X1259372Y-21563D01*
G01X1260574D02*
X1260374Y-22401D01*
G01X1278609Y-23657D02*
Y-28683D01*
G01X1277607D02*
Y-23657D01*
G01X1275403D02*
Y-28683D01*
G01X1274401D02*
Y-23657D01*
G01X1272197Y-23448D02*
Y-28683D01*
G01Y-21982D02*
Y-22610D01*
G01X1271195Y-28683D02*
Y-21982D01*
G01X1269592Y-23657D02*
Y-28683D01*
G01X1268590D02*
Y-23657D01*
G01X1266385D02*
Y-28683D01*
G01X1265383D02*
Y-23657D01*
G01X1263179Y-23448D02*
Y-28683D01*
G01Y-21982D02*
Y-22610D01*
G01X1248150Y-23029D02*
X1247950Y-21772D01*
G01X1242940Y-24495D02*
X1243141Y-25751D01*
G01X1249152Y-22819D02*
X1248952Y-21772D01*
G01X1241938Y-24704D02*
X1242139Y-25751D01*
G01X1260374Y-20306D02*
X1260574Y-21144D01*
G01X1248952Y-21772D02*
X1248752Y-21144D01*
G01X1265383Y-23657D02*
X1265183Y-23238D01*
G01X1248752Y-21144D02*
X1248351Y-20306D01*
G01X1259372Y-21144D02*
X1258971Y-20516D01*
G01X1247950Y-21772D02*
X1247148Y-20516D01*
G01X1243141Y-25751D02*
X1243942Y-27008D01*
G01X1239935Y-21563D02*
X1240335Y-22191D01*
G01X1265584D02*
X1266185Y-22819D01*
G01X1265183Y-23238D02*
X1264983Y-23029D01*
G01X1259572Y-19469D02*
X1260374Y-20306D01*
G01X1248351D02*
X1247750Y-19678D01*
G01X1242740Y-27217D02*
X1243341Y-27845D01*
G01X1258971Y-20516D02*
X1258370Y-20097D01*
G01X1247148Y-20516D02*
X1246547Y-20097D01*
G01X1243942Y-27008D02*
X1244543Y-27427D01*
G01X1247750Y-19678D02*
X1246748Y-19050D01*
G01X1243341Y-27845D02*
X1244343Y-28474D01*
G01X1244543Y-27427D02*
X1245545Y-27636D01*
G01X1244343Y-28474D02*
X1245545Y-28683D01*
G01X1243341Y-19678D02*
X1242740Y-20306D01*
G01X1247148Y-27008D02*
X1247950Y-25751D01*
G01X1243942Y-20516D02*
X1243141Y-21772D01*
G01X1240335Y-25123D02*
X1239935Y-25751D01*
G01X1248351Y-27217D02*
X1248752Y-26379D01*
G01X1242740Y-20306D02*
X1242339Y-21144D01*
G01X1248752Y-26379D02*
X1248952Y-25751D01*
G01X1242339Y-21144D02*
X1242139Y-21772D01*
G01X1253561Y-21144D02*
X1253761Y-20306D01*
G01X1248952Y-25751D02*
X1249152Y-24704D01*
G01X1242139Y-21772D02*
X1241938Y-22819D01*
G01X1247950Y-25751D02*
X1248150Y-24495D01*
G01X1243141Y-21772D02*
X1242940Y-23029D01*
G01X1262177Y-28683D02*
Y-21982D01*
G01X1260574Y-27636D02*
Y-28683D01*
G01Y-21144D02*
Y-21563D01*
G01X1259372D02*
Y-21144D01*
G01X1253360Y-28683D02*
Y-27636D01*
G01X1251757D02*
Y-28683D01*
G01X1250755D02*
Y-27636D01*
G01X1249152Y-24704D02*
Y-22819D01*
G01X1248150Y-24495D02*
Y-23029D01*
G01X1242940D02*
Y-24495D01*
G01X1241938Y-22819D02*
Y-24704D01*
G01X1242139Y-25751D02*
X1242339Y-26379D01*
G01D02*
X1242740Y-27217D01*
G01X1285492Y17868D02*
X1285164Y18035D01*
G01X1285492Y18706D02*
X1285984Y18538D01*
G01X1282867Y18706D02*
X1283359Y18538D01*
G01X1266955Y19376D02*
X1266135D01*
G01X1284836Y18706D02*
X1285492D01*
G01X1282211D02*
X1282867D01*
G01X1280570D02*
X1281391D01*
G01X1277454D02*
X1278110D01*
G01X1274829D02*
X1275485D01*
G01X1273189D02*
X1274009D01*
G01X1244973Y18035D02*
X1249567D01*
G01X1275157D02*
X1274829D01*
G01X1277782D02*
X1277290D01*
G01X1282539D02*
X1282211D01*
G01X1285164D02*
X1284672D01*
G01X1249567Y17030D02*
X1244973D01*
G01X1259573Y13344D02*
X1260557Y13512D01*
G01X1259573Y14182D02*
X1260393Y14350D01*
G01X1286312Y18203D02*
X1286640Y17365D01*
G01X1278930Y18203D02*
X1279258Y17365D01*
G01X1285820D02*
X1285656Y17700D01*
G01X1283195Y17365D02*
X1283031Y17700D01*
G01X1278438Y17365D02*
X1278274Y17700D01*
G01X1275813Y17365D02*
X1275649Y17700D01*
G01X1270892Y19376D02*
X1270564Y19878D01*
G01X1285984Y18538D02*
X1286312Y18203D01*
G01X1285656Y17700D02*
X1285492Y17868D01*
G01X1283359Y18538D02*
X1283851Y18035D01*
G01X1283031Y17700D02*
X1282867Y17868D01*
G01X1278602Y18538D02*
X1278930Y18203D01*
G01X1278274Y17700D02*
X1278110Y17868D01*
G01X1275977Y18538D02*
X1276469Y18035D01*
G01X1275649Y17700D02*
X1275485Y17868D01*
G01X1258261Y14685D02*
X1258753Y14350D01*
G01X1257769Y14015D02*
X1258589Y13512D01*
G01X1254980Y15690D02*
X1251863Y17365D01*
G01X1282867Y17868D02*
X1282539Y18035D01*
G01X1278110Y17868D02*
X1277782Y18035D01*
G01X1275485Y17868D02*
X1275157Y18035D01*
G01X1253011Y17365D02*
X1255308Y16193D01*
G01X1278110Y18706D02*
X1278602Y18538D01*
G01X1275485Y18706D02*
X1275977Y18538D01*
G01X1258753Y14350D02*
X1259573Y14182D01*
G01X1258589Y13512D02*
X1259573Y13344D01*
G01X1267283Y14182D02*
X1271876D01*
G01X1263838D02*
X1264658D01*
G01X1244973Y13344D02*
X1243989D01*
G01X1250551D02*
X1249567D01*
G01X1264658D02*
X1263838D01*
G01X1271876D02*
X1265971D01*
G01X1274009D02*
X1273189D01*
G01X1276633D02*
X1275813D01*
G01X1279258D02*
X1278438D01*
G01X1281391D02*
X1280570D01*
G01X1284015D02*
X1283195D01*
G01X1286640D02*
X1285820D01*
G01X1286640Y17365D02*
Y13344D01*
G01X1261706Y17868D02*
X1261542Y18873D01*
G01X1262526Y18035D02*
X1262362Y18873D01*
G01X1271712Y20046D02*
X1271876Y19376D01*
G01X1262362Y18873D02*
X1262198Y19376D01*
G01X1256784Y15690D02*
X1256948Y15187D01*
G01X1262198Y19376D02*
X1261870Y20046D01*
G01X1256948Y15187D02*
X1257277Y14517D01*
G01X1261542Y18873D02*
X1260885Y19878D01*
G01X1257605Y15690D02*
X1258261Y14685D01*
G01X1254980Y19041D02*
X1255308Y18538D01*
G01X1257277Y14517D02*
X1257769Y14015D01*
G01X1284343Y17868D02*
X1284179Y17700D01*
G01X1283851Y18035D02*
X1284343Y18538D01*
G01X1284179Y17700D02*
X1284015Y17365D01*
G01X1276798Y17700D02*
X1276633Y17365D01*
G01X1271876Y19041D02*
X1271712Y18370D01*
G01X1285820Y13344D02*
Y17365D01*
G01X1284015D02*
Y13344D01*
G01X1283195D02*
Y17365D01*
G01X1281391Y17533D02*
Y13344D01*
G01Y18706D02*
Y18203D01*
G01X1280570Y13344D02*
Y18706D01*
G01X1279258Y17365D02*
Y13344D01*
G01X1278438D02*
Y17365D01*
G01X1276633D02*
Y13344D01*
G01X1275813D02*
Y17365D01*
G01X1274009Y17533D02*
Y13344D01*
G01Y18706D02*
Y18203D01*
G01X1273189Y13344D02*
Y18706D01*
G01X1271876Y14182D02*
Y13344D01*
G01Y19376D02*
Y19041D01*
G01X1270892D02*
Y19376D01*
G01X1265971Y13344D02*
Y14182D01*
G01X1264658D02*
Y13344D01*
G01X1263838D02*
Y14182D01*
G01X1257441Y16695D02*
X1257605Y15690D01*
G01X1256620Y16528D02*
X1256784Y15690D01*
G01X1284343Y18538D02*
X1284836Y18706D01*
G01X1282211Y18035D02*
X1281719Y17868D01*
G01Y18538D02*
X1282211Y18706D01*
G01X1276962Y18538D02*
X1277454Y18706D01*
G01X1274829Y18035D02*
X1274337Y17868D01*
G01Y18538D02*
X1274829Y18706D01*
G01X1284672Y18035D02*
X1284343Y17868D01*
G01X1277290Y18035D02*
X1276962Y17868D01*
G01X1255308Y18538D02*
X1253011Y17365D01*
G01X1251863D02*
X1254980Y19041D01*
G01X1260557Y13512D02*
X1261378Y14015D01*
G01X1260393Y14350D02*
X1260885Y14685D01*
G01X1271384Y17868D02*
X1267283Y14182D01*
G01X1265971D02*
X1270564Y18370D01*
G01X1281719Y17868D02*
X1281391Y17533D01*
G01Y18203D02*
X1281719Y18538D01*
G01X1276962Y17868D02*
X1276798Y17700D01*
G01X1276469Y18035D02*
X1276962Y18538D01*
G01X1274337Y17868D02*
X1274009Y17533D01*
G01Y18203D02*
X1274337Y18538D01*
G01X1261378Y14015D02*
X1261870Y14517D01*
G01X1271712Y18370D02*
X1271384Y17868D01*
G01X1267283Y19878D02*
X1266955Y19376D01*
G01X1260885Y14685D02*
X1261542Y15690D01*
G01X1258261Y19878D02*
X1257605Y18873D01*
G01X1255308Y16193D02*
X1254980Y15690D01*
G01X1270564Y18370D02*
X1270892Y19041D01*
G01X1261870Y14517D02*
X1262198Y15187D01*
G01X1257277Y20046D02*
X1256948Y19376D01*
G01X1262198Y15187D02*
X1262362Y15690D01*
G01X1256948Y19376D02*
X1256784Y18873D01*
G01X1266135Y19376D02*
X1266299Y20046D01*
G01X1262362Y15690D02*
X1262526Y16528D01*
G01X1256784Y18873D02*
X1256620Y18035D01*
G01X1261542Y15690D02*
X1261706Y16695D01*
G01X1257605Y18873D02*
X1257441Y17868D01*
G01X1262526Y16528D02*
Y18035D01*
G01X1261706Y16695D02*
Y17868D01*
G01X1257441D02*
Y16695D01*
G01X1256620Y18035D02*
Y16528D01*
G01X1250551Y21219D02*
Y13344D01*
G01X1249567Y18035D02*
Y21219D01*
G01Y13344D02*
Y17030D01*
G01X1244973D02*
Y13344D01*
G01Y21219D02*
Y18035D01*
G01X1243989Y13344D02*
Y21219D01*
G01X1246627Y53896D02*
X1265036D01*
G01X1264802Y42911D02*
X1484511D01*
G01X1270072Y20213D02*
X1269252Y20381D01*
G01X1269416Y21219D02*
X1270400Y21051D01*
G01X1260557D02*
X1259573Y21219D01*
G01X1268759D02*
X1269416D01*
G01X1249567D02*
X1250551D01*
G01X1243989D02*
X1244973D01*
G01X1269252Y20381D02*
X1268595D01*
G01X1267611Y21051D02*
X1268759Y21219D01*
G01X1259573D02*
X1258589Y21051D01*
G01X1259573Y20381D02*
X1258753Y20213D01*
G01X1268595Y20381D02*
X1267775Y20213D01*
G01X1271056Y20716D02*
X1271712Y20046D01*
G01X1261870D02*
X1261378Y20548D01*
G01X1270564Y19878D02*
X1270072Y20213D01*
G01X1260885Y19878D02*
X1260393Y20213D01*
G01X1261378Y20548D02*
X1260557Y21051D01*
G01X1270400D02*
X1271056Y20716D01*
G01X1260393Y20213D02*
X1259573Y20381D01*
G01X1265036Y42911D02*
Y53896D01*
G01X1264802Y101967D02*
Y42911D01*
G01X1266955Y20716D02*
X1267611Y21051D01*
G01X1258589D02*
X1257769Y20548D01*
G01X1267775Y20213D02*
X1267283Y19878D01*
G01X1258753Y20213D02*
X1258261Y19878D01*
G01X1266299Y20046D02*
X1266955Y20716D01*
G01X1257769Y20548D02*
X1257277Y20046D01*
G01X1246627Y42911D02*
Y101967D01*
G01X1232493Y128817D02*
X1234462D01*
G01Y122451D02*
X1243648D01*
G01Y120440D02*
X1234462D01*
G01Y113069D02*
X1232493D01*
G01X1234462Y120440D02*
Y113069D01*
G01Y128817D02*
Y122451D01*
G01X1232493Y113069D02*
Y128817D01*
G01X1295157Y122116D02*
X1294501Y122451D01*
G01X1289908Y122116D02*
X1289252Y122451D01*
G01X1295157Y123791D02*
X1296141Y123456D01*
G01X1289908Y123791D02*
X1290892Y123456D01*
G01X1280393Y123791D02*
X1281378Y123456D01*
G01X1275144Y123791D02*
X1276128Y123456D01*
G01X1263989Y126807D02*
X1262677Y127142D01*
G01X1260052Y122116D02*
X1261364Y121781D01*
G01X1263989Y120105D02*
X1262677Y120440D01*
G01X1264317Y128482D02*
X1262677Y128817D01*
G01X1243648D02*
X1245616D01*
G01X1262677D02*
X1261364D01*
G01X1262677Y127142D02*
X1261364D01*
G01X1293845Y123791D02*
X1295157D01*
G01X1288595D02*
X1289908D01*
G01X1285315D02*
X1286955D01*
G01X1279081D02*
X1280393D01*
G01X1273832D02*
X1275144D01*
G01X1270551D02*
X1272191D01*
G01X1248241D02*
X1253490D01*
G01Y122451D02*
X1248241D01*
G01X1274488D02*
X1273832D01*
G01X1279737D02*
X1278753D01*
G01X1289252D02*
X1288595D01*
G01X1294501D02*
X1293517D01*
G01X1261364Y121781D02*
X1262677D01*
G01Y120440D02*
X1261364D01*
G01X1248241Y119770D02*
X1253490D01*
G01Y118430D02*
X1248241D01*
G01X1261364Y114744D02*
X1262677D01*
G01X1261036Y113069D02*
X1263005D01*
G01X1245616D02*
X1243648D01*
G01X1272191D02*
X1270551D01*
G01X1277441D02*
X1275800D01*
G01X1282690D02*
X1281049D01*
G01X1286955D02*
X1285315D01*
G01X1292204D02*
X1290564D01*
G01X1297454D02*
X1295813D01*
G01X1261364Y128817D02*
X1259724Y128482D01*
G01X1263005Y113069D02*
X1264645Y113404D01*
G01X1261364Y127142D02*
X1260052Y126807D01*
G01X1262677Y121781D02*
X1263989Y122116D01*
G01X1261364Y120440D02*
X1260052Y120105D01*
G01X1262677Y114744D02*
X1263989Y115079D01*
G01X1296141Y123456D02*
X1296798Y122786D01*
G01X1295485Y121781D02*
X1295157Y122116D01*
G01X1290892Y123456D02*
X1291876Y122451D01*
G01X1290236Y121781D02*
X1289908Y122116D01*
G01X1265301Y125801D02*
X1263989Y126807D01*
G01X1265958Y127477D02*
X1264317Y128482D01*
G01X1280393Y122116D02*
X1279737Y122451D01*
G01X1275144Y122116D02*
X1274488Y122451D01*
G01X1265958Y120775D02*
X1265301Y121110D01*
G01Y119435D02*
X1263989Y120105D01*
G01X1258084Y121446D02*
X1258740Y121110D01*
G01Y115749D02*
X1260052Y115079D01*
G01D02*
X1261364Y114744D01*
G01X1259396Y113404D02*
X1261036Y113069D01*
G01X1264802Y101967D02*
X1324094D01*
G01X1281378Y123456D02*
X1282034Y122786D01*
G01X1280721Y121781D02*
X1280393Y122116D01*
G01X1276128Y123456D02*
X1277112Y122451D01*
G01X1275472Y121781D02*
X1275144Y122116D01*
G01X1266942Y126471D02*
X1265958Y127477D01*
G01X1257099Y122451D02*
X1258084Y121446D01*
G01X1267270Y119770D02*
X1265958Y120775D01*
G01X1258740Y123121D02*
X1260052Y122116D01*
G01X1257756Y114409D02*
X1259396Y113404D01*
G01X1296798Y122786D02*
X1297454Y121110D01*
G01X1295813D02*
X1295485Y121781D01*
G01X1290564Y121110D02*
X1290236Y121781D01*
G01X1281049Y121110D02*
X1280721Y121781D01*
G01X1275800Y121110D02*
X1275472Y121781D01*
G01X1265958Y124796D02*
X1265301Y125801D01*
G01X1258084Y124126D02*
X1258740Y123121D01*
G01X1266286Y118095D02*
X1265301Y119435D01*
G01X1257756Y117090D02*
X1258740Y115749D01*
G01X1256771Y115414D02*
X1257756Y114409D01*
G01X1282034Y122786D02*
X1282690Y121110D01*
G01X1267598Y124796D02*
X1266942Y126471D01*
G01X1267926Y118095D02*
X1267270Y119770D01*
G01X1256443Y123791D02*
X1257099Y122451D01*
G01X1256115Y117090D02*
X1256771Y115414D01*
G01X1297454Y121110D02*
Y113069D01*
G01X1295813D02*
Y121110D01*
G01X1292204D02*
Y113069D01*
G01X1290564D02*
Y121110D01*
G01X1286955Y121446D02*
Y113069D01*
G01Y123791D02*
Y122786D01*
G01X1285315Y113069D02*
Y123791D01*
G01X1282690Y121110D02*
Y113069D01*
G01X1281049D02*
Y121110D01*
G01X1277441D02*
Y113069D01*
G01X1275800D02*
Y121110D01*
G01X1272191Y121446D02*
Y113069D01*
G01Y123791D02*
Y122786D01*
G01X1270551Y113069D02*
Y123791D01*
G01X1267926Y117090D02*
Y118095D01*
G01X1267598Y123791D02*
Y124796D01*
G01X1266286Y117090D02*
Y118095D01*
G01X1265958Y124126D02*
Y124796D01*
G01X1258084D02*
Y124126D01*
G01X1257756Y118095D02*
Y117090D01*
G01X1256443Y124796D02*
Y123791D01*
G01X1256115Y118095D02*
Y117090D01*
G01X1253490Y119770D02*
Y118430D01*
G01Y123791D02*
Y122451D01*
G01X1248241D02*
Y123791D01*
G01Y118430D02*
Y119770D01*
G01X1245616Y128817D02*
Y113069D01*
G01X1243648Y122451D02*
Y128817D01*
G01Y113069D02*
Y120440D01*
G01X1292532Y121781D02*
X1292204Y121110D01*
G01X1277769Y121781D02*
X1277441Y121110D01*
G01X1267270Y115414D02*
X1267926Y117090D01*
G01X1292861Y122116D02*
X1292532Y121781D01*
G01X1291876Y122451D02*
X1292861Y123456D01*
G01X1287611Y122116D02*
X1286955Y121446D01*
G01X1265301Y115749D02*
X1266286Y117090D01*
G01X1265301Y123121D02*
X1265958Y124126D01*
G01X1266942Y122451D02*
X1267598Y123791D01*
G01X1256771Y119770D02*
X1256115Y118095D01*
G01X1257099Y126471D02*
X1256443Y124796D01*
G01X1286955Y122786D02*
X1287611Y123456D01*
G01X1278097Y122116D02*
X1277769Y121781D01*
G01X1277112Y122451D02*
X1278097Y123456D01*
G01X1266286Y114409D02*
X1267270Y115414D01*
G01X1272847Y122116D02*
X1272191Y121446D01*
G01Y122786D02*
X1272847Y123456D01*
G01X1265958Y121446D02*
X1266942Y122451D01*
G01X1258740Y119435D02*
X1257756Y118095D01*
G01X1258740Y125801D02*
X1258084Y124796D01*
G01X1292861Y123456D02*
X1293845Y123791D01*
G01X1288595Y122451D02*
X1287611Y122116D01*
G01Y123456D02*
X1288595Y123791D01*
G01X1278097Y123456D02*
X1279081Y123791D01*
G01X1273832Y122451D02*
X1272847Y122116D01*
G01Y123456D02*
X1273832Y123791D01*
G01X1293517Y122451D02*
X1292861Y122116D01*
G01X1278753Y122451D02*
X1278097Y122116D01*
G01X1263989Y115079D02*
X1265301Y115749D01*
G01Y121110D02*
X1265958Y121446D01*
G01X1260052Y120105D02*
X1258740Y119435D01*
G01Y121110D02*
X1258084Y120775D01*
G01X1264645Y113404D02*
X1266286Y114409D01*
G01X1259724Y128482D02*
X1258084Y127477D01*
G01X1263989Y122116D02*
X1265301Y123121D01*
G01X1258084Y120775D02*
X1256771Y119770D01*
G01X1260052Y126807D02*
X1258740Y125801D01*
G01X1258084Y127477D02*
X1257099Y126471D01*
G01X1264592Y224022D02*
X1262156D01*
G01X1265567Y224744D02*
X1264592Y224022D01*
G01X1266054Y225466D02*
X1265567Y224744D01*
G01X1266054Y226910D02*
Y225466D01*
G01X1265567Y227631D02*
X1266054Y226910D01*
G01X1264592Y228353D02*
X1265567Y227631D01*
G01X1262156Y228353D02*
X1264592D01*
G01X1262156Y219692D02*
Y228353D01*
G01X1258746Y221857D02*
X1258259Y221135D01*
G01X1259233Y224022D02*
X1258746Y221857D01*
G01Y226188D02*
X1259233Y224022D01*
G01X1257771Y227631D02*
X1258746Y226188D01*
G01X1256797Y228353D02*
X1257771Y227631D01*
G01X1255823Y228353D02*
X1256797D01*
G01X1254848Y227631D02*
X1255823Y228353D01*
G01X1254361Y226910D02*
X1254848Y227631D01*
G01X1253874Y226188D02*
X1254361Y226910D01*
G01X1253386Y224022D02*
X1253874Y226188D01*
G01Y221857D02*
X1253386Y224022D01*
G01X1254361Y221135D02*
X1253874Y221857D01*
G01X1254848Y220414D02*
X1254361Y221135D01*
G01X1255823Y219692D02*
X1254848Y220414D01*
G01X1256797Y219692D02*
X1255823D01*
G01X1257771Y220414D02*
X1256797Y219692D01*
G01X1258259Y221135D02*
X1257771Y220414D01*
G01X1277747Y221135D02*
X1277260Y221857D01*
G01X1278234Y220414D02*
X1277747Y221135D01*
G01X1279208Y219692D02*
X1278234Y220414D01*
G01X1280183Y219692D02*
X1279208D01*
G01X1281157Y220414D02*
X1280183Y219692D01*
G01X1281644Y221135D02*
X1281157Y220414D01*
G01X1281644Y222579D02*
Y221135D01*
G01X1281157Y223301D02*
X1281644Y222579D01*
G01X1280183Y224022D02*
X1281157Y223301D01*
G01X1279208Y224744D02*
X1280183Y224022D01*
G01X1278234Y225466D02*
X1279208Y224744D01*
G01X1277747Y226188D02*
X1278234Y225466D01*
G01X1277747Y226910D02*
Y226188D01*
G01X1278234Y227631D02*
X1277747Y226910D01*
G01X1279208Y228353D02*
X1278234Y227631D01*
G01X1280183Y228353D02*
X1279208D01*
G01X1281157Y227631D02*
X1280183Y228353D01*
G01X1281644Y226910D02*
X1281157Y227631D01*
G01X1301133Y228353D02*
X1305030D01*
G01X1301133Y219692D02*
Y228353D01*
G01X1305030Y219692D02*
X1301133D01*
G01X1293337D02*
Y228353D01*
G01X1295286Y219692D02*
X1293337D01*
G01X1296260Y220414D02*
X1295286Y219692D01*
G01X1296748Y221135D02*
X1296260Y220414D01*
G01X1297235Y221857D02*
X1296748Y221135D01*
G01X1297722Y224022D02*
X1297235Y221857D01*
G01Y226188D02*
X1297722Y224022D01*
G01X1296748Y226910D02*
X1297235Y226188D01*
G01X1296260Y227631D02*
X1296748Y226910D01*
G01X1295286Y228353D02*
X1296260Y227631D01*
G01X1293337Y228353D02*
X1295286D01*
G01X1246078D02*
X1250950D01*
G01X1301133Y224022D02*
X1303569D01*
G01X1287491Y228353D02*
Y219692D01*
G01X1248514Y228353D02*
Y219692D01*
G01X1238768Y304591D02*
Y315614D01*
G01X1236602D02*
Y304591D01*
G01X1235618D02*
Y315614D01*
G01X1233453D02*
Y304591D01*
G01X1232468D02*
Y315614D01*
G01X1230303D02*
Y304591D01*
G01X1229319D02*
Y315614D01*
G01X1236602Y304591D02*
X1238768D01*
G01X1233453D02*
X1235618D01*
G01X1230303D02*
X1232468D01*
G01Y315614D02*
X1230303D01*
G01X1235618D02*
X1233453D01*
G01X1238768D02*
X1236602D01*
G01X1305894D02*
Y304591D01*
G01X1304909D02*
Y315614D01*
G01X1302744D02*
Y304591D01*
G01X1301760D02*
Y315614D01*
G01X1299594D02*
Y304591D01*
G01X1298610D02*
Y315614D01*
G01X1296445D02*
Y304591D01*
G01X1295461D02*
Y315614D01*
G01X1293295D02*
Y304591D01*
G01X1292311D02*
Y315614D01*
G01X1290146D02*
Y304591D01*
G01X1289161D02*
Y315614D01*
G01X1286996D02*
Y304591D01*
G01X1286012D02*
Y315614D01*
G01X1283846D02*
Y304591D01*
G01X1282862D02*
Y315614D01*
G01X1280697D02*
Y304591D01*
G01X1279713D02*
Y315614D01*
G01X1277547D02*
Y304591D01*
G01X1276563D02*
Y315614D01*
G01X1274398D02*
Y304591D01*
G01X1273413D02*
Y315614D01*
G01X1271248D02*
Y304591D01*
G01X1270264D02*
Y315614D01*
G01X1268098D02*
Y304591D01*
G01X1267114D02*
Y315614D01*
G01X1264949D02*
Y304591D01*
G01X1263965D02*
Y315614D01*
G01X1261799D02*
Y304591D01*
G01X1260815D02*
Y315614D01*
G01X1258650D02*
Y304591D01*
G01X1257665D02*
Y315614D01*
G01X1255500D02*
Y304591D01*
G01X1254516D02*
Y315614D01*
G01X1252350D02*
Y304591D01*
G01X1251366D02*
Y315614D01*
G01X1249201D02*
Y304591D01*
G01X1248217D02*
Y315614D01*
G01X1246051D02*
Y304591D01*
G01X1245067D02*
Y315614D01*
G01X1242902D02*
Y304591D01*
G01X1241917D02*
Y315614D01*
G01X1239752D02*
Y304591D01*
G01X1305894D02*
X1308059D01*
G01X1302744D02*
X1304909D01*
G01X1299594D02*
X1301760D01*
G01X1296445D02*
X1298610D01*
G01X1293295D02*
X1295461D01*
G01X1290146D02*
X1292311D01*
G01X1286996D02*
X1289161D01*
G01X1283846D02*
X1286012D01*
G01X1280697D02*
X1282862D01*
G01X1277547D02*
X1279713D01*
G01X1274398D02*
X1276563D01*
G01X1271248D02*
X1273413D01*
G01X1268098D02*
X1270264D01*
G01X1264949D02*
X1267114D01*
G01X1261799D02*
X1263965D01*
G01X1258650D02*
X1260815D01*
G01X1255500D02*
X1257665D01*
G01X1252350D02*
X1254516D01*
G01X1249201D02*
X1251366D01*
G01X1246051D02*
X1248217D01*
G01X1242902D02*
X1245067D01*
G01X1239752D02*
X1241917D01*
G01Y315614D02*
X1239752D01*
G01X1245067D02*
X1242902D01*
G01X1248217D02*
X1246051D01*
G01X1251366D02*
X1249201D01*
G01X1254516D02*
X1252350D01*
G01X1257665D02*
X1255500D01*
G01X1260815D02*
X1258650D01*
G01X1263965D02*
X1261799D01*
G01X1267114D02*
X1264949D01*
G01X1270264D02*
X1268098D01*
G01X1273413D02*
X1271248D01*
G01X1276563D02*
X1274398D01*
G01X1279713D02*
X1277547D01*
G01X1282862D02*
X1280697D01*
G01X1286012D02*
X1283846D01*
G01X1289161D02*
X1286996D01*
G01X1292311D02*
X1290146D01*
G01X1295461D02*
X1293295D01*
G01X1298610D02*
X1296445D01*
G01X1301760D02*
X1299594D01*
G01X1304909D02*
X1302744D01*
G01X1308059D02*
X1305894D01*
G01X1232439Y343445D02*
X1233768Y344259D01*
G01X1232173Y344802D02*
X1232970Y345344D01*
G01X1229250Y355658D02*
X1227921Y354844D01*
G01X1229516Y354301D02*
X1228718Y353758D01*
G01X1233768Y344259D02*
X1234565Y345073D01*
G01X1232970Y345344D02*
X1234033Y346973D01*
G01X1228718Y353758D02*
X1227656Y352130D01*
G01X1234565Y345073D02*
X1235096Y346159D01*
G01D02*
X1235362Y346973D01*
G01D02*
X1235628Y348330D01*
G01X1234033Y346973D02*
X1234299Y348601D01*
G01X1239083Y344530D02*
Y343173D01*
G01X1237754D02*
Y344530D01*
G01X1235628Y348330D02*
Y350772D01*
G01X1234299Y350501D02*
X1234033Y352130D01*
G01X1235628Y350772D02*
X1235362Y352130D01*
G01X1230844Y355929D02*
X1229250Y355658D01*
G01X1230844Y354572D02*
X1229516Y354301D01*
G01X1234299Y348601D02*
Y350501D01*
G01X1235362Y352130D02*
X1235096Y352944D01*
G01D02*
X1234565Y354029D01*
G01X1234033Y352130D02*
X1232970Y353758D01*
G01X1232173Y354301D02*
X1230844Y354572D01*
G01X1232439Y355658D02*
X1230844Y355929D01*
G01X1237754Y344530D02*
X1239083D01*
G01Y343173D02*
X1237754D01*
G01X1230844D02*
X1232439Y343445D01*
G01X1230844Y344530D02*
X1232173Y344802D01*
G01X1227656Y346973D02*
X1228718Y345344D01*
G01X1234565Y354029D02*
X1233768Y354844D01*
G01X1232970Y353758D02*
X1232173Y354301D01*
G01X1228718Y345344D02*
X1229516Y344802D01*
G01X1233768Y354844D02*
X1232439Y355658D01*
G01X1227921Y344259D02*
X1229250Y343445D01*
G01X1229516Y344802D02*
X1230844Y344530D01*
G01X1229250Y343445D02*
X1230844Y343173D01*
G01X1270972Y351587D02*
X1271770Y351858D01*
G01X1267518Y350772D02*
X1266720Y350501D01*
G01Y351587D02*
X1267518Y351858D01*
G01X1259014Y351587D02*
X1259811Y351858D01*
G01X1255559Y350772D02*
X1254762Y350501D01*
G01Y351587D02*
X1255559Y351858D01*
G01X1271504Y350772D02*
X1270972Y350501D01*
G01X1259545Y350772D02*
X1259014Y350501D01*
G01X1242803Y355115D02*
X1243866Y355658D01*
G01X1244132Y354301D02*
X1243335Y353758D01*
G01X1249978Y350501D02*
X1243335Y344530D01*
G01X1241209D02*
X1248650Y351315D01*
G01X1270972Y350501D02*
X1270707Y350230D01*
G01X1270175Y350772D02*
X1270972Y351587D01*
G01X1266720Y350501D02*
X1266189Y349958D01*
G01Y351044D02*
X1266720Y351587D01*
G01X1259014Y350501D02*
X1258748Y350230D01*
G01X1258217Y350772D02*
X1259014Y351587D01*
G01X1254762Y350501D02*
X1254230Y349958D01*
G01Y351044D02*
X1254762Y351587D01*
G01X1241740Y354029D02*
X1242803Y355115D01*
G01X1250510Y351315D02*
X1249978Y350501D01*
G01X1243335Y353758D02*
X1242803Y352944D01*
G01X1270707Y350230D02*
X1270441Y349687D01*
G01X1258748Y350230D02*
X1258482Y349687D01*
G01X1248650Y351315D02*
X1249181Y352401D01*
G01X1250776D02*
X1250510Y351315D01*
G01X1241474Y352944D02*
X1241740Y354029D01*
G01X1274693Y349687D02*
Y343173D01*
G01X1273364D02*
Y349687D01*
G01X1270441D02*
Y343173D01*
G01X1269112D02*
Y349687D01*
G01X1266189Y349958D02*
Y343173D01*
G01Y351858D02*
Y351044D01*
G01X1264860Y343173D02*
Y351858D01*
G01X1262734Y349687D02*
Y343173D01*
G01X1261406D02*
Y349687D01*
G01X1274161Y351044D02*
X1274693Y349687D01*
G01X1258482D02*
Y343173D01*
G01X1257154D02*
Y349687D01*
G01X1254230Y349958D02*
Y343173D01*
G01Y351858D02*
Y351044D01*
G01X1252902Y343173D02*
Y351858D01*
G01X1250776Y344530D02*
Y343173D01*
G01Y352944D02*
Y352401D01*
G01X1249181D02*
Y352944D01*
G01X1241209Y343173D02*
Y344530D01*
G01X1250510Y354029D02*
X1250776Y352944D01*
G01X1262203Y351044D02*
X1262734Y349687D01*
G01X1273364D02*
X1273098Y350230D01*
G01X1269112Y349687D02*
X1268846Y350230D01*
G01X1261406Y349687D02*
X1261140Y350230D01*
G01X1257154Y349687D02*
X1256888Y350230D01*
G01X1243866Y355658D02*
X1245726Y355929D01*
G01X1245461Y354572D02*
X1244132Y354301D01*
G01X1249181Y352944D02*
X1248650Y353758D01*
G01X1273630Y351587D02*
X1274161Y351044D01*
G01X1273098Y350230D02*
X1272833Y350501D01*
G01X1269378Y351587D02*
X1270175Y350772D01*
G01X1268846Y350230D02*
X1268581Y350501D01*
G01X1261671Y351587D02*
X1262203Y351044D01*
G01X1261140Y350230D02*
X1260874Y350501D01*
G01X1257419Y351587D02*
X1258217Y350772D01*
G01X1256888Y350230D02*
X1256622Y350501D01*
G01X1249447Y355115D02*
X1250510Y354029D01*
G01X1248650Y353758D02*
X1247852Y354301D01*
G01X1272833Y350501D02*
X1272301Y350772D01*
G01X1268581Y350501D02*
X1268049Y350772D01*
G01X1260874Y350501D02*
X1260343Y350772D01*
G01X1248384Y355658D02*
X1249447Y355115D01*
G01X1256622Y350501D02*
X1256091Y350772D01*
G01X1272833Y351858D02*
X1273630Y351587D01*
G01X1268581Y351858D02*
X1269378Y351587D01*
G01X1260874Y351858D02*
X1261671Y351587D01*
G01X1256622Y351858D02*
X1257419Y351587D01*
G01X1247852Y354301D02*
X1246524Y354572D01*
G01X1246789Y355929D02*
X1248384Y355658D01*
G01X1245726Y355929D02*
X1246789D01*
G01X1246524Y354572D02*
X1245461D01*
G01X1242803Y352944D02*
X1241474D01*
G01X1271770Y351858D02*
X1272833D01*
G01X1267518D02*
X1268581D01*
G01X1264860D02*
X1266189D01*
G01X1259811D02*
X1260874D01*
G01X1255559D02*
X1256622D01*
G01X1252902D02*
X1254230D01*
G01X1256091Y350772D02*
X1255559D01*
G01X1260343D02*
X1259545D01*
G01X1268049D02*
X1267518D01*
G01X1272301D02*
X1271504D01*
G01X1243335Y344530D02*
X1250776D01*
G01Y343173D02*
X1241209D01*
G01X1254230D02*
X1252902D01*
G01X1258482D02*
X1257154D01*
G01X1262734D02*
X1261406D01*
G01X1266189D02*
X1264860D01*
G01X1270441D02*
X1269112D01*
G01X1274693D02*
X1273364D01*
G01X1228488Y416089D02*
X1230663D01*
G01X1250605D02*
X1238278D01*
G01Y406461D02*
X1240816D01*
G01X1240453Y403129D02*
X1238278D01*
G01X1233564Y400537D02*
X1235377D01*
G01X1230663Y398685D02*
X1228488D01*
G01X1235377D02*
X1233564D01*
G01X1238278Y416089D02*
Y406461D01*
G01X1235377Y400537D02*
Y398685D01*
G01X1238278Y403129D02*
X1239003Y401647D01*
G01D02*
X1240090Y400166D01*
G01X1233564Y398685D02*
Y400537D01*
G01X1230663Y416089D02*
Y398685D01*
G01X1228488D02*
Y413127D01*
G01X1247705Y399055D02*
X1249518Y400166D01*
G01X1241903Y409424D02*
X1240090Y408313D01*
G01X1248430Y401647D02*
X1247342Y400907D01*
G01X1240816Y406461D02*
X1242266Y407572D01*
G01X1249518Y400166D02*
X1250605Y401647D01*
G01X1249155Y402758D02*
X1248430Y401647D01*
G01X1289764Y412386D02*
X1284688Y398685D01*
G01X1269459Y412386D02*
X1264383Y398685D01*
G01X1283237Y400537D02*
X1288676Y416089D01*
G01X1262933Y400537D02*
X1268372Y416089D01*
G01X1291939D02*
Y398685D01*
G01X1289764D02*
Y412386D01*
G01X1277799Y416089D02*
X1283237Y400537D01*
G01X1281787Y398685D02*
X1276711Y412386D01*
G01X1288676Y416089D02*
X1291939D01*
G01X1274536D02*
X1277799D01*
G01X1268372D02*
X1271635D01*
G01X1254231D02*
X1257494D01*
G01X1240090Y414237D02*
X1250605D01*
G01X1243716Y409794D02*
X1241903Y409424D01*
G01X1242266Y407572D02*
X1243716Y407942D01*
G01X1247342Y400907D02*
X1245892Y400537D01*
G01X1250605Y401647D02*
X1251330Y403499D01*
G01X1249518Y403869D02*
X1249155Y402758D01*
G01X1276711Y412386D02*
Y398685D01*
G01X1274536D02*
Y416089D01*
G01X1271635D02*
Y398685D01*
G01X1269459D02*
Y412386D01*
G01X1249155Y405721D02*
X1249518Y404610D01*
G01X1257494Y416089D02*
X1262933Y400537D01*
G01X1261483Y398685D02*
X1256407Y412386D01*
G01X1251330Y404980D02*
X1250605Y406832D01*
G01X1245892Y407942D02*
X1247342Y407572D01*
G01X1247705Y409424D02*
X1245892Y409794D01*
G01D02*
X1243716D01*
G01Y407942D02*
X1245892D01*
G01Y400537D02*
X1243716D01*
G01Y398685D02*
X1245892D01*
G01X1256407D02*
X1254231D01*
G01X1264383D02*
X1261483D01*
G01X1271635D02*
X1269459D01*
G01X1276711D02*
X1274536D01*
G01X1284688D02*
X1281787D01*
G01X1291939D02*
X1289764D01*
G01X1245892D02*
X1247705Y399055D01*
G01X1256407Y412386D02*
Y398685D01*
G01X1254231D02*
Y416089D01*
G01X1251330Y403499D02*
Y404980D01*
G01X1250605Y414237D02*
Y416089D01*
G01X1249518Y404610D02*
Y403869D01*
G01X1240090Y408313D02*
Y414237D01*
G01X1241178Y401647D02*
X1240453Y403129D01*
G01X1248430Y406832D02*
X1249155Y405721D01*
G01X1250605Y406832D02*
X1249518Y408313D01*
G01X1247342Y407572D02*
X1248430Y406832D01*
G01X1242266Y400907D02*
X1241178Y401647D01*
G01X1249518Y408313D02*
X1247705Y409424D01*
G01X1240090Y400166D02*
X1241903Y399055D01*
G01X1243716Y400537D02*
X1242266Y400907D01*
G01X1241903Y399055D02*
X1243716Y398685D01*
G01X1230028Y484217D02*
X1231504D01*
G01Y472406D02*
X1230028D01*
G01X1238148Y475924D02*
X1233472Y478437D01*
G01X1235195D02*
X1238640Y476678D01*
G01X1238148Y480950D02*
X1238640Y480196D01*
G01D02*
X1235195Y478437D01*
G01X1233472D02*
X1238148Y480950D01*
G01X1238640Y476678D02*
X1238148Y475924D01*
G01X1231504Y484217D02*
Y472406D01*
G01X1230028Y479442D02*
Y484217D01*
G01Y472406D02*
Y477934D01*
G01X1249959Y484217D02*
X1248482Y483965D01*
G01X1249959Y482960D02*
X1248728Y482709D01*
G01X1274811Y479191D02*
X1274319Y479442D01*
G01X1274811Y480447D02*
X1275549Y480196D01*
G01X1270874Y480447D02*
X1271612Y480196D01*
G01X1263738Y480447D02*
X1264476Y480196D01*
G01X1259801Y480447D02*
X1260539Y480196D01*
G01X1251189Y482709D02*
X1249959Y482960D01*
G01X1248728Y473913D02*
X1249959Y473662D01*
G01X1251435Y483965D02*
X1249959Y484217D01*
G01X1248482Y472657D02*
X1249959Y472406D01*
G01X1242085Y484217D02*
X1243561D01*
G01X1273827Y480447D02*
X1274811D01*
G01X1269890D02*
X1270874D01*
G01X1267429D02*
X1268659D01*
G01X1262754D02*
X1263738D01*
G01X1258817D02*
X1259801D01*
G01X1256356D02*
X1257587D01*
G01X1259309Y479442D02*
X1258817D01*
G01X1263246D02*
X1262508D01*
G01X1270382D02*
X1269890D01*
G01X1274319D02*
X1273581D01*
G01X1243561Y472406D02*
X1242085D01*
G01X1257587D02*
X1256356D01*
G01X1261524D02*
X1260293D01*
G01X1265461D02*
X1264230D01*
G01X1268659D02*
X1267429D01*
G01X1272596D02*
X1271366D01*
G01X1276533D02*
X1275303D01*
G01X1249959D02*
X1251435Y472657D01*
G01X1249959Y473662D02*
X1251189Y473913D01*
G01X1276041Y479693D02*
X1276533Y478437D01*
G01X1275303D02*
X1275057Y478939D01*
G01X1275549Y480196D02*
X1276041Y479693D01*
G01X1275057Y478939D02*
X1274811Y479191D01*
G01X1271612Y480196D02*
X1272350Y479442D01*
G01X1271120Y478939D02*
X1270874Y479191D01*
G01X1264476Y480196D02*
X1264968Y479693D01*
G01X1263984Y478939D02*
X1263738Y479191D01*
G01X1260539Y480196D02*
X1261278Y479442D01*
G01X1260047Y478939D02*
X1259801Y479191D01*
G01X1253404Y482457D02*
X1252665Y483211D01*
G01X1251927Y482206D02*
X1251189Y482709D01*
G01X1247990Y474416D02*
X1248728Y473913D01*
G01X1252665Y483211D02*
X1251435Y483965D01*
G01X1247252Y473411D02*
X1248482Y472657D01*
G01X1270874Y479191D02*
X1270382Y479442D01*
G01X1263738Y479191D02*
X1263246Y479442D01*
G01X1259801Y479191D02*
X1259309Y479442D01*
G01X1254142Y480698D02*
X1253896Y481452D01*
G01X1264968Y479693D02*
X1265461Y478437D01*
G01X1271366D02*
X1271120Y478939D01*
G01X1264230Y478437D02*
X1263984Y478939D01*
G01X1260293Y478437D02*
X1260047Y478939D01*
G01X1253896Y481452D02*
X1253404Y482457D01*
G01X1252911Y480698D02*
X1251927Y482206D01*
G01X1247006Y475924D02*
X1247990Y474416D01*
G01X1246514Y474165D02*
X1247252Y473411D01*
G01X1273089Y480196D02*
X1273827Y480447D01*
G01X1269890Y479442D02*
X1269152Y479191D01*
G01Y480196D02*
X1269890Y480447D01*
G01X1262016Y480196D02*
X1262754Y480447D01*
G01X1258817Y479442D02*
X1258079Y479191D01*
G01Y480196D02*
X1258817Y480447D01*
G01X1273581Y479442D02*
X1273089Y479191D01*
G01X1262508Y479442D02*
X1262016Y479191D01*
G01X1251435Y472657D02*
X1252665Y473411D01*
G01X1251189Y473913D02*
X1251927Y474416D01*
G01X1273089Y479191D02*
X1272843Y478939D01*
G01X1272350Y479442D02*
X1273089Y480196D01*
G01X1269152Y479191D02*
X1268659Y478688D01*
G01Y479693D02*
X1269152Y480196D01*
G01X1262016Y479191D02*
X1261770Y478939D01*
G01X1272843D02*
X1272596Y478437D01*
G01X1276533D02*
Y472406D01*
G01X1275303D02*
Y478437D01*
G01X1272596D02*
Y472406D01*
G01X1271366D02*
Y478437D01*
G01X1268659Y478688D02*
Y472406D01*
G01Y480447D02*
Y479693D01*
G01X1267429Y472406D02*
Y480447D01*
G01X1265461Y478437D02*
Y472406D01*
G01X1264230D02*
Y478437D01*
G01X1261524D02*
Y472406D01*
G01X1260293D02*
Y478437D01*
G01X1253157Y479191D02*
X1252911Y480698D01*
G01X1246760Y477431D02*
X1247006Y475924D01*
G01X1254388Y479442D02*
X1254142Y480698D01*
G01X1245530Y477180D02*
X1245776Y475924D01*
G01D02*
X1246022Y475170D01*
G01D02*
X1246514Y474165D01*
G01X1248482Y483965D02*
X1247252Y483211D01*
G01X1248728Y482709D02*
X1247990Y482206D01*
G01X1261278Y479442D02*
X1262016Y480196D01*
G01X1252665Y473411D02*
X1253404Y474165D01*
G01X1258079Y479191D02*
X1257587Y478688D01*
G01Y479693D02*
X1258079Y480196D01*
G01X1247252Y483211D02*
X1246514Y482457D01*
G01X1242085Y482206D02*
X1240608Y480447D01*
G01Y482457D02*
X1242085Y484217D01*
G01X1251927Y474416D02*
X1252911Y475924D01*
G01X1247990Y482206D02*
X1247006Y480698D01*
G01X1261770Y478939D02*
X1261524Y478437D01*
G01X1253404Y474165D02*
X1253896Y475170D01*
G01X1246514Y482457D02*
X1246022Y481452D01*
G01X1253896Y475170D02*
X1254142Y475924D01*
G01X1246022Y481452D02*
X1245776Y480698D01*
G01X1254142Y475924D02*
X1254388Y477180D01*
G01X1245776Y480698D02*
X1245530Y479442D01*
G01X1252911Y475924D02*
X1253157Y477431D01*
G01X1247006Y480698D02*
X1246760Y479191D01*
G01X1257587Y478688D02*
Y472406D01*
G01Y480447D02*
Y479693D01*
G01X1256356Y472406D02*
Y480447D01*
G01X1254388Y477180D02*
Y479442D01*
G01X1253157Y477431D02*
Y479191D01*
G01X1246760D02*
Y477431D01*
G01X1245530Y479442D02*
Y477180D01*
G01X1243561Y484217D02*
Y472406D01*
G01X1242085D02*
Y482206D01*
G01X1240608Y480447D02*
Y482457D01*
G01X1230323Y497012D02*
X1250008D01*
G01X1233472Y502524D02*
Y497012D01*
G01X1230323Y502524D02*
Y497012D01*
G01X1301189D02*
X1320874D01*
G01X1277567D02*
X1297252D01*
G01X1253945D02*
X1273630D01*
G01X1304339Y502524D02*
Y497012D01*
G01X1301189Y502524D02*
Y497012D01*
G01X1297252Y502524D02*
Y497012D01*
G01X1294102Y502524D02*
Y497012D01*
G01X1280717Y502524D02*
Y497012D01*
G01X1277567Y502524D02*
Y497012D01*
G01X1273630Y502524D02*
Y497012D01*
G01X1270480Y502524D02*
Y497012D01*
G01X1257094Y502524D02*
Y497012D01*
G01X1253945Y502524D02*
Y497012D01*
G01X1250008Y502524D02*
Y497012D01*
G01X1246858Y502524D02*
Y497012D01*
G01X1230323Y577012D02*
X1250008D01*
G01X1233472Y582524D02*
Y577012D01*
G01X1230323Y582524D02*
Y577012D01*
G01X1253945D02*
X1273630D01*
G01X1257094Y582524D02*
Y577012D01*
G01X1253945Y582524D02*
Y577012D01*
G01X1250008Y582524D02*
Y577012D01*
G01X1246858Y582524D02*
Y577012D01*
G01X1231071Y525754D02*
Y525751D01*
G01X1231072Y525756D02*
X1231071Y525754D01*
G01X1231073Y525757D02*
X1231072Y525756D01*
G01X1229563Y510197D02*
X1229562Y510571D01*
G01X1229565Y509887D02*
X1229563Y510197D01*
G01X1229569Y509680D02*
X1229565Y509887D01*
G01X1229573Y509606D02*
X1229569Y509680D01*
G01X1231083Y524181D02*
X1231084Y523807D01*
G01X1231080Y524491D02*
X1231083Y524181D01*
G01X1231077Y524698D02*
X1231080Y524491D01*
G01X1231073Y524772D02*
X1231077Y524698D01*
G01X1229305Y526485D02*
X1229299Y526538D01*
G01X1229311Y526353D02*
X1229305Y526485D01*
G01X1229317Y526147D02*
X1229311Y526353D01*
G01X1231340Y507893D02*
X1231346Y507840D01*
G01X1231334Y508025D02*
X1231340Y507893D01*
G01X1231328Y508231D02*
X1231334Y508025D01*
G01X1233247Y526485D02*
X1233241Y526538D01*
G01X1233253Y526353D02*
X1233247Y526485D01*
G01X1233259Y526147D02*
X1233253Y526353D01*
G01X1229304Y525511D02*
X1229299Y525553D01*
G01X1229308Y525413D02*
X1229304Y525511D01*
G01X1229312Y525261D02*
X1229308Y525413D01*
G01X1231342Y508867D02*
X1231346Y508825D01*
G01X1231337Y508965D02*
X1231342Y508867D01*
G01X1231333Y509117D02*
X1231337Y508965D01*
G01X1233245Y525511D02*
X1233241Y525553D01*
G01X1233250Y525413D02*
X1233245Y525511D01*
G01X1233254Y525261D02*
X1233250Y525413D01*
G01X1233502Y509645D02*
X1233507Y509615D01*
G01X1233498Y509841D02*
X1233502Y509645D01*
G01X1233496Y510169D02*
X1233498Y509841D01*
G01X1233494Y510571D02*
X1233496Y510169D01*
G01X1235017Y524733D02*
X1235013Y524763D01*
G01X1235021Y524537D02*
X1235017Y524733D01*
G01X1235024Y524209D02*
X1235021Y524537D01*
G01X1235025Y523807D02*
X1235024Y524209D01*
G01X1229565Y508770D02*
X1229573Y508621D01*
G01X1229558Y509184D02*
X1229565Y508770D01*
G01X1229553Y509804D02*
X1229558Y509184D01*
G01X1229551Y510552D02*
X1229553Y509804D01*
G01X1231081Y525608D02*
X1231073Y525757D01*
G01X1231088Y525193D02*
X1231081Y525608D01*
G01X1231093Y524573D02*
X1231088Y525193D01*
G01X1231095Y523826D02*
X1231093Y524573D01*
G01X1229569Y524698D02*
X1229573Y524772D01*
G01X1229565Y524491D02*
X1229569Y524698D01*
G01X1229563Y524181D02*
X1229565Y524491D01*
G01X1229562Y523807D02*
X1229563Y524181D01*
G01X1231077Y509680D02*
X1231073Y509606D01*
G01X1231080Y509887D02*
X1231077Y509680D01*
G01X1231083Y510197D02*
X1231080Y509887D01*
G01X1231084Y510571D02*
X1231083Y510197D01*
G01X1229553Y524573D02*
X1229551Y523826D01*
G01X1229558Y525193D02*
X1229553Y524573D01*
G01X1229565Y525608D02*
X1229558Y525193D01*
G01X1229573Y525757D02*
X1229565Y525608D01*
G01X1231093Y509804D02*
X1231095Y510552D01*
G01X1231088Y509184D02*
X1231093Y509804D01*
G01X1231081Y508770D02*
X1231088Y509184D01*
G01X1231073Y508621D02*
X1231081Y508770D01*
G01X1237427Y524573D02*
X1237425Y523826D01*
G01X1237432Y525193D02*
X1237427Y524573D01*
G01X1237439Y525608D02*
X1237432Y525193D01*
G01X1237447Y525757D02*
X1237439Y525608D01*
G01X1229574Y509607D02*
X1229573Y509606D01*
G01X1229574Y509610D02*
Y509607D01*
G01X1229575Y509617D02*
X1229574Y509610D01*
G01X1231072Y524771D02*
X1231073Y524772D01*
G01X1231072Y524768D02*
Y524771D01*
G01X1231071Y524761D02*
X1231072Y524768D01*
G01X1237448Y509607D02*
X1237447Y509606D01*
G01X1237448Y509610D02*
Y509607D01*
G01X1237449Y509617D02*
X1237448Y509610D01*
G01X1238946Y524771D02*
X1238947Y524772D01*
G01X1238946Y524768D02*
Y524771D01*
G01X1238945Y524761D02*
X1238946Y524768D01*
G01X1229308Y508965D02*
X1229312Y509117D01*
G01X1229304Y508867D02*
X1229308Y508965D01*
G01X1229299Y508825D02*
X1229304Y508867D01*
G01X1231337Y525413D02*
X1231333Y525261D01*
G01X1231342Y525511D02*
X1231337Y525413D01*
G01X1231346Y525553D02*
X1231342Y525511D01*
G01X1233241Y508965D02*
X1233245Y509117D01*
G01X1233236Y508867D02*
X1233241Y508965D01*
G01X1233232Y508825D02*
X1233236Y508867D01*
G01X1235279Y525413D02*
X1235275Y525261D01*
G01X1235284Y525511D02*
X1235279Y525413D01*
G01X1235288Y525553D02*
X1235284Y525511D01*
G01X1237182Y508965D02*
X1237186Y509117D01*
G01X1237178Y508867D02*
X1237182Y508965D01*
G01X1237173Y508825D02*
X1237178Y508867D01*
G01X1239211Y525413D02*
X1239207Y525261D01*
G01X1239216Y525511D02*
X1239211Y525413D01*
G01X1239220Y525553D02*
X1239216Y525511D01*
G01X1231334Y526353D02*
X1231328Y526147D01*
G01X1231340Y526485D02*
X1231334Y526353D01*
G01X1231346Y526538D02*
X1231340Y526485D01*
G01X1229311Y508025D02*
X1229317Y508231D01*
G01X1229305Y507893D02*
X1229311Y508025D01*
G01X1229299Y507840D02*
X1229305Y507893D01*
G01X1235276Y526353D02*
X1235270Y526147D01*
G01X1235282Y526485D02*
X1235276Y526353D01*
G01X1235288Y526538D02*
X1235282Y526485D01*
G01X1233244Y508025D02*
X1233250Y508231D01*
G01X1233238Y507893D02*
X1233244Y508025D01*
G01X1233232Y507840D02*
X1233238Y507893D01*
G01X1239208Y526353D02*
X1239202Y526147D01*
G01X1239214Y526485D02*
X1239208Y526353D01*
G01X1239220Y526538D02*
X1239214Y526485D01*
G01X1237185Y508025D02*
X1237191Y508231D01*
G01X1237179Y507893D02*
X1237185Y508025D01*
G01X1237173Y507840D02*
X1237179Y507893D01*
G01X1233505Y524209D02*
X1233504Y523807D01*
G01X1233508Y524537D02*
X1233505Y524209D01*
G01X1233512Y524733D02*
X1233508Y524537D01*
G01X1233516Y524763D02*
X1233512Y524733D01*
G01X1235015Y510169D02*
X1235016Y510571D01*
G01X1235012Y509841D02*
X1235015Y510169D01*
G01X1235008Y509645D02*
X1235012Y509841D01*
G01X1235003Y509615D02*
X1235008Y509645D01*
G01X1238945Y525754D02*
Y525751D01*
G01X1238946Y525756D02*
X1238945Y525754D01*
G01X1238947Y525757D02*
X1238946Y525756D01*
G01X1229574Y508624D02*
X1229575Y508627D01*
G01X1229574Y508622D02*
Y508624D01*
G01X1229573Y508621D02*
X1229574Y508622D01*
G01X1237448Y508624D02*
X1237449Y508627D01*
G01X1237448Y508622D02*
Y508624D01*
G01X1237447Y508621D02*
X1237448Y508622D01*
G01X1237437Y510197D02*
X1237436Y510571D01*
G01X1237439Y509887D02*
X1237437Y510197D01*
G01X1237443Y509680D02*
X1237439Y509887D01*
G01X1237447Y509606D02*
X1237443Y509680D01*
G01X1238957Y524181D02*
X1238958Y523807D01*
G01X1238954Y524491D02*
X1238957Y524181D01*
G01X1238951Y524698D02*
X1238954Y524491D01*
G01X1238947Y524772D02*
X1238951Y524698D01*
G01X1235273Y507893D02*
X1235279Y507840D01*
G01X1235267Y508025D02*
X1235273Y507893D01*
G01X1235261Y508231D02*
X1235267Y508025D01*
G01X1237179Y526485D02*
X1237173Y526538D01*
G01X1237185Y526353D02*
X1237179Y526485D01*
G01X1237191Y526147D02*
X1237185Y526353D01*
G01X1239214Y507893D02*
X1239220Y507840D01*
G01X1239208Y508025D02*
X1239214Y507893D01*
G01X1239202Y508231D02*
X1239208Y508025D01*
G01X1235274Y508867D02*
X1235279Y508825D01*
G01X1235270Y508965D02*
X1235274Y508867D01*
G01X1235266Y509117D02*
X1235270Y508965D01*
G01X1237178Y525511D02*
X1237173Y525553D01*
G01X1237182Y525413D02*
X1237178Y525511D01*
G01X1237186Y525261D02*
X1237182Y525413D01*
G01X1239216Y508867D02*
X1239220Y508825D01*
G01X1239211Y508965D02*
X1239216Y508867D01*
G01X1239207Y509117D02*
X1239211Y508965D01*
G01X1237439Y508770D02*
X1237447Y508621D01*
G01X1237432Y509184D02*
X1237439Y508770D01*
G01X1237427Y509804D02*
X1237432Y509184D01*
G01X1237425Y510552D02*
X1237427Y509804D01*
G01X1238955Y525608D02*
X1238947Y525757D01*
G01X1238962Y525193D02*
X1238955Y525608D01*
G01X1238967Y524573D02*
X1238962Y525193D01*
G01X1238969Y523826D02*
X1238967Y524573D01*
G01X1237443Y524698D02*
X1237447Y524772D01*
G01X1237439Y524491D02*
X1237443Y524698D01*
G01X1237437Y524181D02*
X1237439Y524491D01*
G01X1237436Y523807D02*
X1237437Y524181D01*
G01X1238951Y509680D02*
X1238947Y509606D01*
G01X1238954Y509887D02*
X1238951Y509680D01*
G01X1238957Y510197D02*
X1238954Y509887D01*
G01X1238958Y510571D02*
X1238957Y510197D01*
G01X1238967Y509804D02*
X1238969Y510552D01*
G01X1238962Y509184D02*
X1238967Y509804D01*
G01X1238955Y508770D02*
X1238962Y509184D01*
G01X1238947Y508621D02*
X1238955Y508770D01*
G01X1231072Y508622D02*
X1231073Y508621D01*
G01X1231071Y508624D02*
X1231072Y508622D01*
G01X1231071Y508627D02*
Y508624D01*
G01X1229574Y525756D02*
X1229573Y525757D01*
G01X1229574Y525754D02*
Y525756D01*
G01X1229575Y525751D02*
X1229574Y525754D01*
G01X1238946Y508622D02*
X1238947Y508621D01*
G01X1238945Y508624D02*
X1238946Y508622D01*
G01X1238945Y508627D02*
Y508624D01*
G01X1237448Y525756D02*
X1237447Y525757D01*
G01X1237448Y525754D02*
Y525756D01*
G01X1237449Y525751D02*
X1237448Y525754D01*
G01X1231072Y509610D02*
X1231071Y509617D01*
G01X1231072Y509607D02*
Y509610D01*
G01X1231073Y509606D02*
X1231072Y509607D01*
G01X1229574Y524768D02*
X1229575Y524761D01*
G01X1229574Y524771D02*
Y524768D01*
G01X1229573Y524772D02*
X1229574Y524771D01*
G01X1238946Y509610D02*
X1238945Y509617D01*
G01X1238946Y509607D02*
Y509610D01*
G01X1238947Y509606D02*
X1238946Y509607D01*
G01X1237448Y524768D02*
X1237449Y524761D01*
G01X1237448Y524771D02*
Y524768D01*
G01X1237447Y524772D02*
X1237448Y524771D01*
G01X1231361Y507839D02*
X1231346Y507840D01*
G01X1231376Y507839D02*
X1231361D01*
G01X1231391D02*
X1231376D01*
G01X1235294D02*
X1235279Y507840D01*
G01X1235309Y507839D02*
X1235294D01*
G01X1235324D02*
X1235309D01*
G01X1239235D02*
X1239220Y507840D01*
G01X1239250Y507839D02*
X1239235D01*
G01X1239265D02*
X1239250D01*
G01X1231361Y508824D02*
X1231346Y508825D01*
G01X1231376Y508823D02*
X1231361Y508824D01*
G01X1231391Y508823D02*
X1231376D01*
G01X1239235Y508824D02*
X1239220Y508825D01*
G01X1239250Y508823D02*
X1239235Y508824D01*
G01X1239265Y508823D02*
X1239250D01*
G01X1235309D02*
X1235324D01*
G01X1235294Y508824D02*
X1235309Y508823D01*
G01X1235279Y508825D02*
X1235294Y508824D01*
G01X1237143Y508823D02*
X1237128D01*
G01X1237158Y508824D02*
X1237143Y508823D01*
G01X1237173Y508825D02*
X1237158Y508824D01*
G01X1229269Y508823D02*
X1229254D01*
G01X1229284Y508824D02*
X1229269Y508823D01*
G01X1229299Y508825D02*
X1229284Y508824D01*
G01X1239250Y525555D02*
X1239265D01*
G01X1239235Y525554D02*
X1239250Y525555D01*
G01X1239220Y525553D02*
X1239235Y525554D01*
G01X1235318Y525555D02*
X1235333D01*
G01X1235303Y525554D02*
X1235318Y525555D01*
G01X1235288Y525553D02*
X1235303Y525554D01*
G01X1231376Y525555D02*
X1231391D01*
G01X1231361Y525554D02*
X1231376Y525555D01*
G01X1231346Y525553D02*
X1231361Y525554D01*
G01X1233202Y507839D02*
X1233187D01*
G01X1233217D02*
X1233202D01*
G01X1233232Y507840D02*
X1233217Y507839D01*
G01X1229284Y526539D02*
X1229299Y526538D01*
G01X1229269Y526539D02*
X1229284D01*
G01X1229254D02*
X1229269D01*
G01X1233226D02*
X1233241Y526538D01*
G01X1233211Y526539D02*
X1233226D01*
G01X1233196D02*
X1233211D01*
G01X1237158D02*
X1237173Y526538D01*
G01X1237143Y526539D02*
X1237158D01*
G01X1237128D02*
X1237143D01*
G01X1229284Y525554D02*
X1229299Y525553D01*
G01X1229269Y525555D02*
X1229284Y525554D01*
G01X1229254Y525555D02*
X1229269D01*
G01X1233226Y525554D02*
X1233241Y525553D01*
G01X1233211Y525555D02*
X1233226Y525554D01*
G01X1233196Y525555D02*
X1233211D01*
G01X1237158Y525554D02*
X1237173Y525553D01*
G01X1237143Y525555D02*
X1237158Y525554D01*
G01X1237128Y525555D02*
X1237143D01*
G01X1231504Y530476D02*
X1229142D01*
G01X1235441D02*
X1233079D01*
G01X1239378D02*
X1237016D01*
G01X1230992Y529492D02*
X1229654D01*
G01X1238866D02*
X1237528D01*
G01X1237370Y529394D02*
X1239024D01*
G01X1229496D02*
X1231150D01*
G01X1231504Y529295D02*
X1229142D01*
G01X1235441D02*
X1233079D01*
G01X1239378D02*
X1237016D01*
G01X1231150Y528902D02*
X1229496D01*
G01X1239024D02*
X1237370D01*
G01X1231740Y528035D02*
X1228906D01*
G01X1235677D02*
X1232843D01*
G01X1239614D02*
X1236780D01*
G01X1231150Y527130D02*
X1229496D01*
G01X1239024D02*
X1237370D01*
G01Y526638D02*
X1239024D01*
G01X1229496D02*
X1231150D01*
G01X1231740Y526539D02*
X1228906D01*
G01X1235677D02*
X1232843D01*
G01X1239614D02*
X1236780D01*
G01X1239024Y526382D02*
X1239614D01*
G01X1236780D02*
X1237370D01*
G01X1235087D02*
X1235677D01*
G01X1232843D02*
X1233433D01*
G01X1231150D02*
X1231740D01*
G01X1228906D02*
X1229496D01*
G01X1237191Y526147D02*
X1239202D01*
G01X1233259D02*
X1235270D01*
G01X1229317D02*
X1231328D01*
G01X1231073Y525757D02*
X1229573D01*
G01X1235014D02*
X1233515D01*
G01X1238947D02*
X1237447D01*
G01X1237460Y525738D02*
X1238933D01*
G01X1233528D02*
X1235001D01*
G01X1229586D02*
X1231059D01*
G01X1229496Y525713D02*
X1228906D01*
G01X1231740D02*
X1231150D01*
G01X1233433D02*
X1232843D01*
G01X1235677D02*
X1235087D01*
G01X1237370D02*
X1236780D01*
G01X1239614D02*
X1239024D01*
G01X1236780Y525555D02*
X1239614D01*
G01X1232843D02*
X1235677D01*
G01X1228906D02*
X1231740D01*
G01X1235087Y525457D02*
X1233433D01*
G01X1230806Y525368D02*
X1229840D01*
G01X1234747D02*
X1233782D01*
G01X1238680D02*
X1237714D01*
G01X1232843Y525358D02*
X1233157D01*
G01X1229220D02*
X1228906D01*
G01X1231740D02*
X1231425D01*
G01X1235677D02*
X1235362D01*
G01X1237094D02*
X1236780D01*
G01X1239614D02*
X1239299D01*
G01X1231333Y525261D02*
X1229312D01*
G01X1235275D02*
X1233254D01*
G01X1239207D02*
X1237186D01*
G01X1233433Y524965D02*
X1235087D01*
G01X1231073Y524772D02*
X1229573D01*
G01X1235014D02*
X1233515D01*
G01X1238947D02*
X1237447D01*
G01X1231071Y524763D02*
X1229575D01*
G01X1235013D02*
X1233516D01*
G01X1238945D02*
X1237449D01*
G01X1237669Y524441D02*
X1238725D01*
G01X1233736D02*
X1234793D01*
G01X1229795D02*
X1230851D01*
G01X1237016Y524394D02*
X1239378D01*
G01X1233079D02*
X1235441D01*
G01X1229142D02*
X1231504D01*
G01X1239299Y523862D02*
X1239614D01*
G01X1236780D02*
X1237094D01*
G01X1235362D02*
X1235677D01*
G01X1232843D02*
X1233157D01*
G01X1231425D02*
X1231740D01*
G01X1228906D02*
X1229220D01*
G01X1237425Y523826D02*
X1238969D01*
G01X1233493D02*
X1235036D01*
G01X1229551D02*
X1231095D01*
G01X1237436Y523807D02*
X1238958D01*
G01X1233504D02*
X1235025D01*
G01X1229562D02*
X1231084D01*
G01X1233433Y523193D02*
X1235087D01*
G01Y522701D02*
X1233433D01*
G01X1234929Y522602D02*
X1233591D01*
G01Y521618D02*
X1234929D01*
G01X1231120Y520999D02*
X1229525D01*
G01X1235062D02*
X1233467D01*
G01X1238994D02*
X1237399D01*
G01X1231425Y520890D02*
X1229220D01*
G01X1235362D02*
X1233157D01*
G01X1239299D02*
X1237094D01*
G01X1231192Y520239D02*
X1229453D01*
G01X1235134D02*
X1233395D01*
G01X1239066D02*
X1237327D01*
G01X1237402Y520037D02*
X1238992D01*
G01X1233469D02*
X1235060D01*
G01X1229528D02*
X1231118D01*
G01X1237349Y520013D02*
X1239045D01*
G01X1233416D02*
X1235113D01*
G01X1229475D02*
X1231171D01*
G01X1231178Y519945D02*
X1229468D01*
G01X1235120D02*
X1233409D01*
G01X1239052D02*
X1237342D01*
G01X1237323Y519353D02*
X1239071D01*
G01X1233390D02*
X1235139D01*
G01X1229449D02*
X1231197D01*
G01X1231169Y519051D02*
X1229477D01*
G01X1235110D02*
X1233419D01*
G01X1239043D02*
X1237351D01*
G01X1231178Y518961D02*
X1229468D01*
G01X1235120D02*
X1233409D01*
G01X1239052D02*
X1237342D01*
G01X1237094Y518635D02*
X1239299D01*
G01X1233157D02*
X1235362D01*
G01X1229220D02*
X1231425D01*
G01X1237094Y518468D02*
X1239299D01*
G01X1233157D02*
X1235362D01*
G01X1229220D02*
X1231425D01*
G01Y515910D02*
X1229220D01*
G01X1235362D02*
X1233157D01*
G01X1239299D02*
X1237094D01*
G01X1231425Y515743D02*
X1229220D01*
G01X1235362D02*
X1233157D01*
G01X1239299D02*
X1237094D01*
G01X1237342Y515417D02*
X1239052D01*
G01X1233400D02*
X1235110D01*
G01X1229468D02*
X1231178D01*
G01X1237351Y515327D02*
X1239043D01*
G01X1233409D02*
X1235101D01*
G01X1229477D02*
X1231169D01*
G01X1231197Y515025D02*
X1229449D01*
G01X1235129D02*
X1233381D01*
G01X1239071D02*
X1237323D01*
G01X1237342Y514433D02*
X1239052D01*
G01X1233400D02*
X1235110D01*
G01X1229468D02*
X1231178D01*
G01X1231171Y514365D02*
X1229475D01*
G01X1235103D02*
X1233407D01*
G01X1239045D02*
X1237349D01*
G01X1231118Y514341D02*
X1229528D01*
G01X1235050D02*
X1233460D01*
G01X1238992D02*
X1237402D01*
G01X1237327Y514139D02*
X1239066D01*
G01X1233386D02*
X1235125D01*
G01X1229453D02*
X1231192D01*
G01X1237094Y513488D02*
X1239299D01*
G01X1233157D02*
X1235362D01*
G01X1229220D02*
X1231425D01*
G01X1237399Y513379D02*
X1238994D01*
G01X1233458D02*
X1235053D01*
G01X1229525D02*
X1231120D01*
G01X1234929Y512760D02*
X1233591D01*
G01X1234929Y511776D02*
X1233591D01*
G01X1233433Y511677D02*
X1235087D01*
G01Y511185D02*
X1233433D01*
G01X1231084Y510571D02*
X1229562D01*
G01X1235016D02*
X1233494D01*
G01X1238958D02*
X1237436D01*
G01X1231095Y510552D02*
X1229551D01*
G01X1235027D02*
X1233483D01*
G01X1238969D02*
X1237425D01*
G01X1229220Y510516D02*
X1228906D01*
G01X1231740D02*
X1231425D01*
G01X1233157D02*
X1232843D01*
G01X1237094D02*
X1236780D01*
G01X1235677D02*
X1235362D01*
G01X1239614D02*
X1239299D01*
G01X1231504Y509984D02*
X1229142D01*
G01X1235441D02*
X1233079D01*
G01X1239378D02*
X1237016D01*
G01X1230851Y509937D02*
X1229795D01*
G01X1234783D02*
X1233727D01*
G01X1238725D02*
X1237669D01*
G01X1237449Y509615D02*
X1238945D01*
G01X1233507D02*
X1235003D01*
G01X1229575D02*
X1231071D01*
G01X1237447Y509606D02*
X1238947D01*
G01X1233505D02*
X1235005D01*
G01X1229573D02*
X1231073D01*
G01X1235087Y509413D02*
X1233433D01*
G01X1237186Y509117D02*
X1239207D01*
G01X1233245D02*
X1235266D01*
G01X1229312D02*
X1231333D01*
G01X1235362Y509020D02*
X1235677D01*
G01X1229220D02*
X1228906D01*
G01X1231740D02*
X1231425D01*
G01X1233157D02*
X1232843D01*
G01X1237094D02*
X1236780D01*
G01X1239614D02*
X1239299D01*
G01X1237714Y509010D02*
X1238680D01*
G01X1233772D02*
X1234738D01*
G01X1229840D02*
X1230806D01*
G01X1233433Y508921D02*
X1235087D01*
G01X1236780Y508823D02*
X1239614D01*
G01X1232843D02*
X1235677D01*
G01X1228906D02*
X1231740D01*
G01X1239024Y508665D02*
X1239614D01*
G01X1236780D02*
X1237370D01*
G01X1235087D02*
X1235677D01*
G01X1232843D02*
X1233433D01*
G01X1231150D02*
X1231740D01*
G01X1228906D02*
X1229496D01*
G01X1231059Y508640D02*
X1229586D01*
G01X1234992D02*
X1233519D01*
G01X1238933D02*
X1237460D01*
G01X1237447Y508621D02*
X1238947D01*
G01X1233505D02*
X1235005D01*
G01X1229573D02*
X1231073D01*
G01X1231328Y508231D02*
X1229317D01*
G01X1235261D02*
X1233250D01*
G01X1239202D02*
X1237191D01*
G01X1229496Y507996D02*
X1228906D01*
G01X1231740D02*
X1231150D01*
G01X1233433D02*
X1232843D01*
G01X1235677D02*
X1235087D01*
G01X1237370D02*
X1236780D01*
G01X1239614D02*
X1239024D01*
G01X1231740Y507839D02*
X1228906D01*
G01X1235677D02*
X1232843D01*
G01X1239614D02*
X1236780D01*
G01X1231150Y507740D02*
X1229496D01*
G01X1239024D02*
X1237370D01*
G01Y507248D02*
X1239024D01*
G01X1229496D02*
X1231150D01*
G01X1236780Y506343D02*
X1239614D01*
G01X1232843D02*
X1235677D01*
G01X1228906D02*
X1231740D01*
G01X1237370Y505476D02*
X1239024D01*
G01X1229496D02*
X1231150D01*
G01X1237016Y505083D02*
X1239378D01*
G01X1233079D02*
X1235441D01*
G01X1229142D02*
X1231504D01*
G01X1231150Y504984D02*
X1229496D01*
G01X1239024D02*
X1237370D01*
G01X1230992Y504886D02*
X1229654D01*
G01X1238866D02*
X1237528D01*
G01X1237016Y503902D02*
X1239378D01*
G01X1233079D02*
X1235441D01*
G01X1229142D02*
X1231504D01*
G01X1237714Y525368D02*
X1237460Y525738D01*
G01X1237449Y524760D02*
X1237669Y524441D01*
G01X1233782Y525368D02*
X1233528Y525738D01*
G01X1233736Y524441D02*
X1233515Y524763D01*
G01X1229840Y525368D02*
X1229586Y525738D01*
G01X1229575Y524760D02*
X1229795Y524441D01*
G01X1238945Y509618D02*
X1238725Y509937D01*
G01X1238680Y509010D02*
X1238933Y508640D01*
G01X1234783Y509937D02*
X1235005Y509615D01*
G01X1234738Y509010D02*
X1234992Y508640D01*
G01X1231071Y509618D02*
X1230851Y509937D01*
G01X1230806Y509010D02*
X1231059Y508640D01*
G01X1237678Y524394D02*
X1237669Y524441D01*
G01X1238716Y509984D02*
X1238725Y509937D01*
G01X1233736Y524441D02*
X1233746Y524394D01*
G01X1234783Y509937D02*
X1234774Y509984D01*
G01X1229804Y524394D02*
X1229795Y524441D01*
G01X1230842Y509984D02*
X1230851Y509937D01*
G01X1238994Y513379D02*
X1239045Y514365D01*
G01X1239043Y515327D02*
X1238992Y514341D01*
G01X1239071Y519353D02*
X1239207Y525261D01*
G01X1239202Y526147D02*
X1239066Y520239D01*
G01X1237191Y508231D02*
X1237327Y514139D01*
G01X1237323Y515025D02*
X1237186Y509117D01*
G01X1238693Y509984D02*
X1238680Y509010D01*
G01X1237701Y524394D02*
X1237714Y525368D01*
G01X1239614Y523862D02*
Y528035D01*
G01Y506343D02*
Y510516D01*
G01X1239579Y508823D02*
Y507839D01*
G01X1239575Y508823D02*
Y507839D01*
G01Y526539D02*
Y525555D01*
G01X1239378Y509984D02*
Y503902D01*
G01Y530476D02*
Y524394D01*
G01X1239299Y507839D02*
Y526539D01*
G01X1239220Y508825D02*
Y507840D01*
G01Y526538D02*
Y525553D01*
G01X1239024Y525555D02*
Y530396D01*
G01Y503982D02*
Y508823D01*
G01X1238945Y524760D02*
Y525751D01*
G01Y508627D02*
Y509618D01*
G01X1238866Y504965D02*
Y503902D01*
G01Y530476D02*
Y529413D01*
G01X1238591Y503902D02*
Y504886D01*
G01Y530476D02*
Y529492D01*
G01X1237803Y504886D02*
Y503902D01*
G01Y530476D02*
Y529492D01*
G01X1237528Y504965D02*
Y503902D01*
G01Y530476D02*
Y529413D01*
G01X1237449Y509618D02*
Y508627D01*
G01Y525751D02*
Y524760D01*
G01X1237370Y525555D02*
Y530396D01*
G01Y503982D02*
Y508823D01*
G01X1237173Y507840D02*
Y508825D01*
G01Y525553D02*
Y526538D01*
G01X1237094Y526539D02*
Y507839D01*
G01X1237016Y509984D02*
Y503902D01*
G01Y530476D02*
Y524394D01*
G01X1236819Y508823D02*
Y507839D01*
G01Y526539D02*
Y525555D01*
G01X1236814Y526539D02*
Y525555D01*
G01X1236780Y510516D02*
Y506343D01*
G01Y528035D02*
Y523862D01*
G01X1235677D02*
Y528035D01*
G01Y506343D02*
Y510516D01*
G01X1235642Y526539D02*
Y525555D01*
G01X1235638Y508823D02*
Y507839D01*
G01X1235633Y508823D02*
Y507839D01*
G01X1235441Y509984D02*
Y503902D01*
G01Y530476D02*
Y524394D01*
G01X1235362Y507839D02*
Y526539D01*
G01X1235288Y526538D02*
Y525553D01*
G01X1235279Y508825D02*
Y507840D01*
G01X1238680Y525368D02*
X1238693Y524394D01*
G01X1237714Y509010D02*
X1237701Y509984D01*
G01X1234747Y525368D02*
X1234760Y524394D01*
G01X1239207Y509117D02*
X1239071Y515025D01*
G01X1239066Y514139D02*
X1239202Y508231D01*
G01X1237327Y520239D02*
X1237191Y526147D01*
G01X1237186Y525261D02*
X1237323Y519353D01*
G01X1235266Y509117D02*
X1235129Y515025D01*
G01X1235125Y514139D02*
X1235261Y508231D01*
G01X1239045Y520013D02*
X1238994Y520999D01*
G01X1238992Y520037D02*
X1239043Y519051D01*
G01X1237402Y514341D02*
X1237351Y515327D01*
G01X1237349Y514365D02*
X1237399Y513379D01*
G01X1235113Y520013D02*
X1235062Y520999D01*
G01X1235060Y520037D02*
X1235110Y519051D01*
G01X1233460Y514341D02*
X1233409Y515327D01*
G01X1233407Y514365D02*
X1233458Y513379D01*
G01X1237460Y508640D02*
X1237714Y509010D01*
G01X1237669Y509937D02*
X1237449Y509618D01*
G01X1233519Y508640D02*
X1233772Y509010D01*
G01X1233506Y509615D02*
X1233727Y509937D01*
G01X1229586Y508640D02*
X1229840Y509010D01*
G01X1229795Y509937D02*
X1229575Y509618D01*
G01X1238725Y524441D02*
X1238945Y524760D01*
G01X1238933Y525738D02*
X1238680Y525368D01*
G01X1237669Y509937D02*
X1237678Y509984D01*
G01X1238725Y524441D02*
X1238716Y524394D01*
G01X1233736Y509984D02*
X1233727Y509937D01*
G01X1234783Y524394D02*
X1234793Y524441D01*
G01X1229795Y509937D02*
X1229804Y509984D01*
G01X1230851Y524441D02*
X1230842Y524394D01*
G01X1237351Y519051D02*
X1237402Y520037D01*
G01X1237399Y520999D02*
X1237349Y520013D01*
G01X1235053Y513379D02*
X1235103Y514365D01*
G01X1235101Y515327D02*
X1235050Y514341D01*
G01X1233419Y519051D02*
X1233469Y520037D01*
G01X1233467Y520999D02*
X1233416Y520013D01*
G01X1231120Y513379D02*
X1231171Y514365D01*
G01X1231169Y515327D02*
X1231118Y514341D01*
G01X1229477Y519051D02*
X1229528Y520037D01*
G01X1229525Y520999D02*
X1229475Y520013D01*
G01X1235139Y519353D02*
X1235275Y525261D01*
G01X1235270Y526147D02*
X1235134Y520239D01*
G01X1233250Y508231D02*
X1233386Y514139D01*
G01X1233381Y515025D02*
X1233245Y509117D01*
G01X1231197Y519353D02*
X1231333Y525261D01*
G01X1231328Y526147D02*
X1231192Y520239D01*
G01X1229317Y508231D02*
X1229453Y514139D01*
G01X1229449Y515025D02*
X1229312Y509117D01*
G01X1234751Y509984D02*
X1234738Y509010D01*
G01X1233769Y524394D02*
X1233782Y525368D01*
G01X1230819Y509984D02*
X1230806Y509010D01*
G01X1229827Y524394D02*
X1229840Y525368D01*
G01X1235087Y521698D02*
Y526539D01*
G01Y507839D02*
Y512680D01*
G01X1235013Y524760D02*
Y525751D01*
G01X1235003Y508627D02*
Y509618D01*
G01X1234929Y512760D02*
Y511696D01*
G01Y522681D02*
Y521618D01*
G01X1234654D02*
Y522602D01*
G01Y512760D02*
Y511776D01*
G01X1233866Y521618D02*
Y522602D01*
G01Y512760D02*
Y511776D01*
G01X1233591Y512760D02*
Y511696D01*
G01Y522682D02*
Y521618D01*
G01X1233516Y525751D02*
Y524760D01*
G01X1233507Y509618D02*
Y508627D01*
G01X1233433Y521698D02*
Y526539D01*
G01Y507839D02*
Y512680D01*
G01X1233241Y525553D02*
Y526538D01*
G01X1233232Y507840D02*
Y508825D01*
G01X1233157Y526539D02*
Y507839D01*
G01X1233079Y509984D02*
Y503902D01*
G01Y530476D02*
Y524394D01*
G01X1232887Y526539D02*
Y525555D01*
G01X1232882Y526539D02*
Y525555D01*
G01X1232877Y508823D02*
Y507839D01*
G01X1232843Y510516D02*
Y506343D01*
G01Y528035D02*
Y523862D01*
G01X1231740D02*
Y528035D01*
G01Y506343D02*
Y510516D01*
G01X1231705Y508823D02*
Y507839D01*
G01X1231701Y508823D02*
Y507839D01*
G01Y526539D02*
Y525555D01*
G01X1231504Y509984D02*
Y503902D01*
G01Y530476D02*
Y524394D01*
G01X1231425Y507839D02*
Y526539D01*
G01X1231346Y508825D02*
Y507840D01*
G01Y526538D02*
Y525553D01*
G01X1231150Y525555D02*
Y530396D01*
G01Y503982D02*
Y508823D01*
G01X1231071Y524760D02*
Y525751D01*
G01Y508627D02*
Y509618D01*
G01X1230992Y504965D02*
Y503902D01*
G01Y530476D02*
Y529413D01*
G01X1230717Y503902D02*
Y504886D01*
G01Y530476D02*
Y529492D01*
G01X1229929Y504886D02*
Y503902D01*
G01Y530476D02*
Y529492D01*
G01X1229654Y504965D02*
Y503902D01*
G01Y530476D02*
Y529413D01*
G01X1229575Y509618D02*
Y508627D01*
G01Y525751D02*
Y524760D01*
G01X1229496Y525555D02*
Y530396D01*
G01Y503982D02*
Y508823D01*
G01X1229299Y507840D02*
Y508825D01*
G01Y525553D02*
Y526538D01*
G01X1229220Y526539D02*
Y507839D01*
G01X1229142Y509984D02*
Y503902D01*
G01Y530476D02*
Y524394D01*
G01X1228945Y508823D02*
Y507839D01*
G01Y526539D02*
Y525555D01*
G01X1228940Y526539D02*
Y525555D01*
G01X1228906Y510516D02*
Y506343D01*
G01Y528035D02*
Y523862D01*
G01X1227803D02*
Y528035D01*
G01Y506343D02*
Y510516D01*
G01X1227768Y526539D02*
Y525555D01*
G01X1227764Y508823D02*
Y507839D01*
G01X1227759Y508823D02*
Y507839D01*
G01X1233772Y509010D02*
X1233759Y509984D01*
G01X1230806Y525368D02*
X1230819Y524394D01*
G01X1229840Y509010D02*
X1229827Y509984D01*
G01X1233395Y520239D02*
X1233259Y526147D01*
G01X1233254Y525261D02*
X1233390Y519353D01*
G01X1231333Y509117D02*
X1231197Y515025D01*
G01X1231192Y514139D02*
X1231328Y508231D01*
G01X1229453Y520239D02*
X1229317Y526147D01*
G01X1229312Y525261D02*
X1229449Y519353D01*
G01X1231171Y520013D02*
X1231120Y520999D01*
G01X1231118Y520037D02*
X1231169Y519051D01*
G01X1229528Y514341D02*
X1229477Y515327D01*
G01X1229475Y514365D02*
X1229525Y513379D01*
G01X1235014Y524763D02*
X1234793Y524441D01*
G01X1235001Y525738D02*
X1234747Y525368D01*
G01X1230851Y524441D02*
X1231071Y524760D01*
G01X1231059Y525738D02*
X1230806Y525368D01*
G01X1241379Y524209D02*
X1241378Y523807D01*
G01X1241382Y524537D02*
X1241379Y524209D01*
G01X1241386Y524733D02*
X1241382Y524537D01*
G01X1241390Y524763D02*
X1241386Y524733D01*
G01X1246820Y524768D02*
X1246819Y524763D01*
G01X1246820Y524771D02*
Y524768D01*
G01X1246821Y524772D02*
X1246820Y524771D01*
G01X1245322Y509610D02*
X1245323Y509615D01*
G01X1245322Y509607D02*
Y509610D01*
G01X1245321Y509606D02*
X1245322Y509607D01*
G01X1254694Y524768D02*
X1254693Y524763D01*
G01X1254694Y524771D02*
Y524768D01*
G01X1254695Y524772D02*
X1254694Y524771D01*
G01X1246819Y525754D02*
Y525751D01*
G01X1246820Y525756D02*
X1246819Y525754D01*
G01X1246821Y525757D02*
X1246820Y525756D01*
G01X1254693Y525754D02*
Y525751D01*
G01X1254694Y525756D02*
X1254693Y525754D01*
G01X1254695Y525757D02*
X1254694Y525756D01*
G01X1245322Y508624D02*
X1245323Y508627D01*
G01X1245322Y508622D02*
Y508624D01*
G01X1245321Y508621D02*
X1245322Y508622D01*
G01X1262567Y525754D02*
Y525751D01*
G01X1262568Y525756D02*
X1262567Y525754D01*
G01X1262569Y525757D02*
X1262568Y525756D01*
G01X1253196Y508624D02*
X1253197Y508627D01*
G01X1253196Y508622D02*
Y508624D01*
G01X1253195Y508621D02*
X1253196Y508622D01*
G01X1245322Y524771D02*
X1245321Y524772D01*
G01X1245322Y524768D02*
Y524771D01*
G01X1245323Y524763D02*
X1245322Y524768D01*
G01X1246820Y509607D02*
X1246821Y509606D01*
G01X1246820Y509610D02*
Y509607D01*
G01X1246819Y509615D02*
X1246820Y509610D01*
G01X1241121Y526485D02*
X1241115Y526538D01*
G01X1241127Y526353D02*
X1241121Y526485D01*
G01X1241133Y526147D02*
X1241127Y526353D01*
G01X1243147Y507893D02*
X1243153Y507840D01*
G01X1243141Y508025D02*
X1243147Y507893D01*
G01X1243135Y508231D02*
X1243141Y508025D01*
G01X1245053Y526485D02*
X1245047Y526538D01*
G01X1245059Y526353D02*
X1245053Y526485D01*
G01X1245065Y526147D02*
X1245059Y526353D01*
G01X1247088Y507893D02*
X1247094Y507840D01*
G01X1247082Y508025D02*
X1247088Y507893D01*
G01X1247076Y508231D02*
X1247082Y508025D01*
G01X1248995Y526485D02*
X1248989Y526538D01*
G01X1249001Y526353D02*
X1248995Y526485D01*
G01X1249007Y526147D02*
X1249001Y526353D01*
G01X1251021Y507893D02*
X1251027Y507840D01*
G01X1251015Y508025D02*
X1251021Y507893D01*
G01X1251009Y508231D02*
X1251015Y508025D01*
G01X1252927Y526485D02*
X1252921Y526538D01*
G01X1252933Y526353D02*
X1252927Y526485D01*
G01X1252939Y526147D02*
X1252933Y526353D01*
G01X1254962Y507893D02*
X1254968Y507840D01*
G01X1254956Y508025D02*
X1254962Y507893D01*
G01X1254951Y508231D02*
X1254956Y508025D01*
G01X1256869Y526485D02*
X1256863Y526538D01*
G01X1256875Y526353D02*
X1256869Y526485D01*
G01X1256881Y526147D02*
X1256875Y526353D01*
G01X1241119Y525511D02*
X1241115Y525553D01*
G01X1241124Y525413D02*
X1241119Y525511D01*
G01X1241128Y525261D02*
X1241124Y525413D01*
G01X1243148Y508867D02*
X1243153Y508825D01*
G01X1243144Y508965D02*
X1243148Y508867D01*
G01X1243140Y509117D02*
X1243144Y508965D01*
G01X1245052Y525511D02*
X1245047Y525553D01*
G01X1245056Y525413D02*
X1245052Y525511D01*
G01X1245060Y525261D02*
X1245056Y525413D01*
G01X1247090Y508867D02*
X1247094Y508825D01*
G01X1247086Y508965D02*
X1247090Y508867D01*
G01X1247081Y509117D02*
X1247086Y508965D01*
G01X1248993Y525511D02*
X1248989Y525553D01*
G01X1248998Y525413D02*
X1248993Y525511D01*
G01X1249002Y525261D02*
X1248998Y525413D01*
G01X1251022Y508867D02*
X1251027Y508825D01*
G01X1251018Y508965D02*
X1251022Y508867D01*
G01X1251014Y509117D02*
X1251018Y508965D01*
G01X1252926Y525511D02*
X1252921Y525553D01*
G01X1252930Y525413D02*
X1252926Y525511D01*
G01X1252934Y525261D02*
X1252930Y525413D01*
G01X1254964Y508867D02*
X1254969Y508825D01*
G01X1254960Y508965D02*
X1254964Y508867D01*
G01X1254955Y509117D02*
X1254960Y508965D01*
G01X1256867Y525511D02*
X1256863Y525553D01*
G01X1256872Y525413D02*
X1256867Y525511D01*
G01X1256876Y525261D02*
X1256872Y525413D01*
G01X1241376Y509645D02*
X1241381Y509615D01*
G01X1241372Y509841D02*
X1241376Y509645D01*
G01X1241370Y510169D02*
X1241372Y509841D01*
G01X1241368Y510571D02*
X1241370Y510169D01*
G01X1242891Y524733D02*
X1242887Y524763D01*
G01X1242895Y524537D02*
X1242891Y524733D01*
G01X1242898Y524209D02*
X1242895Y524537D01*
G01X1242899Y523807D02*
X1242898Y524209D01*
G01X1249250Y509645D02*
X1249255Y509615D01*
G01X1249246Y509841D02*
X1249250Y509645D01*
G01X1249244Y510169D02*
X1249246Y509841D01*
G01X1249242Y510571D02*
X1249244Y510169D01*
G01X1250765Y524733D02*
X1250761Y524763D01*
G01X1250769Y524537D02*
X1250765Y524733D01*
G01X1250772Y524209D02*
X1250769Y524537D01*
G01X1250773Y523807D02*
X1250772Y524209D01*
G01X1257124Y509645D02*
X1257129Y509615D01*
G01X1257120Y509841D02*
X1257124Y509645D01*
G01X1257118Y510169D02*
X1257120Y509841D01*
G01X1257117Y510571D02*
X1257118Y510169D01*
G01X1258639Y524733D02*
X1258635Y524763D01*
G01X1258643Y524537D02*
X1258639Y524733D01*
G01X1258646Y524209D02*
X1258643Y524537D01*
G01X1258647Y523807D02*
X1258646Y524209D01*
G01X1245313Y508770D02*
X1245321Y508621D01*
G01X1245306Y509184D02*
X1245313Y508770D01*
G01X1245301Y509804D02*
X1245306Y509184D01*
G01X1245299Y510552D02*
X1245301Y509804D01*
G01X1245317Y509679D02*
X1245321Y509606D01*
G01X1245313Y509887D02*
X1245317Y509679D01*
G01X1245311Y510200D02*
X1245313Y509887D01*
G01X1245310Y510571D02*
X1245311Y510200D01*
G01X1246825Y524699D02*
X1246821Y524772D01*
G01X1246828Y524491D02*
X1246825Y524699D01*
G01X1246831Y524178D02*
X1246828Y524491D01*
G01X1246832Y523807D02*
X1246831Y524178D01*
G01X1246829Y525608D02*
X1246821Y525757D01*
G01X1246836Y525193D02*
X1246829Y525608D01*
G01X1246841Y524573D02*
X1246836Y525193D01*
G01X1246843Y523826D02*
X1246841Y524573D01*
G01X1253187Y508770D02*
X1253195Y508621D01*
G01X1253180Y509184D02*
X1253187Y508770D01*
G01X1253175Y509804D02*
X1253180Y509184D01*
G01X1253173Y510552D02*
X1253175Y509804D01*
G01X1253191Y509679D02*
X1253195Y509606D01*
G01X1253187Y509887D02*
X1253191Y509679D01*
G01X1253185Y510200D02*
X1253187Y509887D01*
G01X1253184Y510571D02*
X1253185Y510200D01*
G01X1254699Y524699D02*
X1254695Y524772D01*
G01X1254702Y524491D02*
X1254699Y524699D01*
G01X1254705Y524178D02*
X1254702Y524491D01*
G01X1254706Y523807D02*
X1254705Y524178D01*
G01X1254703Y525608D02*
X1254695Y525757D01*
G01X1254710Y525193D02*
X1254703Y525608D01*
G01X1254715Y524573D02*
X1254710Y525193D01*
G01X1254717Y523826D02*
X1254715Y524573D01*
G01X1245301D02*
X1245299Y523826D01*
G01X1245306Y525193D02*
X1245301Y524573D01*
G01X1245313Y525608D02*
X1245306Y525193D01*
G01X1245321Y525757D02*
X1245313Y525608D01*
G01X1246841Y509804D02*
X1246843Y510552D01*
G01X1246836Y509184D02*
X1246841Y509804D01*
G01X1246829Y508770D02*
X1246836Y509184D01*
G01X1246821Y508621D02*
X1246829Y508770D01*
G01X1253175Y524573D02*
X1253173Y523826D01*
G01X1253180Y525193D02*
X1253175Y524573D01*
G01X1253187Y525608D02*
X1253180Y525193D01*
G01X1253195Y525757D02*
X1253187Y525608D01*
G01X1254715Y509804D02*
X1254717Y510552D01*
G01X1254710Y509184D02*
X1254715Y509804D01*
G01X1254703Y508770D02*
X1254710Y509184D01*
G01X1254695Y508621D02*
X1254703Y508770D01*
G01X1261049Y524573D02*
X1261047Y523826D01*
G01X1261054Y525193D02*
X1261049Y524573D01*
G01X1261061Y525608D02*
X1261054Y525193D01*
G01X1261069Y525757D02*
X1261061Y525608D01*
G01X1245311Y524178D02*
X1245310Y523807D01*
G01X1245313Y524491D02*
X1245311Y524178D01*
G01X1245317Y524699D02*
X1245313Y524491D01*
G01X1245321Y524772D02*
X1245317Y524699D01*
G01X1246831Y510200D02*
X1246832Y510571D01*
G01X1246828Y509887D02*
X1246831Y510200D01*
G01X1246825Y509679D02*
X1246828Y509887D01*
G01X1246821Y509606D02*
X1246825Y509679D01*
G01X1253185Y524178D02*
X1253184Y523807D01*
G01X1253187Y524491D02*
X1253185Y524178D01*
G01X1253191Y524699D02*
X1253187Y524491D01*
G01X1253195Y524772D02*
X1253191Y524699D01*
G01X1254705Y510200D02*
X1254706Y510571D01*
G01X1254702Y509887D02*
X1254705Y510200D01*
G01X1254699Y509679D02*
X1254702Y509887D01*
G01X1254695Y509606D02*
X1254699Y509679D01*
G01X1261059Y524178D02*
X1261058Y523807D01*
G01X1261061Y524491D02*
X1261059Y524178D01*
G01X1261065Y524699D02*
X1261061Y524491D01*
G01X1261069Y524772D02*
X1261065Y524699D01*
G01X1241115Y508965D02*
X1241119Y509117D01*
G01X1241110Y508867D02*
X1241115Y508965D01*
G01X1241106Y508825D02*
X1241110Y508867D01*
G01X1243153Y525413D02*
X1243149Y525261D01*
G01X1243158Y525511D02*
X1243153Y525413D01*
G01X1243162Y525553D02*
X1243158Y525511D01*
G01X1245056Y508965D02*
X1245060Y509117D01*
G01X1245052Y508867D02*
X1245056Y508965D01*
G01X1245047Y508825D02*
X1245052Y508867D01*
G01X1247086Y525413D02*
X1247081Y525261D01*
G01X1247090Y525511D02*
X1247086Y525413D01*
G01X1247094Y525553D02*
X1247090Y525511D01*
G01X1248989Y508965D02*
X1248993Y509117D01*
G01X1248984Y508867D02*
X1248989Y508965D01*
G01X1248980Y508825D02*
X1248984Y508867D01*
G01X1251027Y525413D02*
X1251023Y525261D01*
G01X1251032Y525511D02*
X1251027Y525413D01*
G01X1251036Y525553D02*
X1251032Y525511D01*
G01X1252930Y508965D02*
X1252934Y509117D01*
G01X1252926Y508867D02*
X1252930Y508965D01*
G01X1252921Y508825D02*
X1252926Y508867D01*
G01X1254960Y525413D02*
X1254955Y525261D01*
G01X1254964Y525511D02*
X1254960Y525413D01*
G01X1254968Y525553D02*
X1254964Y525511D01*
G01X1256863Y508965D02*
X1256867Y509117D01*
G01X1256858Y508867D02*
X1256863Y508965D01*
G01X1256854Y508825D02*
X1256858Y508867D01*
G01X1258901Y525413D02*
X1258897Y525261D01*
G01X1258906Y525511D02*
X1258901Y525413D01*
G01X1258910Y525553D02*
X1258906Y525511D01*
G01X1260804Y508965D02*
X1260808Y509117D01*
G01X1260800Y508867D02*
X1260804Y508965D01*
G01X1260795Y508825D02*
X1260800Y508867D01*
G01X1262834Y525413D02*
X1262829Y525261D01*
G01X1262838Y525511D02*
X1262834Y525413D01*
G01X1262843Y525553D02*
X1262838Y525511D01*
G01X1264737Y508965D02*
X1264741Y509117D01*
G01X1264732Y508867D02*
X1264737Y508965D01*
G01X1264728Y508825D02*
X1264732Y508867D01*
G01X1243150Y526353D02*
X1243144Y526147D01*
G01X1243156Y526485D02*
X1243150Y526353D01*
G01X1243162Y526538D02*
X1243156Y526485D01*
G01X1241118Y508025D02*
X1241124Y508231D01*
G01X1241112Y507893D02*
X1241118Y508025D01*
G01X1241106Y507840D02*
X1241112Y507893D01*
G01X1247082Y526353D02*
X1247076Y526147D01*
G01X1247088Y526485D02*
X1247082Y526353D01*
G01X1247094Y526538D02*
X1247088Y526485D01*
G01X1245059Y508025D02*
X1245065Y508231D01*
G01X1245053Y507893D02*
X1245059Y508025D01*
G01X1245047Y507840D02*
X1245053Y507893D01*
G01X1251024Y526353D02*
X1251018Y526147D01*
G01X1251030Y526485D02*
X1251024Y526353D01*
G01X1251036Y526538D02*
X1251030Y526485D01*
G01X1248992Y508025D02*
X1248998Y508231D01*
G01X1248986Y507893D02*
X1248992Y508025D01*
G01X1248980Y507840D02*
X1248986Y507893D01*
G01X1254956Y526353D02*
X1254951Y526147D01*
G01X1254962Y526485D02*
X1254956Y526353D01*
G01X1254968Y526538D02*
X1254962Y526485D01*
G01X1252933Y508025D02*
X1252939Y508231D01*
G01X1252927Y507893D02*
X1252933Y508025D01*
G01X1252921Y507840D02*
X1252927Y507893D01*
G01X1258898Y526353D02*
X1258892Y526147D01*
G01X1258904Y526485D02*
X1258898Y526353D01*
G01X1258910Y526538D02*
X1258904Y526485D01*
G01X1256866Y508025D02*
X1256872Y508231D01*
G01X1256860Y507893D02*
X1256866Y508025D01*
G01X1256854Y507840D02*
X1256860Y507893D01*
G01X1262830Y526353D02*
X1262825Y526147D01*
G01X1262836Y526485D02*
X1262830Y526353D01*
G01X1262843Y526538D02*
X1262836Y526485D01*
G01X1260807Y508025D02*
X1260813Y508231D01*
G01X1260801Y507893D02*
X1260807Y508025D01*
G01X1260795Y507840D02*
X1260801Y507893D01*
G01X1266772Y526353D02*
X1266766Y526147D01*
G01X1266778Y526485D02*
X1266772Y526353D01*
G01X1266784Y526538D02*
X1266778Y526485D01*
G01X1264740Y508025D02*
X1264746Y508231D01*
G01X1264734Y507893D02*
X1264740Y508025D01*
G01X1264728Y507840D02*
X1264734Y507893D01*
G01X1242889Y510169D02*
X1242890Y510571D01*
G01X1242886Y509841D02*
X1242889Y510169D01*
G01X1242882Y509645D02*
X1242886Y509841D01*
G01X1242877Y509615D02*
X1242882Y509645D01*
G01X1249253Y524209D02*
X1249252Y523807D01*
G01X1249256Y524537D02*
X1249253Y524209D01*
G01X1249260Y524733D02*
X1249256Y524537D01*
G01X1249264Y524763D02*
X1249260Y524733D01*
G01X1250763Y510169D02*
X1250764Y510571D01*
G01X1250760Y509841D02*
X1250763Y510169D01*
G01X1250756Y509645D02*
X1250760Y509841D01*
G01X1250751Y509615D02*
X1250756Y509645D01*
G01X1257127Y524209D02*
X1257126Y523807D01*
G01X1257130Y524537D02*
X1257127Y524209D01*
G01X1257134Y524733D02*
X1257130Y524537D01*
G01X1257138Y524763D02*
X1257134Y524733D01*
G01X1258637Y510169D02*
X1258638Y510571D01*
G01X1258634Y509841D02*
X1258637Y510169D01*
G01X1258630Y509645D02*
X1258634Y509841D01*
G01X1258625Y509615D02*
X1258630Y509645D01*
G01X1265001Y524209D02*
X1265000Y523807D01*
G01X1265004Y524537D02*
X1265001Y524209D01*
G01X1265008Y524733D02*
X1265004Y524537D01*
G01X1265012Y524763D02*
X1265008Y524733D01*
G01X1266511Y510169D02*
X1266512Y510571D01*
G01X1266508Y509841D02*
X1266511Y510169D01*
G01X1266504Y509645D02*
X1266508Y509841D01*
G01X1266499Y509615D02*
X1266504Y509645D01*
G01X1253196Y509610D02*
X1253197Y509615D01*
G01X1253196Y509607D02*
Y509610D01*
G01X1253195Y509606D02*
X1253196Y509607D01*
G01X1262568Y524768D02*
X1262567Y524763D01*
G01X1262568Y524771D02*
Y524768D01*
G01X1262569Y524772D02*
X1262568Y524771D01*
G01X1261070Y509610D02*
X1261071Y509615D01*
G01X1261070Y509607D02*
Y509610D01*
G01X1261069Y509606D02*
X1261070Y509607D01*
G01X1270442Y524768D02*
X1270441Y524763D01*
G01X1270442Y524771D02*
Y524768D01*
G01X1270443Y524772D02*
X1270442Y524771D01*
G01X1268944Y509610D02*
X1268945Y509615D01*
G01X1268944Y509607D02*
Y509610D01*
G01X1268943Y509606D02*
X1268944Y509607D01*
G01X1278316Y524768D02*
X1278315Y524763D01*
G01X1278316Y524771D02*
Y524768D01*
G01X1278317Y524772D02*
X1278316Y524771D01*
G01X1276818Y509610D02*
X1276819Y509615D01*
G01X1276818Y509607D02*
Y509610D01*
G01X1276817Y509606D02*
X1276818Y509607D01*
G01X1286190Y524768D02*
X1286189Y524763D01*
G01X1286190Y524771D02*
Y524768D01*
G01X1286191Y524772D02*
X1286190Y524771D01*
G01X1270442Y525754D02*
X1270441Y525751D01*
G01X1270442Y525756D02*
Y525754D01*
G01X1270443Y525757D02*
X1270442Y525756D01*
G01X1261070Y508624D02*
X1261071Y508627D01*
G01X1261070Y508622D02*
Y508624D01*
G01X1261069Y508621D02*
X1261070Y508622D01*
G01X1278316Y525754D02*
X1278315Y525751D01*
G01X1278316Y525756D02*
Y525754D01*
G01X1278317Y525757D02*
X1278316Y525756D01*
G01X1268944Y508624D02*
X1268945Y508627D01*
G01X1268944Y508622D02*
Y508624D01*
G01X1268943Y508621D02*
X1268944Y508622D01*
G01X1286190Y525754D02*
X1286189Y525751D01*
G01X1286190Y525756D02*
Y525754D01*
G01X1286191Y525757D02*
X1286190Y525756D01*
G01X1276818Y508624D02*
X1276819Y508627D01*
G01X1276818Y508622D02*
Y508624D01*
G01X1276817Y508621D02*
X1276818Y508622D01*
G01X1294064Y525754D02*
X1294063Y525751D01*
G01X1294064Y525756D02*
Y525754D01*
G01X1294065Y525757D02*
X1294064Y525756D01*
G01X1284692Y508624D02*
X1284693Y508627D01*
G01X1284692Y508622D02*
Y508624D01*
G01X1284691Y508621D02*
X1284692Y508622D01*
G01X1301938Y525754D02*
X1301937Y525751D01*
G01X1301938Y525756D02*
Y525754D01*
G01X1301939Y525757D02*
X1301938Y525756D01*
G01X1246820Y508622D02*
X1246821Y508621D01*
G01X1246819Y508624D02*
X1246820Y508622D01*
G01X1246819Y508627D02*
Y508624D01*
G01X1245322Y525756D02*
X1245321Y525757D01*
G01X1245322Y525754D02*
Y525756D01*
G01X1245323Y525751D02*
X1245322Y525754D01*
G01X1253196Y524771D02*
X1253195Y524772D01*
G01X1253196Y524768D02*
Y524771D01*
G01X1253197Y524763D02*
X1253196Y524768D01*
G01X1254694Y509607D02*
X1254695Y509606D01*
G01X1254694Y509610D02*
Y509607D01*
G01X1254693Y509615D02*
X1254694Y509610D01*
G01X1261070Y524771D02*
X1261069Y524772D01*
G01X1261070Y524768D02*
Y524771D01*
G01X1261071Y524763D02*
X1261070Y524768D01*
G01X1262568Y509607D02*
X1262569Y509606D01*
G01X1262568Y509610D02*
Y509607D01*
G01X1262567Y509615D02*
X1262568Y509610D01*
G01X1268944Y524771D02*
X1268943Y524772D01*
G01X1268944Y524768D02*
Y524771D01*
G01X1268945Y524763D02*
X1268944Y524768D01*
G01X1270442Y509607D02*
X1270443Y509606D01*
G01X1270442Y509610D02*
Y509607D01*
G01X1270441Y509615D02*
X1270442Y509610D01*
G01X1276818Y524771D02*
X1276817Y524772D01*
G01X1276818Y524768D02*
Y524771D01*
G01X1276819Y524763D02*
X1276818Y524768D01*
G01X1278316Y509607D02*
X1278317Y509606D01*
G01X1278316Y509610D02*
Y509607D01*
G01X1278315Y509615D02*
X1278316Y509610D01*
G01X1258895Y507893D02*
X1258901Y507840D01*
G01X1258889Y508025D02*
X1258895Y507893D01*
G01X1258883Y508231D02*
X1258889Y508025D01*
G01X1260801Y526485D02*
X1260795Y526538D01*
G01X1260807Y526353D02*
X1260801Y526485D01*
G01X1260813Y526147D02*
X1260807Y526353D01*
G01X1262836Y507893D02*
X1262843Y507840D01*
G01X1262830Y508025D02*
X1262836Y507893D01*
G01X1262825Y508231D02*
X1262830Y508025D01*
G01X1264743Y526485D02*
X1264737Y526538D01*
G01X1264749Y526353D02*
X1264743Y526485D01*
G01X1264755Y526147D02*
X1264749Y526353D01*
G01X1266769Y507893D02*
X1266775Y507840D01*
G01X1266763Y508025D02*
X1266769Y507893D01*
G01X1266757Y508231D02*
X1266763Y508025D01*
G01X1268675Y526485D02*
X1268669Y526538D01*
G01X1268682Y526353D02*
X1268675Y526485D01*
G01X1268687Y526147D02*
X1268682Y526353D01*
G01X1270710Y507893D02*
X1270717Y507840D01*
G01X1270704Y508025D02*
X1270710Y507893D01*
G01X1270699Y508231D02*
X1270704Y508025D01*
G01X1272617Y526485D02*
X1272611Y526538D01*
G01X1272623Y526353D02*
X1272617Y526485D01*
G01X1272629Y526147D02*
X1272623Y526353D01*
G01X1274643Y507893D02*
X1274649Y507840D01*
G01X1274637Y508025D02*
X1274643Y507893D01*
G01X1274631Y508231D02*
X1274637Y508025D01*
G01X1276549Y526485D02*
X1276543Y526538D01*
G01X1276556Y526353D02*
X1276549Y526485D01*
G01X1276561Y526147D02*
X1276556Y526353D01*
G01X1278584Y507893D02*
X1278591Y507840D01*
G01X1278578Y508025D02*
X1278584Y507893D01*
G01X1278573Y508231D02*
X1278578Y508025D01*
G01X1280491Y526485D02*
X1280485Y526538D01*
G01X1280497Y526353D02*
X1280491Y526485D01*
G01X1280503Y526147D02*
X1280497Y526353D01*
G01X1282517Y507893D02*
X1282523Y507840D01*
G01X1282511Y508025D02*
X1282517Y507893D01*
G01X1282505Y508231D02*
X1282511Y508025D01*
G01X1258896Y508867D02*
X1258901Y508825D01*
G01X1258892Y508965D02*
X1258896Y508867D01*
G01X1258888Y509117D02*
X1258892Y508965D01*
G01X1260800Y525511D02*
X1260795Y525553D01*
G01X1260804Y525413D02*
X1260800Y525511D01*
G01X1260808Y525261D02*
X1260804Y525413D01*
G01X1262838Y508867D02*
X1262843Y508825D01*
G01X1262834Y508965D02*
X1262838Y508867D01*
G01X1262829Y509117D02*
X1262834Y508965D01*
G01X1264741Y525511D02*
X1264737Y525553D01*
G01X1264746Y525413D02*
X1264741Y525511D01*
G01X1264750Y525261D02*
X1264746Y525413D01*
G01X1266770Y508867D02*
X1266775Y508825D01*
G01X1266766Y508965D02*
X1266770Y508867D01*
G01X1266762Y509117D02*
X1266766Y508965D01*
G01X1268674Y525511D02*
X1268669Y525553D01*
G01X1268678Y525413D02*
X1268674Y525511D01*
G01X1268682Y525261D02*
X1268678Y525413D01*
G01X1270712Y508867D02*
X1270717Y508825D01*
G01X1270708Y508965D02*
X1270712Y508867D01*
G01X1270703Y509117D02*
X1270708Y508965D01*
G01X1272616Y525511D02*
X1272611Y525553D01*
G01X1272620Y525413D02*
X1272616Y525511D01*
G01X1272624Y525261D02*
X1272620Y525413D01*
G01X1274644Y508867D02*
X1274649Y508825D01*
G01X1274640Y508965D02*
X1274644Y508867D01*
G01X1274636Y509117D02*
X1274640Y508965D01*
G01X1276548Y525511D02*
X1276543Y525553D01*
G01X1276552Y525413D02*
X1276548Y525511D01*
G01X1276557Y525261D02*
X1276552Y525413D01*
G01X1278586Y508867D02*
X1278591Y508825D01*
G01X1278582Y508965D02*
X1278586Y508867D01*
G01X1278577Y509117D02*
X1278582Y508965D01*
G01X1280490Y525511D02*
X1280485Y525553D01*
G01X1280494Y525413D02*
X1280490Y525511D01*
G01X1280498Y525261D02*
X1280494Y525413D01*
G01X1282518Y508867D02*
X1282523Y508825D01*
G01X1282514Y508965D02*
X1282518Y508867D01*
G01X1282510Y509117D02*
X1282514Y508965D01*
G01X1264998Y509645D02*
X1265003Y509615D01*
G01X1264994Y509841D02*
X1264998Y509645D01*
G01X1264992Y510169D02*
X1264994Y509841D01*
G01X1264991Y510571D02*
X1264992Y510169D01*
G01X1266513Y524733D02*
X1266509Y524763D01*
G01X1266517Y524537D02*
X1266513Y524733D01*
G01X1266520Y524209D02*
X1266517Y524537D01*
G01X1266521Y523807D02*
X1266520Y524209D01*
G01X1272872Y509645D02*
X1272877Y509615D01*
G01X1272868Y509841D02*
X1272872Y509645D01*
G01X1272866Y510169D02*
X1272868Y509841D01*
G01X1272865Y510571D02*
X1272866Y510169D01*
G01X1274387Y524733D02*
X1274383Y524763D01*
G01X1274391Y524537D02*
X1274387Y524733D01*
G01X1274394Y524209D02*
X1274391Y524537D01*
G01X1274395Y523807D02*
X1274394Y524209D01*
G01X1280746Y509645D02*
X1280751Y509615D01*
G01X1280742Y509841D02*
X1280746Y509645D01*
G01X1280740Y510169D02*
X1280742Y509841D01*
G01X1280739Y510571D02*
X1280740Y510169D01*
G01X1282261Y524733D02*
X1282257Y524763D01*
G01X1282265Y524537D02*
X1282261Y524733D01*
G01X1282268Y524209D02*
X1282265Y524537D01*
G01X1282269Y523807D02*
X1282268Y524209D01*
G01X1261061Y508770D02*
X1261069Y508621D01*
G01X1261054Y509184D02*
X1261061Y508770D01*
G01X1261049Y509804D02*
X1261054Y509184D01*
G01X1261047Y510552D02*
X1261049Y509804D01*
G01X1261065Y509679D02*
X1261069Y509606D01*
G01X1261061Y509887D02*
X1261065Y509679D01*
G01X1261059Y510200D02*
X1261061Y509887D01*
G01X1261058Y510571D02*
X1261059Y510200D01*
G01X1262573Y524699D02*
X1262569Y524772D01*
G01X1262576Y524491D02*
X1262573Y524699D01*
G01X1262579Y524178D02*
X1262576Y524491D01*
G01X1262580Y523807D02*
X1262579Y524178D01*
G01X1262577Y525608D02*
X1262569Y525757D01*
G01X1262584Y525193D02*
X1262577Y525608D01*
G01X1262589Y524573D02*
X1262584Y525193D01*
G01X1262591Y523826D02*
X1262589Y524573D01*
G01X1268935Y508770D02*
X1268943Y508621D01*
G01X1268928Y509184D02*
X1268935Y508770D01*
G01X1268923Y509804D02*
X1268928Y509184D01*
G01X1268921Y510552D02*
X1268923Y509804D01*
G01X1268939Y509679D02*
X1268943Y509606D01*
G01X1268935Y509887D02*
X1268939Y509679D01*
G01X1268933Y510200D02*
X1268935Y509887D01*
G01X1268932Y510571D02*
X1268933Y510200D01*
G01X1270447Y524699D02*
X1270443Y524772D01*
G01X1270450Y524491D02*
X1270447Y524699D01*
G01X1270453Y524178D02*
X1270450Y524491D01*
G01X1270454Y523807D02*
X1270453Y524178D01*
G01X1270451Y525608D02*
X1270443Y525757D01*
G01X1270458Y525193D02*
X1270451Y525608D01*
G01X1270463Y524573D02*
X1270458Y525193D01*
G01X1270465Y523826D02*
X1270463Y524573D01*
G01X1276809Y508770D02*
X1276817Y508621D01*
G01X1276802Y509184D02*
X1276809Y508770D01*
G01X1276797Y509804D02*
X1276802Y509184D01*
G01X1276795Y510552D02*
X1276797Y509804D01*
G01X1276813Y509679D02*
X1276817Y509606D01*
G01X1276810Y509887D02*
X1276813Y509679D01*
G01X1276807Y510200D02*
X1276810Y509887D01*
G01X1276806Y510571D02*
X1276807Y510200D01*
G01X1278321Y524699D02*
X1278317Y524772D01*
G01X1278324Y524491D02*
X1278321Y524699D01*
G01X1278327Y524178D02*
X1278324Y524491D01*
G01X1278328Y523807D02*
X1278327Y524178D01*
G01X1278325Y525608D02*
X1278317Y525757D01*
G01X1278332Y525193D02*
X1278325Y525608D01*
G01X1278337Y524573D02*
X1278332Y525193D01*
G01X1278339Y523826D02*
X1278337Y524573D01*
G01X1262589Y509804D02*
X1262591Y510552D01*
G01X1262584Y509184D02*
X1262589Y509804D01*
G01X1262577Y508770D02*
X1262584Y509184D01*
G01X1262569Y508621D02*
X1262577Y508770D01*
G01X1268923Y524573D02*
X1268921Y523826D01*
G01X1268928Y525193D02*
X1268923Y524573D01*
G01X1268935Y525608D02*
X1268928Y525193D01*
G01X1268943Y525757D02*
X1268935Y525608D01*
G01X1270463Y509804D02*
X1270465Y510552D01*
G01X1270458Y509184D02*
X1270463Y509804D01*
G01X1270451Y508770D02*
X1270458Y509184D01*
G01X1270443Y508621D02*
X1270451Y508770D01*
G01X1276797Y524573D02*
X1276795Y523826D01*
G01X1276802Y525193D02*
X1276797Y524573D01*
G01X1276809Y525608D02*
X1276802Y525193D01*
G01X1276817Y525757D02*
X1276809Y525608D01*
G01X1278337Y509804D02*
X1278339Y510552D01*
G01X1278332Y509184D02*
X1278337Y509804D01*
G01X1278325Y508770D02*
X1278332Y509184D01*
G01X1278317Y508621D02*
X1278325Y508770D01*
G01X1284671Y524573D02*
X1284669Y523826D01*
G01X1284676Y525193D02*
X1284671Y524573D01*
G01X1284683Y525608D02*
X1284676Y525193D01*
G01X1284691Y525757D02*
X1284683Y525608D01*
G01X1286211Y509804D02*
X1286213Y510552D01*
G01X1286206Y509184D02*
X1286211Y509804D01*
G01X1286199Y508770D02*
X1286206Y509184D01*
G01X1286191Y508621D02*
X1286199Y508770D01*
G01X1262579Y510200D02*
X1262580Y510571D01*
G01X1262576Y509887D02*
X1262579Y510200D01*
G01X1262573Y509679D02*
X1262576Y509887D01*
G01X1262569Y509606D02*
X1262573Y509679D01*
G01X1268933Y524178D02*
X1268932Y523807D01*
G01X1268935Y524491D02*
X1268933Y524178D01*
G01X1268939Y524699D02*
X1268935Y524491D01*
G01X1268943Y524772D02*
X1268939Y524699D01*
G01X1270453Y510200D02*
X1270454Y510571D01*
G01X1270450Y509887D02*
X1270453Y510200D01*
G01X1270447Y509679D02*
X1270450Y509887D01*
G01X1270443Y509606D02*
X1270447Y509679D01*
G01X1276807Y524178D02*
X1276806Y523807D01*
G01X1276810Y524491D02*
X1276807Y524178D01*
G01X1276813Y524699D02*
X1276810Y524491D01*
G01X1276817Y524772D02*
X1276813Y524699D01*
G01X1278327Y510200D02*
X1278328Y510571D01*
G01X1278324Y509887D02*
X1278327Y510200D01*
G01X1278321Y509679D02*
X1278324Y509887D01*
G01X1278317Y509606D02*
X1278321Y509679D01*
G01X1284681Y524178D02*
X1284680Y523807D01*
G01X1284684Y524491D02*
X1284681Y524178D01*
G01X1284687Y524699D02*
X1284684Y524491D01*
G01X1284691Y524772D02*
X1284687Y524699D01*
G01X1286201Y510200D02*
X1286202Y510571D01*
G01X1286198Y509887D02*
X1286201Y510200D01*
G01X1286195Y509679D02*
X1286198Y509887D01*
G01X1286191Y509606D02*
X1286195Y509679D01*
G01X1266775Y525413D02*
X1266771Y525261D01*
G01X1266780Y525511D02*
X1266775Y525413D01*
G01X1266784Y525553D02*
X1266780Y525511D01*
G01X1268678Y508965D02*
X1268682Y509117D01*
G01X1268674Y508867D02*
X1268678Y508965D01*
G01X1268669Y508825D02*
X1268674Y508867D01*
G01X1270708Y525413D02*
X1270703Y525261D01*
G01X1270712Y525511D02*
X1270708Y525413D01*
G01X1270717Y525553D02*
X1270712Y525511D01*
G01X1272611Y508965D02*
X1272615Y509117D01*
G01X1272606Y508867D02*
X1272611Y508965D01*
G01X1272602Y508825D02*
X1272606Y508867D01*
G01X1274649Y525413D02*
X1274645Y525261D01*
G01X1274654Y525511D02*
X1274649Y525413D01*
G01X1274658Y525553D02*
X1274654Y525511D01*
G01X1276552Y508965D02*
X1276557Y509117D01*
G01X1276548Y508867D02*
X1276552Y508965D01*
G01X1276543Y508825D02*
X1276548Y508867D01*
G01X1278582Y525413D02*
X1278577Y525261D01*
G01X1278586Y525511D02*
X1278582Y525413D01*
G01X1278591Y525553D02*
X1278586Y525511D01*
G01X1280485Y508965D02*
X1280489Y509117D01*
G01X1280480Y508867D02*
X1280485Y508965D01*
G01X1280476Y508825D02*
X1280480Y508867D01*
G01X1282523Y525413D02*
X1282519Y525261D01*
G01X1282528Y525511D02*
X1282523Y525413D01*
G01X1282532Y525553D02*
X1282528Y525511D01*
G01X1284426Y508965D02*
X1284431Y509117D01*
G01X1284422Y508867D02*
X1284426Y508965D01*
G01X1284417Y508825D02*
X1284422Y508867D01*
G01X1286456Y525413D02*
X1286451Y525261D01*
G01X1286460Y525511D02*
X1286456Y525413D01*
G01X1286465Y525553D02*
X1286460Y525511D01*
G01X1288359Y508965D02*
X1288363Y509117D01*
G01X1288354Y508867D02*
X1288359Y508965D01*
G01X1288350Y508825D02*
X1288354Y508867D01*
G01X1290397Y525413D02*
X1290393Y525261D01*
G01X1290402Y525511D02*
X1290397Y525413D01*
G01X1290406Y525553D02*
X1290402Y525511D01*
G01X1270704Y526353D02*
X1270699Y526147D01*
G01X1270710Y526485D02*
X1270704Y526353D01*
G01X1270717Y526538D02*
X1270710Y526485D01*
G01X1268682Y508025D02*
X1268687Y508231D01*
G01X1268675Y507893D02*
X1268682Y508025D01*
G01X1268669Y507840D02*
X1268675Y507893D01*
G01X1274646Y526353D02*
X1274640Y526147D01*
G01X1274652Y526485D02*
X1274646Y526353D01*
G01X1274658Y526538D02*
X1274652Y526485D01*
G01X1272614Y508025D02*
X1272620Y508231D01*
G01X1272608Y507893D02*
X1272614Y508025D01*
G01X1272602Y507840D02*
X1272608Y507893D01*
G01X1278578Y526353D02*
X1278573Y526147D01*
G01X1278584Y526485D02*
X1278578Y526353D01*
G01X1278591Y526538D02*
X1278584Y526485D01*
G01X1276556Y508025D02*
X1276561Y508231D01*
G01X1276549Y507893D02*
X1276556Y508025D01*
G01X1276543Y507840D02*
X1276549Y507893D01*
G01X1282520Y526353D02*
X1282514Y526147D01*
G01X1282526Y526485D02*
X1282520Y526353D01*
G01X1282532Y526538D02*
X1282526Y526485D01*
G01X1280488Y508025D02*
X1280494Y508231D01*
G01X1280482Y507893D02*
X1280488Y508025D01*
G01X1280476Y507840D02*
X1280482Y507893D01*
G01X1286452Y526353D02*
X1286447Y526147D01*
G01X1286458Y526485D02*
X1286452Y526353D01*
G01X1286465Y526538D02*
X1286458Y526485D01*
G01X1284430Y508025D02*
X1284435Y508231D01*
G01X1284424Y507893D02*
X1284430Y508025D01*
G01X1284417Y507840D02*
X1284424Y507893D01*
G01X1290394Y526353D02*
X1290388Y526147D01*
G01X1290400Y526485D02*
X1290394Y526353D01*
G01X1290406Y526538D02*
X1290400Y526485D01*
G01X1288362Y508025D02*
X1288368Y508231D01*
G01X1288356Y507893D02*
X1288362Y508025D01*
G01X1288350Y507840D02*
X1288356Y507893D01*
G01X1272875Y524209D02*
X1272874Y523807D01*
G01X1272878Y524537D02*
X1272875Y524209D01*
G01X1272882Y524733D02*
X1272878Y524537D01*
G01X1272886Y524763D02*
X1272882Y524733D01*
G01X1274385Y510169D02*
X1274386Y510571D01*
G01X1274382Y509841D02*
X1274385Y510169D01*
G01X1274378Y509645D02*
X1274382Y509841D01*
G01X1274373Y509615D02*
X1274378Y509645D01*
G01X1280749Y524209D02*
X1280748Y523807D01*
G01X1280752Y524537D02*
X1280749Y524209D01*
G01X1280756Y524733D02*
X1280752Y524537D01*
G01X1280760Y524763D02*
X1280756Y524733D01*
G01X1282259Y510169D02*
X1282260Y510571D01*
G01X1282256Y509841D02*
X1282259Y510169D01*
G01X1282252Y509645D02*
X1282256Y509841D01*
G01X1282247Y509615D02*
X1282252Y509645D01*
G01X1288623Y524209D02*
X1288622Y523807D01*
G01X1288626Y524537D02*
X1288623Y524209D01*
G01X1288630Y524733D02*
X1288626Y524537D01*
G01X1288634Y524763D02*
X1288630Y524733D01*
G01X1290133Y510169D02*
X1290134Y510571D01*
G01X1290130Y509841D02*
X1290133Y510169D01*
G01X1290126Y509645D02*
X1290130Y509841D01*
G01X1290122Y509615D02*
X1290126Y509645D01*
G01X1284692Y509610D02*
X1284693Y509615D01*
G01X1284692Y509607D02*
Y509610D01*
G01X1284691Y509606D02*
X1284692Y509607D01*
G01X1294064Y524768D02*
X1294063Y524763D01*
G01X1294064Y524771D02*
Y524768D01*
G01X1294065Y524772D02*
X1294064Y524771D01*
G01X1292566Y509610D02*
X1292567Y509615D01*
G01X1292566Y509607D02*
Y509610D01*
G01X1292565Y509606D02*
X1292566Y509607D01*
G01Y508624D02*
X1292567Y508627D01*
G01X1292566Y508622D02*
Y508624D01*
G01X1292565Y508621D02*
X1292566Y508622D01*
G01X1300440Y508624D02*
X1300441Y508627D01*
G01X1300440Y508622D02*
Y508624D01*
G01X1300439Y508621D02*
X1300440Y508622D01*
G01X1254694D02*
X1254695Y508621D01*
G01X1254693Y508624D02*
X1254694Y508622D01*
G01X1254693Y508627D02*
Y508624D01*
G01X1253196Y525756D02*
X1253195Y525757D01*
G01X1253196Y525754D02*
Y525756D01*
G01X1253197Y525751D02*
X1253196Y525754D01*
G01X1262568Y508622D02*
X1262569Y508621D01*
G01X1262567Y508624D02*
X1262568Y508622D01*
G01X1262567Y508627D02*
Y508624D01*
G01X1261070Y525756D02*
X1261069Y525757D01*
G01X1261070Y525754D02*
Y525756D01*
G01X1261071Y525751D02*
X1261070Y525754D01*
G01X1270442Y508622D02*
X1270443Y508621D01*
G01X1270442Y508624D02*
Y508622D01*
G01X1270441Y508627D02*
X1270442Y508624D01*
G01X1268944Y525756D02*
X1268943Y525757D01*
G01X1268944Y525754D02*
Y525756D01*
G01X1268945Y525751D02*
X1268944Y525754D01*
G01X1284692Y524771D02*
X1284691Y524772D01*
G01X1284692Y524768D02*
Y524771D01*
G01X1284693Y524763D02*
X1284692Y524768D01*
G01X1286190Y509607D02*
X1286191Y509606D01*
G01X1286190Y509610D02*
Y509607D01*
G01X1286189Y509615D02*
X1286190Y509610D01*
G01X1292566Y524771D02*
X1292565Y524772D01*
G01X1292566Y524768D02*
Y524771D01*
G01X1292567Y524763D02*
X1292566Y524768D01*
G01X1294064Y509607D02*
X1294065Y509606D01*
G01X1294064Y509610D02*
Y509607D01*
G01X1294063Y509615D02*
X1294064Y509610D01*
G01X1300429Y510197D02*
X1300428Y510571D01*
G01X1300432Y509887D02*
X1300429Y510197D01*
G01X1300435Y509680D02*
X1300432Y509887D01*
G01X1300439Y509606D02*
X1300435Y509680D01*
G01X1301949Y524181D02*
X1301950Y523807D01*
G01X1301946Y524491D02*
X1301949Y524181D01*
G01X1301943Y524698D02*
X1301946Y524491D01*
G01X1301939Y524772D02*
X1301943Y524698D01*
G01X1284424Y526485D02*
X1284417Y526538D01*
G01X1284430Y526353D02*
X1284424Y526485D01*
G01X1284435Y526147D02*
X1284430Y526353D01*
G01X1286458Y507893D02*
X1286465Y507840D01*
G01X1286452Y508025D02*
X1286458Y507893D01*
G01X1286447Y508231D02*
X1286452Y508025D01*
G01X1288365Y526485D02*
X1288359Y526538D01*
G01X1288371Y526353D02*
X1288365Y526485D01*
G01X1288377Y526147D02*
X1288371Y526353D01*
G01X1290391Y507893D02*
X1290397Y507840D01*
G01X1290385Y508025D02*
X1290391Y507893D01*
G01X1290379Y508231D02*
X1290385Y508025D01*
G01X1292298Y526485D02*
X1292291Y526538D01*
G01X1292304Y526353D02*
X1292298Y526485D01*
G01X1292309Y526147D02*
X1292304Y526353D01*
G01X1294332Y507893D02*
X1294339Y507840D01*
G01X1294326Y508025D02*
X1294332Y507893D01*
G01X1294321Y508231D02*
X1294326Y508025D01*
G01X1296239Y526485D02*
X1296233Y526538D01*
G01X1296245Y526353D02*
X1296239Y526485D01*
G01X1296251Y526147D02*
X1296245Y526353D01*
G01X1298265Y507893D02*
X1298271Y507840D01*
G01X1298259Y508025D02*
X1298265Y507893D01*
G01X1298253Y508231D02*
X1298259Y508025D01*
G01X1300172Y526485D02*
X1300165Y526538D01*
G01X1300178Y526353D02*
X1300172Y526485D01*
G01X1300183Y526147D02*
X1300178Y526353D01*
G01X1302206Y507893D02*
X1302213Y507840D01*
G01X1302200Y508025D02*
X1302206Y507893D01*
G01X1302195Y508231D02*
X1302200Y508025D01*
G01X1304113Y526485D02*
X1304107Y526538D01*
G01X1304119Y526353D02*
X1304113Y526485D01*
G01X1304125Y526147D02*
X1304119Y526353D01*
G01X1306139Y507893D02*
X1306145Y507840D01*
G01X1306133Y508025D02*
X1306139Y507893D01*
G01X1306127Y508231D02*
X1306133Y508025D01*
G01X1284422Y525511D02*
X1284417Y525553D01*
G01X1284426Y525413D02*
X1284422Y525511D01*
G01X1284431Y525261D02*
X1284426Y525413D01*
G01X1286460Y508867D02*
X1286465Y508825D01*
G01X1286456Y508965D02*
X1286460Y508867D01*
G01X1286451Y509117D02*
X1286456Y508965D01*
G01X1288364Y525511D02*
X1288359Y525553D01*
G01X1288368Y525413D02*
X1288364Y525511D01*
G01X1288372Y525261D02*
X1288368Y525413D01*
G01X1290392Y508867D02*
X1290397Y508825D01*
G01X1290388Y508965D02*
X1290392Y508867D01*
G01X1290384Y509117D02*
X1290388Y508965D01*
G01X1292296Y525511D02*
X1292291Y525553D01*
G01X1292300Y525413D02*
X1292296Y525511D01*
G01X1292305Y525261D02*
X1292300Y525413D01*
G01X1294334Y508867D02*
X1294339Y508825D01*
G01X1294330Y508965D02*
X1294334Y508867D01*
G01X1294325Y509117D02*
X1294330Y508965D01*
G01X1296238Y525511D02*
X1296233Y525553D01*
G01X1296242Y525413D02*
X1296238Y525511D01*
G01X1296246Y525261D02*
X1296242Y525413D01*
G01X1298266Y508867D02*
X1298271Y508825D01*
G01X1298262Y508965D02*
X1298266Y508867D01*
G01X1298258Y509117D02*
X1298262Y508965D01*
G01X1300170Y525511D02*
X1300165Y525553D01*
G01X1300174Y525413D02*
X1300170Y525511D01*
G01X1300179Y525261D02*
X1300174Y525413D01*
G01X1302208Y508867D02*
X1302213Y508825D01*
G01X1302204Y508965D02*
X1302208Y508867D01*
G01X1302199Y509117D02*
X1302204Y508965D01*
G01X1304112Y525511D02*
X1304107Y525553D01*
G01X1304116Y525413D02*
X1304112Y525511D01*
G01X1304120Y525261D02*
X1304116Y525413D01*
G01X1306140Y508867D02*
X1306145Y508825D01*
G01X1306136Y508965D02*
X1306140Y508867D01*
G01X1306132Y509117D02*
X1306136Y508965D01*
G01X1288620Y509645D02*
X1288625Y509615D01*
G01X1288616Y509841D02*
X1288620Y509645D01*
G01X1288614Y510169D02*
X1288616Y509841D01*
G01X1288613Y510571D02*
X1288614Y510169D01*
G01X1290135Y524733D02*
X1290131Y524763D01*
G01X1290139Y524537D02*
X1290135Y524733D01*
G01X1290142Y524209D02*
X1290139Y524537D01*
G01X1290143Y523807D02*
X1290142Y524209D01*
G01X1296494Y509645D02*
X1296499Y509615D01*
G01X1296490Y509841D02*
X1296494Y509645D01*
G01X1296488Y510169D02*
X1296490Y509841D01*
G01X1296487Y510571D02*
X1296488Y510169D01*
G01X1298009Y524733D02*
X1298005Y524763D01*
G01X1298013Y524537D02*
X1298009Y524733D01*
G01X1298016Y524209D02*
X1298013Y524537D01*
G01X1298017Y523807D02*
X1298016Y524209D01*
G01X1304368Y509645D02*
X1304373Y509615D01*
G01X1304364Y509841D02*
X1304368Y509645D01*
G01X1304362Y510169D02*
X1304364Y509841D01*
G01X1304361Y510571D02*
X1304362Y510169D01*
G01X1305883Y524733D02*
X1305879Y524763D01*
G01X1305888Y524537D02*
X1305883Y524733D01*
G01X1305890Y524209D02*
X1305888Y524537D01*
G01X1305891Y523807D02*
X1305890Y524209D01*
G01X1284683Y508770D02*
X1284691Y508621D01*
G01X1284676Y509184D02*
X1284683Y508770D01*
G01X1284671Y509804D02*
X1284676Y509184D01*
G01X1284669Y510552D02*
X1284671Y509804D01*
G01X1284687Y509679D02*
X1284691Y509606D01*
G01X1284684Y509887D02*
X1284687Y509679D01*
G01X1284681Y510200D02*
X1284684Y509887D01*
G01X1284680Y510571D02*
X1284681Y510200D01*
G01X1286195Y524699D02*
X1286191Y524772D01*
G01X1286198Y524491D02*
X1286195Y524699D01*
G01X1286201Y524178D02*
X1286198Y524491D01*
G01X1286202Y523807D02*
X1286201Y524178D01*
G01X1286199Y525608D02*
X1286191Y525757D01*
G01X1286206Y525193D02*
X1286199Y525608D01*
G01X1286211Y524573D02*
X1286206Y525193D01*
G01X1286213Y523826D02*
X1286211Y524573D01*
G01X1292557Y508770D02*
X1292565Y508621D01*
G01X1292550Y509184D02*
X1292557Y508770D01*
G01X1292545Y509804D02*
X1292550Y509184D01*
G01X1292543Y510552D02*
X1292545Y509804D01*
G01X1292561Y509679D02*
X1292565Y509606D01*
G01X1292558Y509887D02*
X1292561Y509679D01*
G01X1292555Y510200D02*
X1292558Y509887D01*
G01X1292554Y510571D02*
X1292555Y510200D01*
G01X1294069Y524699D02*
X1294065Y524772D01*
G01X1294072Y524491D02*
X1294069Y524699D01*
G01X1294075Y524178D02*
X1294072Y524491D01*
G01X1294076Y523807D02*
X1294075Y524178D01*
G01X1294073Y525608D02*
X1294065Y525757D01*
G01X1294080Y525193D02*
X1294073Y525608D01*
G01X1294085Y524573D02*
X1294080Y525193D01*
G01X1294087Y523826D02*
X1294085Y524573D01*
G01X1300431Y508770D02*
X1300439Y508621D01*
G01X1300424Y509184D02*
X1300431Y508770D01*
G01X1300419Y509804D02*
X1300424Y509184D01*
G01X1300417Y510552D02*
X1300419Y509804D01*
G01X1301947Y525608D02*
X1301939Y525757D01*
G01X1301954Y525193D02*
X1301947Y525608D01*
G01X1301959Y524573D02*
X1301954Y525193D01*
G01X1301961Y523826D02*
X1301959Y524573D01*
G01X1300435Y524698D02*
X1300439Y524772D01*
G01X1300432Y524491D02*
X1300435Y524698D01*
G01X1300429Y524181D02*
X1300432Y524491D01*
G01X1300428Y523807D02*
X1300429Y524181D01*
G01X1301943Y509680D02*
X1301939Y509606D01*
G01X1301946Y509887D02*
X1301943Y509680D01*
G01X1301949Y510197D02*
X1301946Y509887D01*
G01X1301950Y510571D02*
X1301949Y510197D01*
G01X1292545Y524573D02*
X1292543Y523826D01*
G01X1292550Y525193D02*
X1292545Y524573D01*
G01X1292557Y525608D02*
X1292550Y525193D01*
G01X1292565Y525757D02*
X1292557Y525608D01*
G01X1294085Y509804D02*
X1294087Y510552D01*
G01X1294080Y509184D02*
X1294085Y509804D01*
G01X1294073Y508770D02*
X1294080Y509184D01*
G01X1294065Y508621D02*
X1294073Y508770D01*
G01X1300419Y524573D02*
X1300417Y523826D01*
G01X1300424Y525193D02*
X1300419Y524573D01*
G01X1300431Y525608D02*
X1300424Y525193D01*
G01X1300439Y525757D02*
X1300431Y525608D01*
G01X1301959Y509804D02*
X1301961Y510552D01*
G01X1301954Y509184D02*
X1301959Y509804D01*
G01X1301947Y508770D02*
X1301954Y509184D01*
G01X1301939Y508621D02*
X1301947Y508770D01*
G01X1292555Y524178D02*
X1292554Y523807D01*
G01X1292558Y524491D02*
X1292555Y524178D01*
G01X1292561Y524699D02*
X1292558Y524491D01*
G01X1292565Y524772D02*
X1292561Y524699D01*
G01X1294075Y510200D02*
X1294076Y510571D01*
G01X1294072Y509887D02*
X1294075Y510200D01*
G01X1294069Y509679D02*
X1294072Y509887D01*
G01X1294065Y509606D02*
X1294069Y509679D01*
G01X1300440Y509607D02*
X1300439Y509606D01*
G01X1300440Y509610D02*
Y509607D01*
G01X1300441Y509617D02*
X1300440Y509610D01*
G01X1301938Y524771D02*
X1301939Y524772D01*
G01X1301938Y524768D02*
Y524771D01*
G01X1301937Y524761D02*
X1301938Y524768D01*
G01X1292300Y508965D02*
X1292305Y509117D01*
G01X1292296Y508867D02*
X1292300Y508965D01*
G01X1292291Y508825D02*
X1292296Y508867D01*
G01X1294330Y525413D02*
X1294325Y525261D01*
G01X1294334Y525511D02*
X1294330Y525413D01*
G01X1294339Y525553D02*
X1294334Y525511D01*
G01X1296233Y508965D02*
X1296237Y509117D01*
G01X1296228Y508867D02*
X1296233Y508965D01*
G01X1296224Y508825D02*
X1296228Y508867D01*
G01X1298271Y525413D02*
X1298267Y525261D01*
G01X1298276Y525511D02*
X1298271Y525413D01*
G01X1298280Y525553D02*
X1298276Y525511D01*
G01X1300174Y508965D02*
X1300179Y509117D01*
G01X1300170Y508867D02*
X1300174Y508965D01*
G01X1300165Y508825D02*
X1300170Y508867D01*
G01X1302204Y525413D02*
X1302199Y525261D01*
G01X1302208Y525511D02*
X1302204Y525413D01*
G01X1302213Y525553D02*
X1302208Y525511D01*
G01X1304107Y508965D02*
X1304111Y509117D01*
G01X1304102Y508867D02*
X1304107Y508965D01*
G01X1304098Y508825D02*
X1304102Y508867D01*
G01X1306145Y525413D02*
X1306141Y525261D01*
G01X1306150Y525511D02*
X1306145Y525413D01*
G01X1306154Y525553D02*
X1306150Y525511D01*
G01X1294326Y526353D02*
X1294321Y526147D01*
G01X1294332Y526485D02*
X1294326Y526353D01*
G01X1294339Y526538D02*
X1294332Y526485D01*
G01X1292304Y508025D02*
X1292309Y508231D01*
G01X1292298Y507893D02*
X1292304Y508025D01*
G01X1292291Y507840D02*
X1292298Y507893D01*
G01X1298268Y526353D02*
X1298262Y526147D01*
G01X1298274Y526485D02*
X1298268Y526353D01*
G01X1298280Y526538D02*
X1298274Y526485D01*
G01X1296236Y508025D02*
X1296242Y508231D01*
G01X1296230Y507893D02*
X1296236Y508025D01*
G01X1296224Y507840D02*
X1296230Y507893D01*
G01X1302200Y526353D02*
X1302195Y526147D01*
G01X1302206Y526485D02*
X1302200Y526353D01*
G01X1302213Y526538D02*
X1302206Y526485D01*
G01X1300178Y508025D02*
X1300183Y508231D01*
G01X1300172Y507893D02*
X1300178Y508025D01*
G01X1300165Y507840D02*
X1300172Y507893D01*
G01X1306142Y526353D02*
X1306136Y526147D01*
G01X1306148Y526485D02*
X1306142Y526353D01*
G01X1306154Y526538D02*
X1306148Y526485D01*
G01X1304110Y508025D02*
X1304116Y508231D01*
G01X1304104Y507893D02*
X1304110Y508025D01*
G01X1304098Y507840D02*
X1304104Y507893D01*
G01X1296497Y524209D02*
X1296496Y523807D01*
G01X1296500Y524537D02*
X1296497Y524209D01*
G01X1296504Y524733D02*
X1296500Y524537D01*
G01X1296508Y524763D02*
X1296504Y524733D01*
G01X1298007Y510169D02*
X1298008Y510571D01*
G01X1298004Y509841D02*
X1298007Y510169D01*
G01X1298000Y509645D02*
X1298004Y509841D01*
G01X1297996Y509615D02*
X1298000Y509645D01*
G01X1304371Y524209D02*
X1304370Y523807D01*
G01X1304374Y524537D02*
X1304371Y524209D01*
G01X1304378Y524733D02*
X1304374Y524537D01*
G01X1304382Y524763D02*
X1304378Y524733D01*
G01X1305881Y510169D02*
X1305882Y510571D01*
G01X1305878Y509841D02*
X1305881Y510169D01*
G01X1305874Y509645D02*
X1305878Y509841D01*
G01X1305870Y509615D02*
X1305874Y509645D01*
G01X1278316Y508622D02*
X1278317Y508621D01*
G01X1278316Y508624D02*
Y508622D01*
G01X1278315Y508627D02*
X1278316Y508624D01*
G01X1276818Y525756D02*
X1276817Y525757D01*
G01X1276818Y525754D02*
Y525756D01*
G01X1276819Y525751D02*
X1276818Y525754D01*
G01X1286190Y508622D02*
X1286191Y508621D01*
G01X1286190Y508624D02*
Y508622D01*
G01X1286189Y508627D02*
X1286190Y508624D01*
G01X1284692Y525756D02*
X1284691Y525757D01*
G01X1284692Y525754D02*
Y525756D01*
G01X1284693Y525751D02*
X1284692Y525754D01*
G01X1294064Y508622D02*
X1294065Y508621D01*
G01X1294064Y508624D02*
Y508622D01*
G01X1294063Y508627D02*
X1294064Y508624D01*
G01X1292566Y525756D02*
X1292565Y525757D01*
G01X1292566Y525754D02*
Y525756D01*
G01X1292567Y525751D02*
X1292566Y525754D01*
G01X1301938Y509610D02*
X1301937Y509617D01*
G01X1301938Y509607D02*
Y509610D01*
G01X1301939Y509606D02*
X1301938Y509607D01*
G01X1300440Y524768D02*
X1300441Y524761D01*
G01X1300440Y524771D02*
Y524768D01*
G01X1300439Y524772D02*
X1300440Y524771D01*
G01X1301938Y508622D02*
X1301939Y508621D01*
G01X1301938Y508624D02*
Y508622D01*
G01X1301937Y508627D02*
X1301938Y508624D01*
G01X1300440Y525756D02*
X1300439Y525757D01*
G01X1300440Y525754D02*
Y525756D01*
G01X1300441Y525751D02*
X1300440Y525754D01*
G01X1300135Y508823D02*
X1300120D01*
G01X1300150Y508824D02*
X1300135Y508823D01*
G01X1300165Y508825D02*
X1300150Y508824D01*
G01X1292261Y508823D02*
X1292246D01*
G01X1292276Y508824D02*
X1292261Y508823D01*
G01X1292291Y508825D02*
X1292276Y508824D01*
G01X1288320Y508823D02*
X1288305D01*
G01X1288335Y508824D02*
X1288320Y508823D01*
G01X1288350Y508825D02*
X1288335Y508824D01*
G01X1284387Y508823D02*
X1284372D01*
G01X1284402Y508824D02*
X1284387Y508823D01*
G01X1284417Y508825D02*
X1284402Y508824D01*
G01X1280446Y508823D02*
X1280431D01*
G01X1280461Y508824D02*
X1280446Y508823D01*
G01X1280476Y508825D02*
X1280461Y508824D01*
G01X1276513Y508823D02*
X1276498D01*
G01X1276528Y508824D02*
X1276513Y508823D01*
G01X1276543Y508825D02*
X1276528Y508824D01*
G01X1272572Y508823D02*
X1272557D01*
G01X1272587Y508824D02*
X1272572Y508823D01*
G01X1272602Y508825D02*
X1272587Y508824D01*
G01X1268639Y508823D02*
X1268624D01*
G01X1268654Y508824D02*
X1268639Y508823D01*
G01X1268669Y508825D02*
X1268654Y508824D01*
G01X1304068Y507839D02*
X1304053D01*
G01X1304083D02*
X1304068D01*
G01X1304098Y507840D02*
X1304083Y507839D01*
G01X1296194D02*
X1296179D01*
G01X1296209D02*
X1296194D01*
G01X1296224Y507840D02*
X1296209Y507839D01*
G01X1292261D02*
X1292246D01*
G01X1292276D02*
X1292261D01*
G01X1292291Y507840D02*
X1292276Y507839D01*
G01X1288320D02*
X1288305D01*
G01X1288335D02*
X1288320D01*
G01X1288350Y507840D02*
X1288335Y507839D01*
G01X1284387D02*
X1284372D01*
G01X1284402D02*
X1284387D01*
G01X1284417Y507840D02*
X1284402Y507839D01*
G01X1280446D02*
X1280431D01*
G01X1280461D02*
X1280446D01*
G01X1280476Y507840D02*
X1280461Y507839D01*
G01X1276513D02*
X1276498D01*
G01X1276528D02*
X1276513D01*
G01X1276543Y507840D02*
X1276528Y507839D01*
G01X1272572D02*
X1272557D01*
G01X1272587D02*
X1272572D01*
G01X1272602Y507840D02*
X1272587Y507839D01*
G01X1268639D02*
X1268624D01*
G01X1268654D02*
X1268639D01*
G01X1268669Y507840D02*
X1268654Y507839D01*
G01X1264698D02*
X1264683D01*
G01X1264713D02*
X1264698D01*
G01X1264728Y507840D02*
X1264713Y507839D01*
G01X1260765D02*
X1260750D01*
G01X1260780D02*
X1260765D01*
G01X1260795Y507840D02*
X1260780Y507839D01*
G01X1256824D02*
X1256809D01*
G01X1256839D02*
X1256824D01*
G01X1256854Y507840D02*
X1256839Y507839D01*
G01X1252891D02*
X1252876D01*
G01X1252906D02*
X1252891D01*
G01X1252921Y507840D02*
X1252906Y507839D01*
G01X1248950D02*
X1248935D01*
G01X1248965D02*
X1248950D01*
G01X1248980Y507840D02*
X1248965Y507839D01*
G01X1245017D02*
X1245002D01*
G01X1245032D02*
X1245017D01*
G01X1245047Y507840D02*
X1245032Y507839D01*
G01X1241076D02*
X1241061D01*
G01X1241091D02*
X1241076D01*
G01X1241106Y507840D02*
X1241091Y507839D01*
G01X1243168D02*
X1243153Y507840D01*
G01X1243183Y507839D02*
X1243168D01*
G01X1243198D02*
X1243183D01*
G01X1247109D02*
X1247094Y507840D01*
G01X1247124Y507839D02*
X1247109D01*
G01X1247140D02*
X1247124D01*
G01X1251042D02*
X1251027Y507840D01*
G01X1251057Y507839D02*
X1251042D01*
G01X1251072D02*
X1251057D01*
G01X1254984D02*
X1254968Y507840D01*
G01X1254999Y507839D02*
X1254984D01*
G01X1255014D02*
X1254999D01*
G01X1258916D02*
X1258901Y507840D01*
G01X1258931Y507839D02*
X1258916D01*
G01X1258946D02*
X1258931D01*
G01X1262858D02*
X1262843Y507840D01*
G01X1262873Y507839D02*
X1262858D01*
G01X1262888D02*
X1262873D01*
G01X1266790D02*
X1266775Y507840D01*
G01X1266805Y507839D02*
X1266790D01*
G01X1266820D02*
X1266805D01*
G01X1270732D02*
X1270717Y507840D01*
G01X1270747Y507839D02*
X1270732D01*
G01X1270762D02*
X1270747D01*
G01X1274664D02*
X1274649Y507840D01*
G01X1274679Y507839D02*
X1274664D01*
G01X1274694D02*
X1274679D01*
G01X1278606D02*
X1278591Y507840D01*
G01X1278621Y507839D02*
X1278606D01*
G01X1278636D02*
X1278621D01*
G01X1282538D02*
X1282523Y507840D01*
G01X1282553Y507839D02*
X1282538D01*
G01X1282568D02*
X1282553D01*
G01X1286480D02*
X1286465Y507840D01*
G01X1286495Y507839D02*
X1286480D01*
G01X1286510D02*
X1286495D01*
G01X1290412D02*
X1290397Y507840D01*
G01X1290427Y507839D02*
X1290412D01*
G01X1290442D02*
X1290427D01*
G01X1294354D02*
X1294339Y507840D01*
G01X1294369Y507839D02*
X1294354D01*
G01X1294384D02*
X1294369D01*
G01X1298286D02*
X1298271Y507840D01*
G01X1298301Y507839D02*
X1298286D01*
G01X1298316D02*
X1298301D01*
G01X1302228D02*
X1302213Y507840D01*
G01X1302243Y507839D02*
X1302228D01*
G01X1302258D02*
X1302243D01*
G01X1306160D02*
X1306145Y507840D01*
G01X1306175Y507839D02*
X1306160D01*
G01X1306190D02*
X1306175D01*
G01X1243168Y508824D02*
X1243153Y508825D01*
G01X1243183Y508823D02*
X1243168Y508824D01*
G01X1243198Y508823D02*
X1243183D01*
G01X1247109Y508824D02*
X1247094Y508825D01*
G01X1247124Y508823D02*
X1247109Y508824D01*
G01X1247140Y508823D02*
X1247124D01*
G01X1251042Y508824D02*
X1251027Y508825D01*
G01X1251057Y508823D02*
X1251042Y508824D01*
G01X1251072Y508823D02*
X1251057D01*
G01X1254984Y508824D02*
X1254968Y508825D01*
G01X1254999Y508823D02*
X1254984Y508824D01*
G01X1255014Y508823D02*
X1254999D01*
G01X1258916Y508824D02*
X1258901Y508825D01*
G01X1258931Y508823D02*
X1258916Y508824D01*
G01X1258946Y508823D02*
X1258931D01*
G01X1262858Y508824D02*
X1262843Y508825D01*
G01X1262873Y508823D02*
X1262858Y508824D01*
G01X1262888Y508823D02*
X1262873D01*
G01X1266790Y508824D02*
X1266775Y508825D01*
G01X1266805Y508823D02*
X1266790Y508824D01*
G01X1266820Y508823D02*
X1266805D01*
G01X1270732Y508824D02*
X1270717Y508825D01*
G01X1270747Y508823D02*
X1270732Y508824D01*
G01X1270762Y508823D02*
X1270747D01*
G01X1274664Y508824D02*
X1274649Y508825D01*
G01X1274679Y508823D02*
X1274664Y508824D01*
G01X1274694Y508823D02*
X1274679D01*
G01X1278606Y508824D02*
X1278591Y508825D01*
G01X1278621Y508823D02*
X1278606Y508824D01*
G01X1278636Y508823D02*
X1278621D01*
G01X1282538Y508824D02*
X1282523Y508825D01*
G01X1282553Y508823D02*
X1282538Y508824D01*
G01X1282568Y508823D02*
X1282553D01*
G01X1286480Y508824D02*
X1286465Y508825D01*
G01X1286495Y508823D02*
X1286480Y508824D01*
G01X1286510Y508823D02*
X1286495D01*
G01X1290412Y508824D02*
X1290397Y508825D01*
G01X1290427Y508823D02*
X1290412Y508824D01*
G01X1290442Y508823D02*
X1290427D01*
G01X1294354Y508824D02*
X1294339Y508825D01*
G01X1294369Y508823D02*
X1294354Y508824D01*
G01X1294384Y508823D02*
X1294369D01*
G01X1302228Y508824D02*
X1302213Y508825D01*
G01X1302243Y508823D02*
X1302228Y508824D01*
G01X1302258Y508823D02*
X1302243D01*
G01X1298301D02*
X1298316D01*
G01X1298286Y508824D02*
X1298301Y508823D01*
G01X1298271Y508825D02*
X1298286Y508824D01*
G01X1306175Y508823D02*
X1306190D01*
G01X1306160Y508824D02*
X1306175Y508823D01*
G01X1306145Y508825D02*
X1306160Y508824D01*
G01X1264698Y508823D02*
X1264683D01*
G01X1264713Y508824D02*
X1264698Y508823D01*
G01X1264728Y508825D02*
X1264713Y508824D01*
G01X1260765Y508823D02*
X1260750D01*
G01X1260780Y508824D02*
X1260765Y508823D01*
G01X1260795Y508825D02*
X1260780Y508824D01*
G01X1256824Y508823D02*
X1256809D01*
G01X1256839Y508824D02*
X1256824Y508823D01*
G01X1256854Y508825D02*
X1256839Y508824D01*
G01X1252891Y508823D02*
X1252876D01*
G01X1252906Y508824D02*
X1252891Y508823D01*
G01X1252921Y508825D02*
X1252906Y508824D01*
G01X1248950Y508823D02*
X1248935D01*
G01X1248965Y508824D02*
X1248950Y508823D01*
G01X1248980Y508825D02*
X1248965Y508824D01*
G01X1245017Y508823D02*
X1245002D01*
G01X1245032Y508824D02*
X1245017Y508823D01*
G01X1245047Y508825D02*
X1245032Y508824D01*
G01X1241076Y508823D02*
X1241061D01*
G01X1241091Y508824D02*
X1241076Y508823D01*
G01X1241106Y508825D02*
X1241091Y508824D01*
G01X1306184Y525555D02*
X1306199D01*
G01X1306169Y525554D02*
X1306184Y525555D01*
G01X1306154Y525553D02*
X1306169Y525554D01*
G01X1302243Y525555D02*
X1302258D01*
G01X1302228Y525554D02*
X1302243Y525555D01*
G01X1302213Y525553D02*
X1302228Y525554D01*
G01X1298310Y525555D02*
X1298325D01*
G01X1298295Y525554D02*
X1298310Y525555D01*
G01X1298280Y525553D02*
X1298295Y525554D01*
G01X1294369Y525555D02*
X1294384D01*
G01X1294354Y525554D02*
X1294369Y525555D01*
G01X1294339Y525553D02*
X1294354Y525554D01*
G01X1290436Y525555D02*
X1290451D01*
G01X1290421Y525554D02*
X1290436Y525555D01*
G01X1290406Y525553D02*
X1290421Y525554D01*
G01X1286495Y525555D02*
X1286510D01*
G01X1286480Y525554D02*
X1286495Y525555D01*
G01X1286465Y525553D02*
X1286480Y525554D01*
G01X1278621Y525555D02*
X1278636D01*
G01X1278606Y525554D02*
X1278621Y525555D01*
G01X1278591Y525553D02*
X1278606Y525554D01*
G01X1270747Y525555D02*
X1270762D01*
G01X1270732Y525554D02*
X1270747Y525555D01*
G01X1270717Y525553D02*
X1270732Y525554D01*
G01X1266814Y525555D02*
X1266829D01*
G01X1266799Y525554D02*
X1266814Y525555D01*
G01X1266784Y525553D02*
X1266799Y525554D01*
G01X1262873Y525555D02*
X1262888D01*
G01X1262858Y525554D02*
X1262873Y525555D01*
G01X1262843Y525553D02*
X1262858Y525554D01*
G01X1258940Y525555D02*
X1258955D01*
G01X1258925Y525554D02*
X1258940Y525555D01*
G01X1258910Y525553D02*
X1258925Y525554D01*
G01X1254999Y525555D02*
X1255014D01*
G01X1254984Y525554D02*
X1254999Y525555D01*
G01X1254968Y525553D02*
X1254984Y525554D01*
G01X1247124Y525555D02*
X1247140D01*
G01X1247109Y525554D02*
X1247124Y525555D01*
G01X1247094Y525553D02*
X1247109Y525554D01*
G01X1298310Y526539D02*
X1298325D01*
G01X1298295D02*
X1298310D01*
G01X1298280Y526538D02*
X1298295Y526539D01*
G01X1294369D02*
X1294384D01*
G01X1294354D02*
X1294369D01*
G01X1294339Y526538D02*
X1294354Y526539D01*
G01X1290436D02*
X1290451D01*
G01X1290421D02*
X1290436D01*
G01X1290406Y526538D02*
X1290421Y526539D01*
G01X1286495D02*
X1286510D01*
G01X1286480D02*
X1286495D01*
G01X1286465Y526538D02*
X1286480Y526539D01*
G01X1282562D02*
X1282577D01*
G01X1282547D02*
X1282562D01*
G01X1282532Y526538D02*
X1282547Y526539D01*
G01X1278621D02*
X1278636D01*
G01X1278606D02*
X1278621D01*
G01X1278591Y526538D02*
X1278606Y526539D01*
G01X1274688D02*
X1274703D01*
G01X1274673D02*
X1274688D01*
G01X1274658Y526538D02*
X1274673Y526539D01*
G01X1270747D02*
X1270762D01*
G01X1270732D02*
X1270747D01*
G01X1270717Y526538D02*
X1270732Y526539D01*
G01X1266814D02*
X1266829D01*
G01X1266799D02*
X1266814D01*
G01X1266784Y526538D02*
X1266799Y526539D01*
G01X1262873D02*
X1262888D01*
G01X1262858D02*
X1262873D01*
G01X1262843Y526538D02*
X1262858Y526539D01*
G01X1258940D02*
X1258955D01*
G01X1258925D02*
X1258940D01*
G01X1258910Y526538D02*
X1258925Y526539D01*
G01X1254999D02*
X1255014D01*
G01X1254984D02*
X1254999D01*
G01X1254968Y526538D02*
X1254984Y526539D01*
G01X1251066D02*
X1251081D01*
G01X1251051D02*
X1251066D01*
G01X1251036Y526538D02*
X1251051Y526539D01*
G01X1247124D02*
X1247140D01*
G01X1247109D02*
X1247124D01*
G01X1247094Y526538D02*
X1247109Y526539D01*
G01X1243192D02*
X1243207D01*
G01X1243177D02*
X1243192D01*
G01X1243162Y526538D02*
X1243177Y526539D01*
G01X1241100D02*
X1241115Y526538D01*
G01X1241085Y526539D02*
X1241100D01*
G01X1241070D02*
X1241085D01*
G01X1245032D02*
X1245047Y526538D01*
G01X1245017Y526539D02*
X1245032D01*
G01X1245002D02*
X1245017D01*
G01X1248974D02*
X1248989Y526538D01*
G01X1248959Y526539D02*
X1248974D01*
G01X1248944D02*
X1248959D01*
G01X1252906D02*
X1252921Y526538D01*
G01X1252891Y526539D02*
X1252906D01*
G01X1252876D02*
X1252891D01*
G01X1256848D02*
X1256863Y526538D01*
G01X1256833Y526539D02*
X1256848D01*
G01X1256818D02*
X1256833D01*
G01X1260780D02*
X1260795Y526538D01*
G01X1260765Y526539D02*
X1260780D01*
G01X1260750D02*
X1260765D01*
G01X1264722D02*
X1264737Y526538D01*
G01X1264707Y526539D02*
X1264722D01*
G01X1264692D02*
X1264707D01*
G01X1268654D02*
X1268669Y526538D01*
G01X1268639Y526539D02*
X1268654D01*
G01X1268624D02*
X1268639D01*
G01X1272596D02*
X1272611Y526538D01*
G01X1272581Y526539D02*
X1272596D01*
G01X1272566D02*
X1272581D01*
G01X1276528D02*
X1276543Y526538D01*
G01X1276513Y526539D02*
X1276528D01*
G01X1276498D02*
X1276513D01*
G01X1280470D02*
X1280485Y526538D01*
G01X1280455Y526539D02*
X1280470D01*
G01X1280440D02*
X1280455D01*
G01X1284402D02*
X1284417Y526538D01*
G01X1284387Y526539D02*
X1284402D01*
G01X1284372D02*
X1284387D01*
G01X1288344D02*
X1288359Y526538D01*
G01X1288329Y526539D02*
X1288344D01*
G01X1288314D02*
X1288329D01*
G01X1292276D02*
X1292291Y526538D01*
G01X1292261Y526539D02*
X1292276D01*
G01X1292246D02*
X1292261D01*
G01X1296218D02*
X1296233Y526538D01*
G01X1296203Y526539D02*
X1296218D01*
G01X1296188D02*
X1296203D01*
G01X1300150D02*
X1300165Y526538D01*
G01X1300135Y526539D02*
X1300150D01*
G01X1300120D02*
X1300135D01*
G01X1304092D02*
X1304107Y526538D01*
G01X1304077Y526539D02*
X1304092D01*
G01X1304062D02*
X1304077D01*
G01X1241100Y525554D02*
X1241115Y525553D01*
G01X1241085Y525555D02*
X1241100Y525554D01*
G01X1241070Y525555D02*
X1241085D01*
G01X1245032Y525554D02*
X1245047Y525553D01*
G01X1245017Y525555D02*
X1245032Y525554D01*
G01X1245002Y525555D02*
X1245017D01*
G01X1248974Y525554D02*
X1248989Y525553D01*
G01X1248959Y525555D02*
X1248974Y525554D01*
G01X1248944Y525555D02*
X1248959D01*
G01X1252906Y525554D02*
X1252921Y525553D01*
G01X1252891Y525555D02*
X1252906Y525554D01*
G01X1252876Y525555D02*
X1252891D01*
G01X1260780Y525554D02*
X1260795Y525553D01*
G01X1260765Y525555D02*
X1260780Y525554D01*
G01X1260750Y525555D02*
X1260765D01*
G01X1268654Y525554D02*
X1268669Y525553D01*
G01X1268639Y525555D02*
X1268654Y525554D01*
G01X1268624Y525555D02*
X1268639D01*
G01X1272596Y525554D02*
X1272611Y525553D01*
G01X1272581Y525555D02*
X1272596Y525554D01*
G01X1272566Y525555D02*
X1272581D01*
G01X1276528Y525554D02*
X1276543Y525553D01*
G01X1276513Y525555D02*
X1276528Y525554D01*
G01X1276498Y525555D02*
X1276513D01*
G01X1280470Y525554D02*
X1280485Y525553D01*
G01X1280455Y525555D02*
X1280470Y525554D01*
G01X1280440Y525555D02*
X1280455D01*
G01X1284402Y525554D02*
X1284417Y525553D01*
G01X1284387Y525555D02*
X1284402Y525554D01*
G01X1284372Y525555D02*
X1284387D01*
G01X1292276Y525554D02*
X1292291Y525553D01*
G01X1292261Y525555D02*
X1292276Y525554D01*
G01X1292246Y525555D02*
X1292261D01*
G01X1296218Y525554D02*
X1296233Y525553D01*
G01X1296203Y525555D02*
X1296218Y525554D01*
G01X1296188Y525555D02*
X1296203D01*
G01X1300150Y525554D02*
X1300165Y525553D01*
G01X1300135Y525555D02*
X1300150Y525554D01*
G01X1300120Y525555D02*
X1300135D01*
G01X1304092Y525554D02*
X1304107Y525553D01*
G01X1304077Y525555D02*
X1304092Y525554D01*
G01X1304062Y525555D02*
X1304077D01*
G01X1256833D02*
X1256818D01*
G01X1256848Y525554D02*
X1256833Y525555D01*
G01X1256863Y525553D02*
X1256848Y525554D01*
G01X1264707Y525555D02*
X1264692D01*
G01X1264722Y525554D02*
X1264707Y525555D01*
G01X1264737Y525553D02*
X1264722Y525554D01*
G01X1288329Y525555D02*
X1288314D01*
G01X1288344Y525554D02*
X1288329Y525555D01*
G01X1288359Y525553D02*
X1288344Y525554D01*
G01X1243315Y530476D02*
X1240953D01*
G01X1247252D02*
X1244890D01*
G01X1251189D02*
X1248827D01*
G01X1255126D02*
X1252764D01*
G01X1259063D02*
X1256701D01*
G01X1263000D02*
X1260638D01*
G01X1266937D02*
X1264575D01*
G01X1270874D02*
X1268512D01*
G01X1274811D02*
X1272449D01*
G01X1278748D02*
X1276386D01*
G01X1282685D02*
X1280323D01*
G01X1286622D02*
X1284260D01*
G01X1290559D02*
X1288197D01*
G01X1294496D02*
X1292134D01*
G01X1298433D02*
X1296071D01*
G01X1302370D02*
X1300008D01*
G01X1306307D02*
X1303945D01*
G01X1246740Y529492D02*
X1245402D01*
G01X1254614D02*
X1253276D01*
G01X1262488D02*
X1261150D01*
G01X1270362D02*
X1269024D01*
G01X1278236D02*
X1276898D01*
G01X1286110D02*
X1284772D01*
G01X1293984D02*
X1292646D01*
G01X1301858D02*
X1300520D01*
G01X1300362Y529394D02*
X1302016D01*
G01X1292488D02*
X1294142D01*
G01X1284614D02*
X1286268D01*
G01X1276740D02*
X1278394D01*
G01X1268866D02*
X1270520D01*
G01X1260992D02*
X1262646D01*
G01X1253118D02*
X1254772D01*
G01X1245244D02*
X1246898D01*
G01X1243315Y529295D02*
X1240953D01*
G01X1247252D02*
X1244890D01*
G01X1251189D02*
X1248827D01*
G01X1255126D02*
X1252764D01*
G01X1259063D02*
X1256701D01*
G01X1263000D02*
X1260638D01*
G01X1266937D02*
X1264575D01*
G01X1270874D02*
X1268512D01*
G01X1274811D02*
X1272449D01*
G01X1278748D02*
X1276386D01*
G01X1282685D02*
X1280323D01*
G01X1286622D02*
X1284260D01*
G01X1290559D02*
X1288197D01*
G01X1294496D02*
X1292134D01*
G01X1298433D02*
X1296071D01*
G01X1302370D02*
X1300008D01*
G01X1306307D02*
X1303945D01*
G01X1246898Y528902D02*
X1245244D01*
G01X1254772D02*
X1253118D01*
G01X1262646D02*
X1260992D01*
G01X1270520D02*
X1268866D01*
G01X1278394D02*
X1276740D01*
G01X1286268D02*
X1284614D01*
G01X1294142D02*
X1292488D01*
G01X1302016D02*
X1300362D01*
G01X1243551Y528035D02*
X1240717D01*
G01X1247488D02*
X1244654D01*
G01X1251425D02*
X1248591D01*
G01X1255362D02*
X1252528D01*
G01X1259299D02*
X1256465D01*
G01X1263236D02*
X1260402D01*
G01X1267173D02*
X1264339D01*
G01X1271110D02*
X1268276D01*
G01X1275047D02*
X1272213D01*
G01X1278984D02*
X1276150D01*
G01X1282921D02*
X1280087D01*
G01X1286858D02*
X1284024D01*
G01X1290795D02*
X1287961D01*
G01X1294732D02*
X1291898D01*
G01X1298669D02*
X1295835D01*
G01X1302606D02*
X1299772D01*
G01X1306543D02*
X1303709D01*
G01X1310480D02*
X1307646D01*
G01X1246898Y527130D02*
X1245244D01*
G01X1254772D02*
X1253118D01*
G01X1262646D02*
X1260992D01*
G01X1270520D02*
X1268866D01*
G01X1278394D02*
X1276740D01*
G01X1286268D02*
X1284614D01*
G01X1294142D02*
X1292488D01*
G01X1302016D02*
X1300362D01*
G01Y526638D02*
X1302016D01*
G01X1292488D02*
X1294142D01*
G01X1284614D02*
X1286268D01*
G01X1276740D02*
X1278394D01*
G01X1268866D02*
X1270520D01*
G01X1260992D02*
X1262646D01*
G01X1253118D02*
X1254772D01*
G01X1245244D02*
X1246898D01*
G01X1243551Y526539D02*
X1240717D01*
G01X1247488D02*
X1244654D01*
G01X1251425D02*
X1248591D01*
G01X1255362D02*
X1252528D01*
G01X1259299D02*
X1256465D01*
G01X1263236D02*
X1260402D01*
G01X1267173D02*
X1264339D01*
G01X1271110D02*
X1268276D01*
G01X1275047D02*
X1272213D01*
G01X1278984D02*
X1276150D01*
G01X1282921D02*
X1280087D01*
G01X1286858D02*
X1284024D01*
G01X1290795D02*
X1287961D01*
G01X1294732D02*
X1291898D01*
G01X1298669D02*
X1295835D01*
G01X1302606D02*
X1299772D01*
G01X1306543D02*
X1303709D01*
G01X1310480D02*
X1307646D01*
G01Y526382D02*
X1308236D01*
G01X1305953D02*
X1306543D01*
G01X1303709D02*
X1304299D01*
G01X1302016D02*
X1302606D01*
G01X1299772D02*
X1300362D01*
G01X1298079D02*
X1298669D01*
G01X1295835D02*
X1296425D01*
G01X1294142D02*
X1294732D01*
G01X1291898D02*
X1292488D01*
G01X1290205D02*
X1290795D01*
G01X1287961D02*
X1288551D01*
G01X1286268D02*
X1286858D01*
G01X1284024D02*
X1284614D01*
G01X1282331D02*
X1282921D01*
G01X1280087D02*
X1280677D01*
G01X1278394D02*
X1278984D01*
G01X1276150D02*
X1276740D01*
G01X1274457D02*
X1275047D01*
G01X1272213D02*
X1272803D01*
G01X1270520D02*
X1271110D01*
G01X1268276D02*
X1268866D01*
G01X1266583D02*
X1267173D01*
G01X1264339D02*
X1264929D01*
G01X1262646D02*
X1263236D01*
G01X1260402D02*
X1260992D01*
G01X1258709D02*
X1259299D01*
G01X1256465D02*
X1257055D01*
G01X1254772D02*
X1255362D01*
G01X1252528D02*
X1253118D01*
G01X1250835D02*
X1251425D01*
G01X1248591D02*
X1249181D01*
G01X1246898D02*
X1247488D01*
G01X1244654D02*
X1245244D01*
G01X1242961D02*
X1243551D01*
G01X1240717D02*
X1241307D01*
G01X1304125Y526147D02*
X1306136D01*
G01X1300183D02*
X1302195D01*
G01X1296251D02*
X1298262D01*
G01X1292309D02*
X1294321D01*
G01X1288377D02*
X1290388D01*
G01X1284435D02*
X1286447D01*
G01X1280503D02*
X1282514D01*
G01X1276561D02*
X1278573D01*
G01X1272629D02*
X1274640D01*
G01X1268687D02*
X1270699D01*
G01X1264755D02*
X1266766D01*
G01X1260813D02*
X1262825D01*
G01X1256881D02*
X1258892D01*
G01X1252939D02*
X1254951D01*
G01X1249007D02*
X1251018D01*
G01X1245065D02*
X1247076D01*
G01X1241133D02*
X1243144D01*
G01X1242888Y525757D02*
X1241389D01*
G01X1246821D02*
X1245321D01*
G01X1250762D02*
X1249263D01*
G01X1254695D02*
X1253195D01*
G01X1258636D02*
X1257137D01*
G01X1262569D02*
X1261069D01*
G01X1266510D02*
X1265011D01*
G01X1270443D02*
X1268943D01*
G01X1274384D02*
X1272885D01*
G01X1278317D02*
X1276817D01*
G01X1282258D02*
X1280759D01*
G01X1286191D02*
X1284691D01*
G01X1290132D02*
X1288633D01*
G01X1294065D02*
X1292565D01*
G01X1298006D02*
X1296507D01*
G01X1301939D02*
X1300439D01*
G01X1305880D02*
X1304381D01*
G01X1304394Y525738D02*
X1305867D01*
G01X1300452D02*
X1301925D01*
G01X1296520D02*
X1297993D01*
G01X1292578D02*
X1294051D01*
G01X1288646D02*
X1290119D01*
G01X1284704D02*
X1286177D01*
G01X1280772D02*
X1282245D01*
G01X1276830D02*
X1278303D01*
G01X1272898D02*
X1274371D01*
G01X1268956D02*
X1270429D01*
G01X1265024D02*
X1266497D01*
G01X1261082D02*
X1262555D01*
G01X1257150D02*
X1258623D01*
G01X1253208D02*
X1254681D01*
G01X1249276D02*
X1250749D01*
G01X1245334D02*
X1246807D01*
G01X1241402D02*
X1242875D01*
G01X1241307Y525713D02*
X1240717D01*
G01X1243551D02*
X1242961D01*
G01X1245244D02*
X1244654D01*
G01X1247488D02*
X1246898D01*
G01X1249181D02*
X1248591D01*
G01X1251425D02*
X1250835D01*
G01X1253118D02*
X1252528D01*
G01X1255362D02*
X1254772D01*
G01X1257055D02*
X1256465D01*
G01X1259299D02*
X1258709D01*
G01X1260992D02*
X1260402D01*
G01X1263236D02*
X1262646D01*
G01X1264929D02*
X1264339D01*
G01X1267173D02*
X1266583D01*
G01X1268866D02*
X1268276D01*
G01X1271110D02*
X1270520D01*
G01X1272803D02*
X1272213D01*
G01X1275047D02*
X1274457D01*
G01X1276740D02*
X1276150D01*
G01X1278984D02*
X1278394D01*
G01X1280677D02*
X1280087D01*
G01X1282921D02*
X1282331D01*
G01X1284614D02*
X1284024D01*
G01X1286858D02*
X1286268D01*
G01X1288551D02*
X1287961D01*
G01X1290795D02*
X1290205D01*
G01X1292488D02*
X1291898D01*
G01X1294732D02*
X1294142D01*
G01X1296425D02*
X1295835D01*
G01X1298669D02*
X1298079D01*
G01X1300362D02*
X1299772D01*
G01X1302606D02*
X1302016D01*
G01X1304299D02*
X1303709D01*
G01X1306543D02*
X1305953D01*
G01X1308236D02*
X1307646D01*
G01Y525555D02*
X1310480D01*
G01X1303709D02*
X1306543D01*
G01X1299772D02*
X1302606D01*
G01X1291898D02*
X1294732D01*
G01X1287961D02*
X1290795D01*
G01X1284024D02*
X1286858D01*
G01X1280087D02*
X1282921D01*
G01X1276150D02*
X1278984D01*
G01X1272213D02*
X1275047D01*
G01X1268276D02*
X1271110D01*
G01X1260402D02*
X1263236D01*
G01X1252528D02*
X1255362D01*
G01X1248591D02*
X1251425D01*
G01X1244654D02*
X1247488D01*
G01X1240717D02*
X1243551D01*
G01X1259299D02*
X1256465D01*
G01X1267173D02*
X1264339D01*
G01X1298669D02*
X1295835D01*
G01X1242961Y525457D02*
X1241307D01*
G01X1250835D02*
X1249181D01*
G01X1258709D02*
X1257055D01*
G01X1266583D02*
X1264929D01*
G01X1274457D02*
X1272803D01*
G01X1282331D02*
X1280677D01*
G01X1290205D02*
X1288551D01*
G01X1298079D02*
X1296425D01*
G01X1305953D02*
X1304299D01*
G01X1242621Y525368D02*
X1241656D01*
G01X1246554D02*
X1245588D01*
G01X1250495D02*
X1249530D01*
G01X1254428D02*
X1253462D01*
G01X1258369D02*
X1257404D01*
G01X1262302D02*
X1261336D01*
G01X1266243D02*
X1265278D01*
G01X1270176D02*
X1269210D01*
G01X1274117D02*
X1273152D01*
G01X1278050D02*
X1277084D01*
G01X1281991D02*
X1281026D01*
G01X1285924D02*
X1284958D01*
G01X1289865D02*
X1288900D01*
G01X1293798D02*
X1292832D01*
G01X1297739D02*
X1296774D01*
G01X1301672D02*
X1300706D01*
G01X1305613D02*
X1304648D01*
G01X1303709Y525358D02*
X1304024D01*
G01X1295835D02*
X1296150D01*
G01X1291898D02*
X1292213D01*
G01X1287961D02*
X1288276D01*
G01X1284024D02*
X1284339D01*
G01X1280087D02*
X1280402D01*
G01X1276150D02*
X1276465D01*
G01X1272213D02*
X1272528D01*
G01X1268276D02*
X1268591D01*
G01X1264339D02*
X1264654D01*
G01X1260402D02*
X1260717D01*
G01X1256465D02*
X1256780D01*
G01X1252528D02*
X1252843D01*
G01X1248591D02*
X1248906D01*
G01X1244654D02*
X1244968D01*
G01X1240717D02*
X1241031D01*
G01X1243551D02*
X1243236D01*
G01X1247488D02*
X1247173D01*
G01X1251425D02*
X1251110D01*
G01X1255362D02*
X1255047D01*
G01X1259299D02*
X1258984D01*
G01X1263236D02*
X1262921D01*
G01X1267173D02*
X1266858D01*
G01X1271110D02*
X1270795D01*
G01X1275047D02*
X1274732D01*
G01X1278984D02*
X1278669D01*
G01X1282921D02*
X1282606D01*
G01X1286858D02*
X1286543D01*
G01X1290795D02*
X1290480D01*
G01X1294732D02*
X1294417D01*
G01X1298669D02*
X1298354D01*
G01X1300087D02*
X1299772D01*
G01X1302606D02*
X1302291D01*
G01X1306543D02*
X1306228D01*
G01X1307961D02*
X1307646D01*
G01X1243149Y525261D02*
X1241128D01*
G01X1247081D02*
X1245060D01*
G01X1251023D02*
X1249002D01*
G01X1254955D02*
X1252934D01*
G01X1258897D02*
X1256876D01*
G01X1262829D02*
X1260808D01*
G01X1266771D02*
X1264750D01*
G01X1270703D02*
X1268682D01*
G01X1274645D02*
X1272624D01*
G01X1278577D02*
X1276557D01*
G01X1282519D02*
X1280498D01*
G01X1286451D02*
X1284431D01*
G01X1290393D02*
X1288372D01*
G01X1294325D02*
X1292305D01*
G01X1298267D02*
X1296246D01*
G01X1302199D02*
X1300179D01*
G01X1306141D02*
X1304120D01*
G01X1304299Y524965D02*
X1305953D01*
G01X1296425D02*
X1298079D01*
G01X1288551D02*
X1290205D01*
G01X1280677D02*
X1282331D01*
G01X1272803D02*
X1274457D01*
G01X1264929D02*
X1266583D01*
G01X1257055D02*
X1258709D01*
G01X1249181D02*
X1250835D01*
G01X1241307D02*
X1242961D01*
G01X1242888Y524772D02*
X1241389D01*
G01X1246821D02*
X1245321D01*
G01X1250762D02*
X1249263D01*
G01X1254695D02*
X1253195D01*
G01X1258636D02*
X1257137D01*
G01X1262569D02*
X1261069D01*
G01X1266510D02*
X1265011D01*
G01X1270443D02*
X1268943D01*
G01X1274384D02*
X1272885D01*
G01X1278317D02*
X1276817D01*
G01X1282258D02*
X1280759D01*
G01X1286191D02*
X1284691D01*
G01X1290132D02*
X1288633D01*
G01X1294065D02*
X1292565D01*
G01X1298006D02*
X1296507D01*
G01X1301939D02*
X1300439D01*
G01X1305880D02*
X1304381D01*
G01X1242887Y524763D02*
X1241390D01*
G01X1246819D02*
X1245323D01*
G01X1250761D02*
X1249264D01*
G01X1254693D02*
X1253197D01*
G01X1258635D02*
X1257138D01*
G01X1262567D02*
X1261071D01*
G01X1266509D02*
X1265012D01*
G01X1270441D02*
X1268945D01*
G01X1274383D02*
X1272886D01*
G01X1278315D02*
X1276819D01*
G01X1282257D02*
X1280760D01*
G01X1286189D02*
X1284693D01*
G01X1290131D02*
X1288634D01*
G01X1294063D02*
X1292567D01*
G01X1298005D02*
X1296508D01*
G01X1301937D02*
X1300441D01*
G01X1305879D02*
X1304382D01*
G01X1304602Y524441D02*
X1305659D01*
G01X1300661D02*
X1301717D01*
G01X1296728D02*
X1297785D01*
G01X1292787D02*
X1293843D01*
G01X1288854D02*
X1289911D01*
G01X1284913D02*
X1285969D01*
G01X1280980D02*
X1282037D01*
G01X1277039D02*
X1278095D01*
G01X1273106D02*
X1274163D01*
G01X1269165D02*
X1270221D01*
G01X1265232D02*
X1266289D01*
G01X1261291D02*
X1262347D01*
G01X1257358D02*
X1258415D01*
G01X1253417D02*
X1254473D01*
G01X1249484D02*
X1250541D01*
G01X1245543D02*
X1246599D01*
G01X1241610D02*
X1242667D01*
G01X1303945Y524394D02*
X1306307D01*
G01X1300008D02*
X1302370D01*
G01X1243315D02*
X1240953D01*
G01X1247252D02*
X1244890D01*
G01X1251189D02*
X1248827D01*
G01X1255126D02*
X1252764D01*
G01X1259063D02*
X1256701D01*
G01X1263000D02*
X1260638D01*
G01X1266937D02*
X1264575D01*
G01X1270874D02*
X1268512D01*
G01X1274811D02*
X1272449D01*
G01X1278748D02*
X1276386D01*
G01X1282685D02*
X1280323D01*
G01X1286622D02*
X1284260D01*
G01X1290559D02*
X1288197D01*
G01X1294496D02*
X1292134D01*
G01X1298433D02*
X1296071D01*
G01X1307646Y523862D02*
X1307961D01*
G01X1306228D02*
X1306543D01*
G01X1303709D02*
X1304024D01*
G01X1302291D02*
X1302606D01*
G01X1299772D02*
X1300087D01*
G01X1298354D02*
X1298669D01*
G01X1295835D02*
X1296150D01*
G01X1294417D02*
X1294732D01*
G01X1291898D02*
X1292213D01*
G01X1290480D02*
X1290795D01*
G01X1287961D02*
X1288276D01*
G01X1286543D02*
X1286858D01*
G01X1284024D02*
X1284339D01*
G01X1282606D02*
X1282921D01*
G01X1280087D02*
X1280402D01*
G01X1278669D02*
X1278984D01*
G01X1276150D02*
X1276465D01*
G01X1274732D02*
X1275047D01*
G01X1272213D02*
X1272528D01*
G01X1270795D02*
X1271110D01*
G01X1268276D02*
X1268591D01*
G01X1266858D02*
X1267173D01*
G01X1264339D02*
X1264654D01*
G01X1262921D02*
X1263236D01*
G01X1260402D02*
X1260717D01*
G01X1258984D02*
X1259299D01*
G01X1256465D02*
X1256780D01*
G01X1255047D02*
X1255362D01*
G01X1252528D02*
X1252843D01*
G01X1251110D02*
X1251425D01*
G01X1248591D02*
X1248906D01*
G01X1247173D02*
X1247488D01*
G01X1244654D02*
X1244968D01*
G01X1243236D02*
X1243551D01*
G01X1240717D02*
X1241031D01*
G01X1304359Y523826D02*
X1305902D01*
G01X1300417D02*
X1301961D01*
G01X1296485D02*
X1298028D01*
G01X1292543D02*
X1294087D01*
G01X1288611D02*
X1290154D01*
G01X1284669D02*
X1286213D01*
G01X1280737D02*
X1282280D01*
G01X1276795D02*
X1278339D01*
G01X1272863D02*
X1274406D01*
G01X1268921D02*
X1270465D01*
G01X1264989D02*
X1266532D01*
G01X1261047D02*
X1262591D01*
G01X1257115D02*
X1258658D01*
G01X1253173D02*
X1254717D01*
G01X1249241D02*
X1250784D01*
G01X1245299D02*
X1246843D01*
G01X1241367D02*
X1242910D01*
G01X1304370Y523807D02*
X1305891D01*
G01X1300428D02*
X1301950D01*
G01X1296496D02*
X1298017D01*
G01X1292554D02*
X1294076D01*
G01X1288622D02*
X1290143D01*
G01X1284680D02*
X1286202D01*
G01X1280748D02*
X1282269D01*
G01X1276806D02*
X1278328D01*
G01X1272874D02*
X1274395D01*
G01X1268932D02*
X1270454D01*
G01X1265000D02*
X1266521D01*
G01X1261058D02*
X1262580D01*
G01X1257126D02*
X1258647D01*
G01X1253184D02*
X1254706D01*
G01X1249252D02*
X1250773D01*
G01X1245310D02*
X1246832D01*
G01X1241378D02*
X1242899D01*
G01X1304299Y523193D02*
X1305953D01*
G01X1296425D02*
X1298079D01*
G01X1288551D02*
X1290205D01*
G01X1280677D02*
X1282331D01*
G01X1272803D02*
X1274457D01*
G01X1264929D02*
X1266583D01*
G01X1257055D02*
X1258709D01*
G01X1249181D02*
X1250835D01*
G01X1241307D02*
X1242961D01*
G01Y522701D02*
X1241307D01*
G01X1250835D02*
X1249181D01*
G01X1258709D02*
X1257055D01*
G01X1266583D02*
X1264929D01*
G01X1274457D02*
X1272803D01*
G01X1282331D02*
X1280677D01*
G01X1290205D02*
X1288551D01*
G01X1298079D02*
X1296425D01*
G01X1305953D02*
X1304299D01*
G01X1242803Y522602D02*
X1241465D01*
G01X1250677D02*
X1249339D01*
G01X1258551D02*
X1257213D01*
G01X1266425D02*
X1265087D01*
G01X1274299D02*
X1272961D01*
G01X1282173D02*
X1280835D01*
G01X1290047D02*
X1288709D01*
G01X1297921D02*
X1296583D01*
G01X1305795D02*
X1304457D01*
G01Y521618D02*
X1305795D01*
G01X1296583D02*
X1297921D01*
G01X1288709D02*
X1290047D01*
G01X1280835D02*
X1282173D01*
G01X1272961D02*
X1274299D01*
G01X1265087D02*
X1266425D01*
G01X1257213D02*
X1258551D01*
G01X1249339D02*
X1250677D01*
G01X1241465D02*
X1242803D01*
G01X1242936Y520999D02*
X1241341D01*
G01X1246868D02*
X1245273D01*
G01X1250810D02*
X1249215D01*
G01X1254742D02*
X1253147D01*
G01X1258684D02*
X1257089D01*
G01X1262616D02*
X1261021D01*
G01X1266558D02*
X1264963D01*
G01X1270490D02*
X1268895D01*
G01X1274432D02*
X1272837D01*
G01X1278365D02*
X1276769D01*
G01X1282306D02*
X1280711D01*
G01X1286239D02*
X1284643D01*
G01X1290180D02*
X1288585D01*
G01X1294113D02*
X1292517D01*
G01X1298054D02*
X1296459D01*
G01X1301987D02*
X1300391D01*
G01X1305928D02*
X1304333D01*
G01X1243236Y520890D02*
X1241031D01*
G01X1247173D02*
X1244968D01*
G01X1251110D02*
X1248906D01*
G01X1255047D02*
X1252843D01*
G01X1258984D02*
X1256780D01*
G01X1262921D02*
X1260717D01*
G01X1266858D02*
X1264654D01*
G01X1270795D02*
X1268591D01*
G01X1274732D02*
X1272528D01*
G01X1278669D02*
X1276465D01*
G01X1282606D02*
X1280402D01*
G01X1286543D02*
X1284339D01*
G01X1290480D02*
X1288276D01*
G01X1294417D02*
X1292213D01*
G01X1298354D02*
X1296150D01*
G01X1302291D02*
X1300087D01*
G01X1306228D02*
X1304024D01*
G01X1243008Y520239D02*
X1241269D01*
G01X1246940D02*
X1245201D01*
G01X1250882D02*
X1249143D01*
G01X1254814D02*
X1253075D01*
G01X1258756D02*
X1257017D01*
G01X1262688D02*
X1260949D01*
G01X1266630D02*
X1264891D01*
G01X1270562D02*
X1268824D01*
G01X1274504D02*
X1272765D01*
G01X1278436D02*
X1276698D01*
G01X1282378D02*
X1280639D01*
G01X1286310D02*
X1284572D01*
G01X1290252D02*
X1288513D01*
G01X1294184D02*
X1292446D01*
G01X1298126D02*
X1296387D01*
G01X1302058D02*
X1300320D01*
G01X1306000D02*
X1304261D01*
G01X1304335Y520037D02*
X1305926D01*
G01X1300394D02*
X1301984D01*
G01X1296461D02*
X1298052D01*
G01X1292520D02*
X1294110D01*
G01X1288587D02*
X1290178D01*
G01X1284646D02*
X1286236D01*
G01X1280713D02*
X1282304D01*
G01X1276772D02*
X1278362D01*
G01X1272839D02*
X1274430D01*
G01X1268898D02*
X1270488D01*
G01X1264965D02*
X1266556D01*
G01X1261024D02*
X1262614D01*
G01X1257091D02*
X1258682D01*
G01X1253150D02*
X1254740D01*
G01X1249217D02*
X1250808D01*
G01X1245276D02*
X1246866D01*
G01X1241343D02*
X1242934D01*
G01X1304283Y520013D02*
X1305979D01*
G01X1300341D02*
X1302037D01*
G01X1296409D02*
X1298105D01*
G01X1292467D02*
X1294163D01*
G01X1288535D02*
X1290231D01*
G01X1284593D02*
X1286289D01*
G01X1280661D02*
X1282357D01*
G01X1276719D02*
X1278415D01*
G01X1272787D02*
X1274483D01*
G01X1268845D02*
X1270541D01*
G01X1264912D02*
X1266609D01*
G01X1260971D02*
X1262667D01*
G01X1257038D02*
X1258735D01*
G01X1253097D02*
X1254793D01*
G01X1249164D02*
X1250861D01*
G01X1245223D02*
X1246919D01*
G01X1241290D02*
X1242987D01*
G01X1242994Y519945D02*
X1241283D01*
G01X1246926D02*
X1245216D01*
G01X1250868D02*
X1249157D01*
G01X1254800D02*
X1253090D01*
G01X1258742D02*
X1257031D01*
G01X1262674D02*
X1260964D01*
G01X1266616D02*
X1264905D01*
G01X1270548D02*
X1268838D01*
G01X1274490D02*
X1272780D01*
G01X1278422D02*
X1276712D01*
G01X1282364D02*
X1280654D01*
G01X1286296D02*
X1284586D01*
G01X1290238D02*
X1288528D01*
G01X1294170D02*
X1292460D01*
G01X1298112D02*
X1296402D01*
G01X1302044D02*
X1300334D01*
G01X1305986D02*
X1304276D01*
G01X1304256Y519353D02*
X1306005D01*
G01X1300315D02*
X1302063D01*
G01X1296382D02*
X1298131D01*
G01X1292441D02*
X1294189D01*
G01X1288508D02*
X1290257D01*
G01X1284567D02*
X1286315D01*
G01X1280634D02*
X1282383D01*
G01X1276693D02*
X1278441D01*
G01X1272760D02*
X1274509D01*
G01X1268819D02*
X1270567D01*
G01X1264886D02*
X1266635D01*
G01X1260945D02*
X1262693D01*
G01X1257012D02*
X1258761D01*
G01X1253071D02*
X1254819D01*
G01X1249138D02*
X1250887D01*
G01X1245197D02*
X1246945D01*
G01X1241264D02*
X1243013D01*
G01X1242984Y519051D02*
X1241293D01*
G01X1246917D02*
X1245225D01*
G01X1250858D02*
X1249167D01*
G01X1254791D02*
X1253099D01*
G01X1258732D02*
X1257041D01*
G01X1262665D02*
X1260973D01*
G01X1266606D02*
X1264915D01*
G01X1270539D02*
X1268847D01*
G01X1274480D02*
X1272789D01*
G01X1278413D02*
X1276721D01*
G01X1282354D02*
X1280663D01*
G01X1286287D02*
X1284595D01*
G01X1290228D02*
X1288537D01*
G01X1294161D02*
X1292469D01*
G01X1298102D02*
X1296411D01*
G01X1302035D02*
X1300343D01*
G01X1305976D02*
X1304285D01*
G01X1242994Y518961D02*
X1241283D01*
G01X1246926D02*
X1245216D01*
G01X1250868D02*
X1249157D01*
G01X1254800D02*
X1253090D01*
G01X1258742D02*
X1257031D01*
G01X1262674D02*
X1260964D01*
G01X1266616D02*
X1264905D01*
G01X1270548D02*
X1268838D01*
G01X1274490D02*
X1272780D01*
G01X1278422D02*
X1276712D01*
G01X1282364D02*
X1280654D01*
G01X1286296D02*
X1284586D01*
G01X1290238D02*
X1288528D01*
G01X1294170D02*
X1292460D01*
G01X1298112D02*
X1296402D01*
G01X1302044D02*
X1300334D01*
G01X1305986D02*
X1304276D01*
G01X1304024Y518635D02*
X1306228D01*
G01X1300087D02*
X1302291D01*
G01X1296150D02*
X1298354D01*
G01X1292213D02*
X1294417D01*
G01X1288276D02*
X1290480D01*
G01X1284339D02*
X1286543D01*
G01X1280402D02*
X1282606D01*
G01X1276465D02*
X1278669D01*
G01X1272528D02*
X1274732D01*
G01X1268591D02*
X1270795D01*
G01X1264654D02*
X1266858D01*
G01X1260717D02*
X1262921D01*
G01X1256780D02*
X1258984D01*
G01X1252843D02*
X1255047D01*
G01X1248906D02*
X1251110D01*
G01X1244968D02*
X1247173D01*
G01X1241031D02*
X1243236D01*
G01X1304024Y518468D02*
X1306228D01*
G01X1300087D02*
X1302291D01*
G01X1296150D02*
X1298354D01*
G01X1292213D02*
X1294417D01*
G01X1288276D02*
X1290480D01*
G01X1284339D02*
X1286543D01*
G01X1280402D02*
X1282606D01*
G01X1276465D02*
X1278669D01*
G01X1272528D02*
X1274732D01*
G01X1268591D02*
X1270795D01*
G01X1264654D02*
X1266858D01*
G01X1260717D02*
X1262921D01*
G01X1256780D02*
X1258984D01*
G01X1252843D02*
X1255047D01*
G01X1248906D02*
X1251110D01*
G01X1244968D02*
X1247173D01*
G01X1241031D02*
X1243236D01*
G01Y515910D02*
X1241031D01*
G01X1247173D02*
X1244968D01*
G01X1251110D02*
X1248906D01*
G01X1255047D02*
X1252843D01*
G01X1258984D02*
X1256780D01*
G01X1262921D02*
X1260717D01*
G01X1266858D02*
X1264654D01*
G01X1270795D02*
X1268591D01*
G01X1274732D02*
X1272528D01*
G01X1278669D02*
X1276465D01*
G01X1282606D02*
X1280402D01*
G01X1286543D02*
X1284339D01*
G01X1290480D02*
X1288276D01*
G01X1294417D02*
X1292213D01*
G01X1298354D02*
X1296150D01*
G01X1302291D02*
X1300087D01*
G01X1306228D02*
X1304024D01*
G01X1243236Y515743D02*
X1241031D01*
G01X1247173D02*
X1244968D01*
G01X1251110D02*
X1248906D01*
G01X1255047D02*
X1252843D01*
G01X1258984D02*
X1256780D01*
G01X1262921D02*
X1260717D01*
G01X1266858D02*
X1264654D01*
G01X1270795D02*
X1268591D01*
G01X1274732D02*
X1272528D01*
G01X1278669D02*
X1276465D01*
G01X1282606D02*
X1280402D01*
G01X1286543D02*
X1284339D01*
G01X1290480D02*
X1288276D01*
G01X1294417D02*
X1292213D01*
G01X1298354D02*
X1296150D01*
G01X1302291D02*
X1300087D01*
G01X1306228D02*
X1304024D01*
G01X1304266Y515417D02*
X1305976D01*
G01X1300334D02*
X1302044D01*
G01X1296392D02*
X1298102D01*
G01X1292460D02*
X1294170D01*
G01X1288518D02*
X1290228D01*
G01X1284586D02*
X1286296D01*
G01X1280644D02*
X1282354D01*
G01X1276712D02*
X1278422D01*
G01X1272770D02*
X1274480D01*
G01X1268838D02*
X1270548D01*
G01X1264896D02*
X1266606D01*
G01X1260964D02*
X1262674D01*
G01X1257022D02*
X1258732D01*
G01X1253090D02*
X1254800D01*
G01X1249148D02*
X1250858D01*
G01X1245216D02*
X1246926D01*
G01X1241274D02*
X1242984D01*
G01X1304276Y515327D02*
X1305967D01*
G01X1300343D02*
X1302035D01*
G01X1296402D02*
X1298093D01*
G01X1292469D02*
X1294161D01*
G01X1288528D02*
X1290219D01*
G01X1284595D02*
X1286287D01*
G01X1280654D02*
X1282345D01*
G01X1276721D02*
X1278413D01*
G01X1272780D02*
X1274471D01*
G01X1268847D02*
X1270539D01*
G01X1264905D02*
X1266597D01*
G01X1260973D02*
X1262665D01*
G01X1257031D02*
X1258723D01*
G01X1253099D02*
X1254791D01*
G01X1249157D02*
X1250849D01*
G01X1245225D02*
X1246917D01*
G01X1241283D02*
X1242975D01*
G01X1243003Y515025D02*
X1241255D01*
G01X1246945D02*
X1245197D01*
G01X1250877D02*
X1249129D01*
G01X1254819D02*
X1253071D01*
G01X1258751D02*
X1257003D01*
G01X1262693D02*
X1260945D01*
G01X1266625D02*
X1264877D01*
G01X1270567D02*
X1268819D01*
G01X1274499D02*
X1272751D01*
G01X1278441D02*
X1276693D01*
G01X1282373D02*
X1280625D01*
G01X1286315D02*
X1284567D01*
G01X1290247D02*
X1288499D01*
G01X1294189D02*
X1292441D01*
G01X1298121D02*
X1296373D01*
G01X1302063D02*
X1300315D01*
G01X1305995D02*
X1304247D01*
G01X1304266Y514433D02*
X1305976D01*
G01X1300334D02*
X1302044D01*
G01X1296392D02*
X1298102D01*
G01X1292460D02*
X1294170D01*
G01X1288518D02*
X1290228D01*
G01X1284586D02*
X1286296D01*
G01X1280644D02*
X1282354D01*
G01X1276712D02*
X1278422D01*
G01X1272770D02*
X1274480D01*
G01X1268838D02*
X1270548D01*
G01X1264896D02*
X1266606D01*
G01X1260964D02*
X1262674D01*
G01X1257022D02*
X1258732D01*
G01X1253090D02*
X1254800D01*
G01X1249148D02*
X1250858D01*
G01X1245216D02*
X1246926D01*
G01X1241274D02*
X1242984D01*
G01X1242977Y514365D02*
X1241281D01*
G01X1246919D02*
X1245223D01*
G01X1250851D02*
X1249155D01*
G01X1254793D02*
X1253097D01*
G01X1258725D02*
X1257029D01*
G01X1262667D02*
X1260971D01*
G01X1266599D02*
X1264903D01*
G01X1270541D02*
X1268845D01*
G01X1274473D02*
X1272777D01*
G01X1278415D02*
X1276719D01*
G01X1282347D02*
X1280651D01*
G01X1286289D02*
X1284593D01*
G01X1290221D02*
X1288525D01*
G01X1294163D02*
X1292467D01*
G01X1298095D02*
X1296399D01*
G01X1302037D02*
X1300341D01*
G01X1305969D02*
X1304273D01*
G01X1242924Y514341D02*
X1241334D01*
G01X1246866D02*
X1245276D01*
G01X1250798D02*
X1249208D01*
G01X1254740D02*
X1253150D01*
G01X1258672D02*
X1257082D01*
G01X1262614D02*
X1261024D01*
G01X1266546D02*
X1264956D01*
G01X1270488D02*
X1268898D01*
G01X1274420D02*
X1272830D01*
G01X1278362D02*
X1276772D01*
G01X1282295D02*
X1280704D01*
G01X1286236D02*
X1284646D01*
G01X1290169D02*
X1288578D01*
G01X1294110D02*
X1292520D01*
G01X1298043D02*
X1296452D01*
G01X1301984D02*
X1300394D01*
G01X1305917D02*
X1304326D01*
G01X1304252Y514139D02*
X1305991D01*
G01X1300320D02*
X1302058D01*
G01X1296378D02*
X1298117D01*
G01X1292446D02*
X1294184D01*
G01X1288504D02*
X1290243D01*
G01X1284572D02*
X1286310D01*
G01X1280630D02*
X1282369D01*
G01X1276698D02*
X1278436D01*
G01X1272756D02*
X1274495D01*
G01X1268824D02*
X1270562D01*
G01X1264882D02*
X1266621D01*
G01X1260949D02*
X1262688D01*
G01X1257008D02*
X1258747D01*
G01X1253075D02*
X1254814D01*
G01X1249134D02*
X1250873D01*
G01X1245201D02*
X1246940D01*
G01X1241260D02*
X1242999D01*
G01X1304024Y513488D02*
X1306228D01*
G01X1300087D02*
X1302291D01*
G01X1296150D02*
X1298354D01*
G01X1292213D02*
X1294417D01*
G01X1288276D02*
X1290480D01*
G01X1284339D02*
X1286543D01*
G01X1280402D02*
X1282606D01*
G01X1276465D02*
X1278669D01*
G01X1272528D02*
X1274732D01*
G01X1268591D02*
X1270795D01*
G01X1264654D02*
X1266858D01*
G01X1260717D02*
X1262921D01*
G01X1256780D02*
X1258984D01*
G01X1252843D02*
X1255047D01*
G01X1248906D02*
X1251110D01*
G01X1244968D02*
X1247173D01*
G01X1241031D02*
X1243236D01*
G01X1304324Y513379D02*
X1305919D01*
G01X1300391D02*
X1301987D01*
G01X1296450D02*
X1298045D01*
G01X1292517D02*
X1294113D01*
G01X1288576D02*
X1290171D01*
G01X1284643D02*
X1286239D01*
G01X1280702D02*
X1282297D01*
G01X1276769D02*
X1278365D01*
G01X1272828D02*
X1274423D01*
G01X1268895D02*
X1270490D01*
G01X1264954D02*
X1266549D01*
G01X1261021D02*
X1262616D01*
G01X1257080D02*
X1258675D01*
G01X1253147D02*
X1254742D01*
G01X1249206D02*
X1250801D01*
G01X1245273D02*
X1246868D01*
G01X1241332D02*
X1242927D01*
G01X1242803Y512760D02*
X1241465D01*
G01X1250677D02*
X1249339D01*
G01X1258551D02*
X1257213D01*
G01X1266425D02*
X1265087D01*
G01X1274299D02*
X1272961D01*
G01X1282173D02*
X1280835D01*
G01X1290047D02*
X1288709D01*
G01X1297921D02*
X1296583D01*
G01X1305795D02*
X1304457D01*
G01X1242803Y511776D02*
X1241465D01*
G01X1250677D02*
X1249339D01*
G01X1258551D02*
X1257213D01*
G01X1266425D02*
X1265087D01*
G01X1274299D02*
X1272961D01*
G01X1282173D02*
X1280835D01*
G01X1290047D02*
X1288709D01*
G01X1297921D02*
X1296583D01*
G01X1305795D02*
X1304457D01*
G01X1304299Y511677D02*
X1305953D01*
G01X1296425D02*
X1298079D01*
G01X1288551D02*
X1290205D01*
G01X1280677D02*
X1282331D01*
G01X1272803D02*
X1274457D01*
G01X1264929D02*
X1266583D01*
G01X1257055D02*
X1258709D01*
G01X1249181D02*
X1250835D01*
G01X1241307D02*
X1242961D01*
G01Y511185D02*
X1241307D01*
G01X1250835D02*
X1249181D01*
G01X1258709D02*
X1257055D01*
G01X1266583D02*
X1264929D01*
G01X1274457D02*
X1272803D01*
G01X1282331D02*
X1280677D01*
G01X1290205D02*
X1288551D01*
G01X1298079D02*
X1296425D01*
G01X1305953D02*
X1304299D01*
G01X1304648Y525368D02*
X1304394Y525738D01*
G01X1304602Y524441D02*
X1304381Y524763D01*
G01X1300706Y525368D02*
X1300452Y525738D01*
G01X1300441Y524760D02*
X1300661Y524441D01*
G01X1296774Y525368D02*
X1296520Y525738D01*
G01X1296728Y524441D02*
X1296507Y524763D01*
G01X1305650Y509937D02*
X1305871Y509615D01*
G01X1305604Y509010D02*
X1305858Y508640D01*
G01X1242890Y510571D02*
X1241368D01*
G01X1246832D02*
X1245310D01*
G01X1250764D02*
X1249242D01*
G01X1254706D02*
X1253184D01*
G01X1258638D02*
X1257117D01*
G01X1262580D02*
X1261058D01*
G01X1266512D02*
X1264991D01*
G01X1270454D02*
X1268932D01*
G01X1274386D02*
X1272865D01*
G01X1278328D02*
X1276806D01*
G01X1282260D02*
X1280739D01*
G01X1286202D02*
X1284680D01*
G01X1290134D02*
X1288613D01*
G01X1294076D02*
X1292554D01*
G01X1298008D02*
X1296487D01*
G01X1301950D02*
X1300428D01*
G01X1305882D02*
X1304361D01*
G01X1242901Y510552D02*
X1241358D01*
G01X1246843D02*
X1245299D01*
G01X1250775D02*
X1249232D01*
G01X1254717D02*
X1253173D01*
G01X1258649D02*
X1257106D01*
G01X1262591D02*
X1261047D01*
G01X1266523D02*
X1264980D01*
G01X1270465D02*
X1268921D01*
G01X1274397D02*
X1272854D01*
G01X1278339D02*
X1276795D01*
G01X1282271D02*
X1280728D01*
G01X1286213D02*
X1284669D01*
G01X1290145D02*
X1288602D01*
G01X1294087D02*
X1292543D01*
G01X1298019D02*
X1296476D01*
G01X1301961D02*
X1300417D01*
G01X1305893D02*
X1304350D01*
G01X1241031Y510516D02*
X1240717D01*
G01X1243551D02*
X1243236D01*
G01X1244968D02*
X1244654D01*
G01X1247488D02*
X1247173D01*
G01X1248906D02*
X1248591D01*
G01X1251425D02*
X1251110D01*
G01X1252843D02*
X1252528D01*
G01X1256780D02*
X1256465D01*
G01X1255362D02*
X1255047D01*
G01X1259299D02*
X1258984D01*
G01X1260717D02*
X1260402D01*
G01X1263236D02*
X1262921D01*
G01X1264654D02*
X1264339D01*
G01X1267173D02*
X1266858D01*
G01X1268591D02*
X1268276D01*
G01X1271110D02*
X1270795D01*
G01X1272528D02*
X1272213D01*
G01X1275047D02*
X1274732D01*
G01X1276465D02*
X1276150D01*
G01X1278984D02*
X1278669D01*
G01X1280402D02*
X1280087D01*
G01X1282921D02*
X1282606D01*
G01X1284339D02*
X1284024D01*
G01X1288276D02*
X1287961D01*
G01X1286858D02*
X1286543D01*
G01X1290795D02*
X1290480D01*
G01X1292213D02*
X1291898D01*
G01X1294732D02*
X1294417D01*
G01X1296150D02*
X1295835D01*
G01X1298669D02*
X1298354D01*
G01X1300087D02*
X1299772D01*
G01X1302606D02*
X1302291D01*
G01X1304024D02*
X1303709D01*
G01X1306543D02*
X1306228D01*
G01X1307961D02*
X1307646D01*
G01X1243315Y509984D02*
X1240953D01*
G01X1247252D02*
X1244890D01*
G01X1251189D02*
X1248827D01*
G01X1255126D02*
X1252764D01*
G01X1259063D02*
X1256701D01*
G01X1263000D02*
X1260638D01*
G01X1266937D02*
X1264575D01*
G01X1270874D02*
X1268512D01*
G01X1274811D02*
X1272449D01*
G01X1278748D02*
X1276386D01*
G01X1282685D02*
X1280323D01*
G01X1286622D02*
X1284260D01*
G01X1290559D02*
X1288197D01*
G01X1294496D02*
X1292134D01*
G01X1298433D02*
X1296071D01*
G01X1302370D02*
X1300008D01*
G01X1306307D02*
X1303945D01*
G01X1242657Y509937D02*
X1241601D01*
G01X1246599D02*
X1245543D01*
G01X1250531D02*
X1249475D01*
G01X1254473D02*
X1253417D01*
G01X1258406D02*
X1257349D01*
G01X1262347D02*
X1261291D01*
G01X1266280D02*
X1265223D01*
G01X1270221D02*
X1269165D01*
G01X1274154D02*
X1273097D01*
G01X1278095D02*
X1277039D01*
G01X1282028D02*
X1280971D01*
G01X1285969D02*
X1284913D01*
G01X1289902D02*
X1288845D01*
G01X1293843D02*
X1292787D01*
G01X1297776D02*
X1296719D01*
G01X1301717D02*
X1300661D01*
G01X1305650D02*
X1304593D01*
G01X1304373Y509615D02*
X1305870D01*
G01X1300441D02*
X1301937D01*
G01X1296499D02*
X1297996D01*
G01X1292567D02*
X1294063D01*
G01X1288625D02*
X1290122D01*
G01X1284693D02*
X1286189D01*
G01X1280751D02*
X1282247D01*
G01X1276819D02*
X1278315D01*
G01X1272877D02*
X1274373D01*
G01X1268945D02*
X1270441D01*
G01X1265003D02*
X1266499D01*
G01X1261071D02*
X1262567D01*
G01X1257129D02*
X1258625D01*
G01X1253197D02*
X1254693D01*
G01X1249255D02*
X1250751D01*
G01X1245323D02*
X1246819D01*
G01X1241381D02*
X1242877D01*
G01X1304372Y509606D02*
X1305871D01*
G01X1300439D02*
X1301939D01*
G01X1296498D02*
X1297997D01*
G01X1292565D02*
X1294065D01*
G01X1288624D02*
X1290123D01*
G01X1284691D02*
X1286191D01*
G01X1280750D02*
X1282249D01*
G01X1276817D02*
X1278317D01*
G01X1272876D02*
X1274375D01*
G01X1268943D02*
X1270443D01*
G01X1265002D02*
X1266501D01*
G01X1261069D02*
X1262569D01*
G01X1257127D02*
X1258627D01*
G01X1253195D02*
X1254695D01*
G01X1249253D02*
X1250753D01*
G01X1245321D02*
X1246821D01*
G01X1241379D02*
X1242879D01*
G01X1242961Y509413D02*
X1241307D01*
G01X1250835D02*
X1249181D01*
G01X1258709D02*
X1257055D01*
G01X1266583D02*
X1264929D01*
G01X1274457D02*
X1272803D01*
G01X1282331D02*
X1280677D01*
G01X1290205D02*
X1288551D01*
G01X1298079D02*
X1296425D01*
G01X1305953D02*
X1304299D01*
G01X1304111Y509117D02*
X1306132D01*
G01X1300179D02*
X1302199D01*
G01X1296237D02*
X1298258D01*
G01X1292305D02*
X1294325D01*
G01X1288363D02*
X1290384D01*
G01X1284431D02*
X1286451D01*
G01X1280489D02*
X1282510D01*
G01X1276557D02*
X1278577D01*
G01X1272615D02*
X1274636D01*
G01X1268682D02*
X1270703D01*
G01X1264741D02*
X1266762D01*
G01X1260808D02*
X1262829D01*
G01X1256867D02*
X1258888D01*
G01X1252934D02*
X1254955D01*
G01X1248993D02*
X1251014D01*
G01X1245060D02*
X1247081D01*
G01X1241119D02*
X1243140D01*
G01X1306228Y509020D02*
X1306543D01*
G01X1298354D02*
X1298669D01*
G01X1294417D02*
X1294732D01*
G01X1290480D02*
X1290795D01*
G01X1286543D02*
X1286858D01*
G01X1282606D02*
X1282921D01*
G01X1278669D02*
X1278984D01*
G01X1274732D02*
X1275047D01*
G01X1270795D02*
X1271110D01*
G01X1266858D02*
X1267173D01*
G01X1262921D02*
X1263236D01*
G01X1258984D02*
X1259299D01*
G01X1255047D02*
X1255362D01*
G01X1251110D02*
X1251425D01*
G01X1247173D02*
X1247488D01*
G01X1243236D02*
X1243551D01*
G01X1241031D02*
X1240717D01*
G01X1244968D02*
X1244654D01*
G01X1248906D02*
X1248591D01*
G01X1252843D02*
X1252528D01*
G01X1256780D02*
X1256465D01*
G01X1260717D02*
X1260402D01*
G01X1264654D02*
X1264339D01*
G01X1268591D02*
X1268276D01*
G01X1272528D02*
X1272213D01*
G01X1276465D02*
X1276150D01*
G01X1280402D02*
X1280087D01*
G01X1284339D02*
X1284024D01*
G01X1288276D02*
X1287961D01*
G01X1292213D02*
X1291898D01*
G01X1296150D02*
X1295835D01*
G01X1300087D02*
X1299772D01*
G01X1302606D02*
X1302291D01*
G01X1304024D02*
X1303709D01*
G01X1307961D02*
X1307646D01*
G01X1304639Y509010D02*
X1305604D01*
G01X1300706D02*
X1301672D01*
G01X1296765D02*
X1297730D01*
G01X1292832D02*
X1293798D01*
G01X1288891D02*
X1289856D01*
G01X1284958D02*
X1285924D01*
G01X1281017D02*
X1281982D01*
G01X1277084D02*
X1278050D01*
G01X1273143D02*
X1274108D01*
G01X1269210D02*
X1270176D01*
G01X1265269D02*
X1266234D01*
G01X1261336D02*
X1262302D01*
G01X1257395D02*
X1258360D01*
G01X1253462D02*
X1254428D01*
G01X1249521D02*
X1250486D01*
G01X1245588D02*
X1246554D01*
G01X1241647D02*
X1242612D01*
G01X1304299Y508921D02*
X1305953D01*
G01X1296425D02*
X1298079D01*
G01X1288551D02*
X1290205D01*
G01X1280677D02*
X1282331D01*
G01X1272803D02*
X1274457D01*
G01X1264929D02*
X1266583D01*
G01X1257055D02*
X1258709D01*
G01X1249181D02*
X1250835D01*
G01X1241307D02*
X1242961D01*
G01X1307646Y508823D02*
X1310480D01*
G01X1303709D02*
X1306543D01*
G01X1299772D02*
X1302606D01*
G01X1295835D02*
X1298669D01*
G01X1291898D02*
X1294732D01*
G01X1287961D02*
X1290795D01*
G01X1284024D02*
X1286858D01*
G01X1280087D02*
X1282921D01*
G01X1276150D02*
X1278984D01*
G01X1272213D02*
X1275047D01*
G01X1268276D02*
X1271110D01*
G01X1264339D02*
X1267173D01*
G01X1260402D02*
X1263236D01*
G01X1256465D02*
X1259299D01*
G01X1252528D02*
X1255362D01*
G01X1248591D02*
X1251425D01*
G01X1244654D02*
X1247488D01*
G01X1240717D02*
X1243551D01*
G01X1307646Y508665D02*
X1308236D01*
G01X1305953D02*
X1306543D01*
G01X1303709D02*
X1304299D01*
G01X1302016D02*
X1302606D01*
G01X1299772D02*
X1300362D01*
G01X1298079D02*
X1298669D01*
G01X1295835D02*
X1296425D01*
G01X1294142D02*
X1294732D01*
G01X1291898D02*
X1292488D01*
G01X1290205D02*
X1290795D01*
G01X1287961D02*
X1288551D01*
G01X1286268D02*
X1286858D01*
G01X1284024D02*
X1284614D01*
G01X1282331D02*
X1282921D01*
G01X1280087D02*
X1280677D01*
G01X1278394D02*
X1278984D01*
G01X1276150D02*
X1276740D01*
G01X1274457D02*
X1275047D01*
G01X1272213D02*
X1272803D01*
G01X1270520D02*
X1271110D01*
G01X1268276D02*
X1268866D01*
G01X1266583D02*
X1267173D01*
G01X1264339D02*
X1264929D01*
G01X1262646D02*
X1263236D01*
G01X1260402D02*
X1260992D01*
G01X1258709D02*
X1259299D01*
G01X1256465D02*
X1257055D01*
G01X1254772D02*
X1255362D01*
G01X1252528D02*
X1253118D01*
G01X1250835D02*
X1251425D01*
G01X1248591D02*
X1249181D01*
G01X1246898D02*
X1247488D01*
G01X1244654D02*
X1245244D01*
G01X1242961D02*
X1243551D01*
G01X1240717D02*
X1241307D01*
G01X1242866Y508640D02*
X1241393D01*
G01X1246807D02*
X1245334D01*
G01X1250740D02*
X1249267D01*
G01X1254681D02*
X1253208D01*
G01X1258614D02*
X1257141D01*
G01X1262555D02*
X1261082D01*
G01X1266488D02*
X1265015D01*
G01X1270429D02*
X1268956D01*
G01X1274362D02*
X1272889D01*
G01X1278303D02*
X1276830D01*
G01X1282236D02*
X1280763D01*
G01X1286177D02*
X1284704D01*
G01X1290110D02*
X1288637D01*
G01X1294051D02*
X1292578D01*
G01X1297984D02*
X1296511D01*
G01X1301925D02*
X1300452D01*
G01X1305858D02*
X1304385D01*
G01X1304372Y508621D02*
X1305871D01*
G01X1300439D02*
X1301939D01*
G01X1296498D02*
X1297997D01*
G01X1292565D02*
X1294065D01*
G01X1288624D02*
X1290123D01*
G01X1284691D02*
X1286191D01*
G01X1280750D02*
X1282249D01*
G01X1276817D02*
X1278317D01*
G01X1272876D02*
X1274375D01*
G01X1268943D02*
X1270443D01*
G01X1265002D02*
X1266501D01*
G01X1261069D02*
X1262569D01*
G01X1257127D02*
X1258627D01*
G01X1253195D02*
X1254695D01*
G01X1249253D02*
X1250753D01*
G01X1245321D02*
X1246821D01*
G01X1241379D02*
X1242879D01*
G01X1243135Y508231D02*
X1241124D01*
G01X1247076D02*
X1245065D01*
G01X1251009D02*
X1248998D01*
G01X1254951D02*
X1252939D01*
G01X1258883D02*
X1256872D01*
G01X1262825D02*
X1260813D01*
G01X1266757D02*
X1264746D01*
G01X1270699D02*
X1268687D01*
G01X1274631D02*
X1272620D01*
G01X1278573D02*
X1276561D01*
G01X1282505D02*
X1280494D01*
G01X1286447D02*
X1284435D01*
G01X1290379D02*
X1288368D01*
G01X1294321D02*
X1292309D01*
G01X1298253D02*
X1296242D01*
G01X1302195D02*
X1300183D01*
G01X1306127D02*
X1304116D01*
G01X1241307Y507996D02*
X1240717D01*
G01X1243551D02*
X1242961D01*
G01X1245244D02*
X1244654D01*
G01X1247488D02*
X1246898D01*
G01X1249181D02*
X1248591D01*
G01X1251425D02*
X1250835D01*
G01X1253118D02*
X1252528D01*
G01X1255362D02*
X1254772D01*
G01X1257055D02*
X1256465D01*
G01X1259299D02*
X1258709D01*
G01X1260992D02*
X1260402D01*
G01X1263236D02*
X1262646D01*
G01X1264929D02*
X1264339D01*
G01X1267173D02*
X1266583D01*
G01X1268866D02*
X1268276D01*
G01X1271110D02*
X1270520D01*
G01X1272803D02*
X1272213D01*
G01X1275047D02*
X1274457D01*
G01X1276740D02*
X1276150D01*
G01X1278984D02*
X1278394D01*
G01X1280677D02*
X1280087D01*
G01X1282921D02*
X1282331D01*
G01X1284614D02*
X1284024D01*
G01X1286858D02*
X1286268D01*
G01X1288551D02*
X1287961D01*
G01X1290795D02*
X1290205D01*
G01X1292488D02*
X1291898D01*
G01X1294732D02*
X1294142D01*
G01X1296425D02*
X1295835D01*
G01X1298669D02*
X1298079D01*
G01X1300362D02*
X1299772D01*
G01X1302606D02*
X1302016D01*
G01X1304299D02*
X1303709D01*
G01X1306543D02*
X1305953D01*
G01X1308236D02*
X1307646D01*
G01X1243551Y507839D02*
X1240717D01*
G01X1247488D02*
X1244654D01*
G01X1251425D02*
X1248591D01*
G01X1255362D02*
X1252528D01*
G01X1259299D02*
X1256465D01*
G01X1263236D02*
X1260402D01*
G01X1267173D02*
X1264339D01*
G01X1271110D02*
X1268276D01*
G01X1275047D02*
X1272213D01*
G01X1278984D02*
X1276150D01*
G01X1282921D02*
X1280087D01*
G01X1286858D02*
X1284024D01*
G01X1290795D02*
X1287961D01*
G01X1294732D02*
X1291898D01*
G01X1298669D02*
X1295835D01*
G01X1302606D02*
X1299772D01*
G01X1306543D02*
X1303709D01*
G01X1310480D02*
X1307646D01*
G01X1246898Y507740D02*
X1245244D01*
G01X1254772D02*
X1253118D01*
G01X1262646D02*
X1260992D01*
G01X1270520D02*
X1268866D01*
G01X1278394D02*
X1276740D01*
G01X1286268D02*
X1284614D01*
G01X1294142D02*
X1292488D01*
G01X1302016D02*
X1300362D01*
G01Y507248D02*
X1302016D01*
G01X1292488D02*
X1294142D01*
G01X1284614D02*
X1286268D01*
G01X1276740D02*
X1278394D01*
G01X1268866D02*
X1270520D01*
G01X1260992D02*
X1262646D01*
G01X1253118D02*
X1254772D01*
G01X1245244D02*
X1246898D01*
G01X1307646Y506343D02*
X1310480D01*
G01X1303709D02*
X1306543D01*
G01X1299772D02*
X1302606D01*
G01X1295835D02*
X1298669D01*
G01X1291898D02*
X1294732D01*
G01X1287961D02*
X1290795D01*
G01X1284024D02*
X1286858D01*
G01X1280087D02*
X1282921D01*
G01X1276150D02*
X1278984D01*
G01X1272213D02*
X1275047D01*
G01X1268276D02*
X1271110D01*
G01X1264339D02*
X1267173D01*
G01X1260402D02*
X1263236D01*
G01X1256465D02*
X1259299D01*
G01X1252528D02*
X1255362D01*
G01X1248591D02*
X1251425D01*
G01X1244654D02*
X1247488D01*
G01X1240717D02*
X1243551D01*
G01X1300362Y505476D02*
X1302016D01*
G01X1292488D02*
X1294142D01*
G01X1284614D02*
X1286268D01*
G01X1276740D02*
X1278394D01*
G01X1268866D02*
X1270520D01*
G01X1260992D02*
X1262646D01*
G01X1253118D02*
X1254772D01*
G01X1245244D02*
X1246898D01*
G01X1303945Y505083D02*
X1306307D01*
G01X1300008D02*
X1302370D01*
G01X1296071D02*
X1298433D01*
G01X1243315D02*
X1240953D01*
G01X1247252D02*
X1244890D01*
G01X1251189D02*
X1248827D01*
G01X1255126D02*
X1252764D01*
G01X1259063D02*
X1256701D01*
G01X1263000D02*
X1260638D01*
G01X1266937D02*
X1264575D01*
G01X1270874D02*
X1268512D01*
G01X1274811D02*
X1272449D01*
G01X1278748D02*
X1276386D01*
G01X1282685D02*
X1280323D01*
G01X1286622D02*
X1284260D01*
G01X1290559D02*
X1288197D01*
G01X1294496D02*
X1292134D01*
G01X1246898Y504984D02*
X1245244D01*
G01X1254772D02*
X1253118D01*
G01X1262646D02*
X1260992D01*
G01X1270520D02*
X1268866D01*
G01X1278394D02*
X1276740D01*
G01X1286268D02*
X1284614D01*
G01X1294142D02*
X1292488D01*
G01X1302016D02*
X1300362D01*
G01X1246740Y504886D02*
X1245402D01*
G01X1254614D02*
X1253276D01*
G01X1262488D02*
X1261150D01*
G01X1270362D02*
X1269024D01*
G01X1278236D02*
X1276898D01*
G01X1286110D02*
X1284772D01*
G01X1293984D02*
X1292646D01*
G01X1301858D02*
X1300520D01*
G01X1303945Y503902D02*
X1306307D01*
G01X1300008D02*
X1302370D01*
G01X1296071D02*
X1298433D01*
G01X1292134D02*
X1294496D01*
G01X1288197D02*
X1290559D01*
G01X1284260D02*
X1286622D01*
G01X1280323D02*
X1282685D01*
G01X1276386D02*
X1278748D01*
G01X1272449D02*
X1274811D01*
G01X1268512D02*
X1270874D01*
G01X1264575D02*
X1266937D01*
G01X1260638D02*
X1263000D01*
G01X1256701D02*
X1259063D01*
G01X1252764D02*
X1255126D01*
G01X1248827D02*
X1251189D01*
G01X1244890D02*
X1247252D01*
G01X1240953D02*
X1243315D01*
G01X1304602Y524441D02*
X1304612Y524394D01*
G01X1305650Y509937D02*
X1305640Y509984D01*
G01X1300670Y524394D02*
X1300661Y524441D01*
G01X1301708Y509984D02*
X1301717Y509937D01*
G01X1296728Y524441D02*
X1296738Y524394D01*
G01X1292578Y525738D02*
X1292832Y525368D01*
G01X1292787Y524441D02*
X1292565Y524763D01*
G01X1301937Y509618D02*
X1301717Y509937D01*
G01X1301672Y509010D02*
X1301925Y508640D01*
G01X1288646Y525738D02*
X1288900Y525368D01*
G01X1288854Y524441D02*
X1288633Y524763D01*
G01X1297776Y509937D02*
X1297997Y509615D01*
G01X1297730Y509010D02*
X1297984Y508640D01*
G01X1284704Y525738D02*
X1284958Y525368D01*
G01X1284913Y524441D02*
X1284691Y524763D01*
G01X1293843Y509937D02*
X1294065Y509615D01*
G01X1294051Y508640D02*
X1293798Y509010D01*
G01X1280772Y525738D02*
X1281026Y525368D01*
G01X1280980Y524441D02*
X1280759Y524763D01*
G01X1289902Y509937D02*
X1290123Y509615D01*
G01X1290110Y508640D02*
X1289856Y509010D01*
G01X1276830Y525738D02*
X1277084Y525368D01*
G01X1277039Y524441D02*
X1276817Y524763D01*
G01X1285969Y509937D02*
X1286191Y509615D01*
G01X1286177Y508640D02*
X1285924Y509010D01*
G01X1272898Y525738D02*
X1273152Y525368D01*
G01X1273106Y524441D02*
X1272885Y524763D01*
G01X1282028Y509937D02*
X1282249Y509615D01*
G01X1282236Y508640D02*
X1281982Y509010D01*
G01X1268956Y525738D02*
X1269210Y525368D01*
G01X1269165Y524441D02*
X1268943Y524763D01*
G01X1278095Y509937D02*
X1278317Y509615D01*
G01X1278303Y508640D02*
X1278050Y509010D01*
G01X1265024Y525738D02*
X1265278Y525368D01*
G01X1265232Y524441D02*
X1265011Y524763D01*
G01X1305979Y520013D02*
X1305928Y520999D01*
G01X1305926Y520037D02*
X1305976Y519051D01*
G01X1297776Y509937D02*
X1297766Y509984D01*
G01X1292787Y524441D02*
X1292796Y524394D01*
G01X1293843Y509937D02*
X1293834Y509984D01*
G01X1288854Y524441D02*
X1288864Y524394D01*
G01X1289902Y509937D02*
X1289892Y509984D01*
G01X1284913Y524441D02*
X1284922Y524394D01*
G01X1285969Y509937D02*
X1285960Y509984D01*
G01X1280980Y524441D02*
X1280990Y524394D01*
G01X1282028Y509937D02*
X1282018Y509984D01*
G01X1277039Y524441D02*
X1277048Y524394D01*
G01X1278095Y509937D02*
X1278086Y509984D01*
G01X1273106Y524441D02*
X1273116Y524394D01*
G01X1274154Y509937D02*
X1274144Y509984D01*
G01X1274154Y509937D02*
X1274375Y509615D01*
G01X1274362Y508640D02*
X1274108Y509010D01*
G01X1261082Y525738D02*
X1261336Y525368D01*
G01X1261291Y524441D02*
X1261069Y524763D01*
G01X1270221Y509937D02*
X1270443Y509615D01*
G01X1270429Y508640D02*
X1270176Y509010D01*
G01X1257150Y525738D02*
X1257404Y525368D01*
G01X1257358Y524441D02*
X1257137Y524763D01*
G01X1266280Y509937D02*
X1266501Y509615D01*
G01X1266488Y508640D02*
X1266234Y509010D01*
G01X1253208Y525738D02*
X1253462Y525368D01*
G01X1253417Y524441D02*
X1253195Y524763D01*
G01X1262347Y509937D02*
X1262569Y509615D01*
G01X1262555Y508640D02*
X1262302Y509010D01*
G01X1249276Y525738D02*
X1249530Y525368D01*
G01X1249484Y524441D02*
X1249263Y524763D01*
G01X1258406Y509937D02*
X1258627Y509615D01*
G01X1258614Y508640D02*
X1258360Y509010D01*
G01X1245334Y525738D02*
X1245588Y525368D01*
G01X1245543Y524441D02*
X1245321Y524763D01*
G01X1254473Y509937D02*
X1254695Y509615D01*
G01X1254681Y508640D02*
X1254428Y509010D01*
G01X1241402Y525738D02*
X1241656Y525368D01*
G01X1241610Y524441D02*
X1241389Y524763D01*
G01X1250531Y509937D02*
X1250753Y509615D01*
G01X1250740Y508640D02*
X1250486Y509010D01*
G01X1246599Y509937D02*
X1246820Y509615D01*
G01X1246807Y508640D02*
X1246554Y509010D01*
G01X1304603Y509984D02*
X1304593Y509937D01*
G01X1305649Y524394D02*
X1305659Y524441D01*
G01X1300661Y509937D02*
X1300670Y509984D01*
G01X1301717Y524441D02*
X1301708Y524394D01*
G01X1296729Y509984D02*
X1296719Y509937D01*
G01X1297775Y524394D02*
X1297785Y524441D01*
G01X1305919Y513379D02*
X1305969Y514365D01*
G01X1305967Y515327D02*
X1305917Y514341D01*
G01X1304285Y519051D02*
X1304335Y520037D01*
G01X1304333Y520999D02*
X1304283Y520013D01*
G01X1301987Y513379D02*
X1302037Y514365D01*
G01X1302035Y515327D02*
X1301984Y514341D01*
G01X1300343Y519051D02*
X1300394Y520037D01*
G01X1300391Y520999D02*
X1300341Y520013D01*
G01X1298045Y513379D02*
X1298095Y514365D01*
G01X1298093Y515327D02*
X1298043Y514341D01*
G01X1296411Y519051D02*
X1296461Y520037D01*
G01X1296459Y520999D02*
X1296409Y520013D01*
G01X1294113Y513379D02*
X1294163Y514365D01*
G01X1294161Y515327D02*
X1294110Y514341D01*
G01X1292469Y519051D02*
X1292520Y520037D01*
G01X1292517Y520999D02*
X1292467Y520013D01*
G01X1290171Y513379D02*
X1290221Y514365D01*
G01X1290219Y515327D02*
X1290169Y514341D01*
G01X1288537Y519051D02*
X1288587Y520037D01*
G01X1288585Y520999D02*
X1288535Y520013D01*
G01X1306005Y519353D02*
X1306141Y525261D01*
G01X1306136Y526147D02*
X1306000Y520239D01*
G01X1304116Y508231D02*
X1304252Y514139D01*
G01X1304247Y515025D02*
X1304111Y509117D01*
G01X1302063Y519353D02*
X1302199Y525261D01*
G01X1302195Y526147D02*
X1302058Y520239D01*
G01X1300183Y508231D02*
X1300320Y514139D01*
G01X1300315Y515025D02*
X1300179Y509117D01*
G01X1298131Y519353D02*
X1298267Y525261D01*
G01X1298262Y526147D02*
X1298126Y520239D01*
G01X1296242Y508231D02*
X1296378Y514139D01*
G01X1296373Y515025D02*
X1296237Y509117D01*
G01X1294189Y519353D02*
X1294325Y525261D01*
G01X1294321Y526147D02*
X1294184Y520239D01*
G01X1292309Y508231D02*
X1292446Y514139D01*
G01X1292441Y515025D02*
X1292305Y509117D01*
G01X1290257Y519353D02*
X1290393Y525261D01*
G01X1290388Y526147D02*
X1290252Y520239D01*
G01X1288368Y508231D02*
X1288504Y514139D01*
G01X1288499Y515025D02*
X1288363Y509117D01*
G01X1286315Y519353D02*
X1286451Y525261D01*
G01X1286447Y526147D02*
X1286310Y520239D01*
G01X1305617Y509984D02*
X1305604Y509010D01*
G01X1304635Y524394D02*
X1304648Y525368D01*
G01X1301685Y509984D02*
X1301672Y509010D01*
G01X1300693Y524394D02*
X1300706Y525368D01*
G01X1297743Y509984D02*
X1297730Y509010D01*
G01X1296761Y524394D02*
X1296774Y525368D01*
G01X1293811Y509984D02*
X1293798Y509010D01*
G01X1292819Y524394D02*
X1292832Y525368D01*
G01X1289869Y509984D02*
X1289856Y509010D01*
G01X1288887Y524394D02*
X1288900Y525368D01*
G01X1285937Y509984D02*
X1285924Y509010D01*
G01X1307685Y508823D02*
Y507839D01*
G01Y526539D02*
Y525555D01*
G01X1307680Y526539D02*
Y525555D01*
G01X1307646Y510516D02*
Y506343D01*
G01Y528035D02*
Y523862D01*
G01X1306543D02*
Y528035D01*
G01Y506343D02*
Y510516D01*
G01X1306509Y526539D02*
Y525555D01*
G01X1306504Y508823D02*
Y507839D01*
G01X1306499Y508823D02*
Y507839D01*
G01X1306307Y509984D02*
Y503902D01*
G01Y530476D02*
Y524394D01*
G01X1306228Y507839D02*
Y526539D01*
G01X1306154Y526538D02*
Y525553D01*
G01X1306145Y508825D02*
Y507840D01*
G01X1305953Y521698D02*
Y526539D01*
G01Y507839D02*
Y512680D01*
G01X1305879Y524760D02*
Y525751D01*
G01X1305869Y508627D02*
Y509618D01*
G01X1305795Y512760D02*
Y511696D01*
G01Y522681D02*
Y521618D01*
G01X1305520D02*
Y522602D01*
G01Y512760D02*
Y511776D01*
G01X1304732Y521618D02*
Y522602D01*
G01Y512760D02*
Y511776D01*
G01X1304457Y512760D02*
Y511696D01*
G01Y522682D02*
Y521618D01*
G01X1304383Y525751D02*
Y524760D01*
G01X1304373Y509618D02*
Y508627D01*
G01X1304299Y521698D02*
Y526539D01*
G01Y507839D02*
Y512680D01*
G01X1304107Y525553D02*
Y526538D01*
G01X1304098Y507840D02*
Y508825D01*
G01X1304024Y526539D02*
Y507839D01*
G01X1303945Y509984D02*
Y503902D01*
G01Y530476D02*
Y524394D01*
G01X1303753Y526539D02*
Y525555D01*
G01X1303748Y526539D02*
Y525555D01*
G01X1303743Y508823D02*
Y507839D01*
G01X1303709Y510516D02*
Y506343D01*
G01Y528035D02*
Y523862D01*
G01X1302606D02*
Y528035D01*
G01Y506343D02*
Y510516D01*
G01X1302572Y508823D02*
Y507839D01*
G01X1302567Y508823D02*
Y507839D01*
G01Y526539D02*
Y525555D01*
G01X1302370Y509984D02*
Y503902D01*
G01Y530476D02*
Y524394D01*
G01X1302291Y507839D02*
Y526539D01*
G01X1302213Y508825D02*
Y507840D01*
G01Y526538D02*
Y525553D01*
G01X1302016Y525555D02*
Y530396D01*
G01Y503982D02*
Y508823D01*
G01X1301937Y524760D02*
Y525751D01*
G01Y508627D02*
Y509618D01*
G01X1301858Y504965D02*
Y503902D01*
G01Y530476D02*
Y529413D01*
G01X1301583Y503902D02*
Y504886D01*
G01Y530476D02*
Y529492D01*
G01X1300795Y504886D02*
Y503902D01*
G01Y530476D02*
Y529492D01*
G01X1300520Y504965D02*
Y503902D01*
G01Y530476D02*
Y529413D01*
G01X1300441Y509618D02*
Y508627D01*
G01Y525751D02*
Y524760D01*
G01X1300362Y525555D02*
Y530396D01*
G01Y503982D02*
Y508823D01*
G01X1300165Y507840D02*
Y508825D01*
G01Y525553D02*
Y526538D01*
G01X1300087Y526539D02*
Y507839D01*
G01X1300008Y509984D02*
Y503902D01*
G01Y530476D02*
Y524394D01*
G01X1299811Y508823D02*
Y507839D01*
G01Y526539D02*
Y525555D01*
G01X1299806Y526539D02*
Y525555D01*
G01X1299772Y510516D02*
Y506343D01*
G01Y528035D02*
Y523862D01*
G01X1298669D02*
Y528035D01*
G01Y506343D02*
Y510516D01*
G01X1298635Y526539D02*
Y525555D01*
G01X1298630Y508823D02*
Y507839D01*
G01X1298625Y508823D02*
Y507839D01*
G01X1298433Y509984D02*
Y503902D01*
G01Y530476D02*
Y524394D01*
G01X1298354Y507839D02*
Y526539D01*
G01X1298280Y526538D02*
Y525553D01*
G01X1298271Y508825D02*
Y507840D01*
G01X1298079Y521698D02*
Y526539D01*
G01Y507839D02*
Y512680D01*
G01X1298005Y524760D02*
Y525751D01*
G01X1297995Y508627D02*
Y509618D01*
G01X1297921Y512760D02*
Y511696D01*
G01Y522681D02*
Y521618D01*
G01X1297646D02*
Y522602D01*
G01Y512760D02*
Y511776D01*
G01X1296858Y521618D02*
Y522602D01*
G01Y512760D02*
Y511776D01*
G01X1296583Y512760D02*
Y511696D01*
G01Y522682D02*
Y521618D01*
G01X1296509Y525751D02*
Y524760D01*
G01X1296499Y509618D02*
Y508627D01*
G01X1296425Y521698D02*
Y526539D01*
G01Y507839D02*
Y512680D01*
G01X1296233Y525553D02*
Y526538D01*
G01X1296224Y507840D02*
Y508825D01*
G01X1296150Y526539D02*
Y507839D01*
G01X1296071Y509984D02*
Y503902D01*
G01Y530476D02*
Y524394D01*
G01X1295879Y526539D02*
Y525555D01*
G01X1295874Y526539D02*
Y525555D01*
G01X1295869Y508823D02*
Y507839D01*
G01X1295835Y510516D02*
Y506343D01*
G01Y528035D02*
Y523862D01*
G01X1294732D02*
Y528035D01*
G01Y506343D02*
Y510516D01*
G01X1294698Y508823D02*
Y507839D01*
G01X1294693Y508823D02*
Y507839D01*
G01Y526539D02*
Y525555D01*
G01X1294496Y509984D02*
Y503902D01*
G01Y530476D02*
Y524394D01*
G01X1294417Y507839D02*
Y526539D01*
G01X1294339Y508825D02*
Y507840D01*
G01Y526538D02*
Y525553D01*
G01X1294142Y525555D02*
Y530396D01*
G01Y503982D02*
Y508823D01*
G01X1294063Y524760D02*
Y525751D01*
G01Y508627D02*
Y509618D01*
G01X1293984Y504965D02*
Y503902D01*
G01Y530476D02*
Y529413D01*
G01X1293709Y504886D02*
Y503902D01*
G01Y530476D02*
Y529492D01*
G01X1292921D02*
Y530476D01*
G01Y504886D02*
Y503902D01*
G01X1292646Y504965D02*
Y503902D01*
G01Y530476D02*
Y529413D01*
G01X1292567Y509618D02*
Y508627D01*
G01Y525751D02*
Y524760D01*
G01X1292488Y525555D02*
Y530396D01*
G01Y503982D02*
Y508823D01*
G01X1292291Y507840D02*
Y508825D01*
G01Y525553D02*
Y526538D01*
G01X1292213Y526539D02*
Y507839D01*
G01X1292134Y509984D02*
Y503902D01*
G01Y530476D02*
Y524394D01*
G01X1291937Y508823D02*
Y507839D01*
G01Y526539D02*
Y525555D01*
G01X1291932Y526539D02*
Y525555D01*
G01X1291898Y510516D02*
Y506343D01*
G01Y528035D02*
Y523862D01*
G01X1290795D02*
Y528035D01*
G01Y506343D02*
Y510516D01*
G01X1290761Y526539D02*
Y525555D01*
G01X1290756Y508823D02*
Y507839D01*
G01X1290751Y508823D02*
Y507839D01*
G01X1290559Y509984D02*
Y503902D01*
G01Y530476D02*
Y524394D01*
G01X1290480Y507839D02*
Y526539D01*
G01X1290406Y526538D02*
Y525553D01*
G01X1290397Y508825D02*
Y507840D01*
G01X1290205Y521698D02*
Y526539D01*
G01Y507839D02*
Y512680D01*
G01X1290131Y524760D02*
Y525751D01*
G01X1290121Y508627D02*
Y509618D01*
G01X1290047Y512760D02*
Y511696D01*
G01Y522681D02*
Y521618D01*
G01X1289772Y512760D02*
Y511776D01*
G01Y522602D02*
Y521618D01*
G01X1288984Y512760D02*
Y511776D01*
G01Y522602D02*
Y521618D01*
G01X1288709Y512760D02*
Y511696D01*
G01Y522682D02*
Y521618D01*
G01X1288635Y525751D02*
Y524760D01*
G01X1288625Y509618D02*
Y508627D01*
G01X1288551Y521698D02*
Y526539D01*
G01Y507839D02*
Y512680D01*
G01X1288359Y525553D02*
Y526538D01*
G01X1288350Y507840D02*
Y508825D01*
G01X1288276Y526539D02*
Y507839D01*
G01X1288197Y509984D02*
Y503902D01*
G01Y530476D02*
Y524394D01*
G01X1288005Y526539D02*
Y525555D01*
G01X1288000Y526539D02*
Y525555D01*
G01X1287995Y508823D02*
Y507839D01*
G01X1287961Y510516D02*
Y506343D01*
G01Y528035D02*
Y523862D01*
G01X1286858D02*
Y528035D01*
G01Y506343D02*
Y510516D01*
G01X1286824Y508823D02*
Y507839D01*
G01X1286819Y508823D02*
Y507839D01*
G01Y526539D02*
Y525555D01*
G01X1286622Y509984D02*
Y503902D01*
G01Y530476D02*
Y524394D01*
G01X1286543Y507839D02*
Y526539D01*
G01X1286465Y508825D02*
Y507840D01*
G01Y526538D02*
Y525553D01*
G01X1286268Y525555D02*
Y530396D01*
G01Y503982D02*
Y508823D01*
G01X1286189Y524760D02*
Y525751D01*
G01Y508627D02*
Y509618D01*
G01X1286110Y504965D02*
Y503902D01*
G01Y530476D02*
Y529413D01*
G01X1285835Y504886D02*
Y503902D01*
G01Y530476D02*
Y529492D01*
G01X1285047D02*
Y530476D01*
G01Y504886D02*
Y503902D01*
G01X1284772Y504965D02*
Y503902D01*
G01Y530476D02*
Y529413D01*
G01X1284693Y509618D02*
Y508627D01*
G01Y525751D02*
Y524760D01*
G01X1284614Y525555D02*
Y530396D01*
G01Y503982D02*
Y508823D01*
G01X1284417Y525553D02*
Y526538D01*
G01Y507840D02*
Y508825D01*
G01X1284339Y526539D02*
Y507839D01*
G01X1284260Y509984D02*
Y503902D01*
G01Y530476D02*
Y524394D01*
G01X1305613Y525368D02*
X1305626Y524394D01*
G01X1304639Y509010D02*
X1304626Y509984D01*
G01X1301672Y525368D02*
X1301685Y524394D01*
G01X1300706Y509010D02*
X1300693Y509984D01*
G01X1297739Y525368D02*
X1297752Y524394D01*
G01X1296765Y509010D02*
X1296751Y509984D01*
G01X1293798Y525368D02*
X1293811Y524394D01*
G01X1292832Y509010D02*
X1292819Y509984D01*
G01X1289865Y525368D02*
X1289878Y524394D01*
G01X1288891Y509010D02*
X1288877Y509984D01*
G01X1285924Y525368D02*
X1285937Y524394D01*
G01X1284958Y509010D02*
X1284945Y509984D01*
G01X1306132Y509117D02*
X1305995Y515025D01*
G01X1305991Y514139D02*
X1306127Y508231D01*
G01X1304261Y520239D02*
X1304125Y526147D01*
G01X1304120Y525261D02*
X1304256Y519353D01*
G01X1302199Y509117D02*
X1302063Y515025D01*
G01X1302058Y514139D02*
X1302195Y508231D01*
G01X1300320Y520239D02*
X1300183Y526147D01*
G01X1300179Y525261D02*
X1300315Y519353D01*
G01X1298258Y509117D02*
X1298121Y515025D01*
G01X1298117Y514139D02*
X1298253Y508231D01*
G01X1296387Y520239D02*
X1296251Y526147D01*
G01X1296246Y525261D02*
X1296382Y519353D01*
G01X1294325Y509117D02*
X1294189Y515025D01*
G01X1294184Y514139D02*
X1294321Y508231D01*
G01X1292446Y520239D02*
X1292309Y526147D01*
G01X1292305Y525261D02*
X1292441Y519353D01*
G01X1290384Y509117D02*
X1290247Y515025D01*
G01X1290243Y514139D02*
X1290379Y508231D01*
G01X1288513Y520239D02*
X1288377Y526147D01*
G01X1288372Y525261D02*
X1288508Y519353D01*
G01X1286451Y509117D02*
X1286315Y515025D01*
G01X1286310Y514139D02*
X1286447Y508231D01*
G01X1284572Y520239D02*
X1284435Y526147D01*
G01X1284431Y525261D02*
X1284567Y519353D01*
G01X1304326Y514341D02*
X1304276Y515327D01*
G01X1304273Y514365D02*
X1304324Y513379D01*
G01X1302037Y520013D02*
X1301987Y520999D01*
G01X1301984Y520037D02*
X1302035Y519051D01*
G01X1300394Y514341D02*
X1300343Y515327D01*
G01X1300341Y514365D02*
X1300391Y513379D01*
G01X1298105Y520013D02*
X1298054Y520999D01*
G01X1298052Y520037D02*
X1298102Y519051D01*
G01X1296452Y514341D02*
X1296402Y515327D01*
G01X1296399Y514365D02*
X1296450Y513379D01*
G01X1294163Y520013D02*
X1294113Y520999D01*
G01X1294110Y520037D02*
X1294161Y519051D01*
G01X1292520Y514341D02*
X1292469Y515327D01*
G01X1292467Y514365D02*
X1292517Y513379D01*
G01X1290231Y520013D02*
X1290180Y520999D01*
G01X1290178Y520037D02*
X1290228Y519051D01*
G01X1288578Y514341D02*
X1288528Y515327D01*
G01X1288525Y514365D02*
X1288576Y513379D01*
G01X1286289Y520013D02*
X1286239Y520999D01*
G01X1286236Y520037D02*
X1286287Y519051D01*
G01X1284646Y514341D02*
X1284595Y515327D01*
G01X1284593Y514365D02*
X1284643Y513379D01*
G01X1282357Y520013D02*
X1282306Y520999D01*
G01X1282304Y520037D02*
X1282354Y519051D01*
G01X1269165Y524441D02*
X1269174Y524394D01*
G01X1270221Y509937D02*
X1270212Y509984D01*
G01X1265232Y524441D02*
X1265242Y524394D01*
G01X1266280Y509937D02*
X1266270Y509984D01*
G01X1261291Y524441D02*
X1261300Y524394D01*
G01X1262347Y509937D02*
X1262338Y509984D01*
G01X1257358Y524441D02*
X1257368Y524394D01*
G01X1258406Y509937D02*
X1258396Y509984D01*
G01X1253417Y524441D02*
X1253426Y524394D01*
G01X1254473Y509937D02*
X1254464Y509984D01*
G01X1249484Y524441D02*
X1249494Y524394D01*
G01X1250531Y509937D02*
X1250522Y509984D01*
G01X1245543Y524441D02*
X1245552Y524394D01*
G01X1242657Y509937D02*
X1242879Y509615D01*
G01X1242866Y508640D02*
X1242612Y509010D01*
G01X1304385Y508640D02*
X1304639Y509010D01*
G01X1304372Y509615D02*
X1304593Y509937D01*
G01X1300452Y508640D02*
X1300706Y509010D01*
G01X1300661Y509937D02*
X1300441Y509618D01*
G01X1296511Y508640D02*
X1296765Y509010D01*
G01X1296498Y509615D02*
X1296719Y509937D01*
G01X1305880Y524763D02*
X1305659Y524441D01*
G01X1305867Y525738D02*
X1305613Y525368D01*
G01X1292578Y508640D02*
X1292832Y509010D01*
G01X1292565Y509615D02*
X1292787Y509937D01*
G01X1301717Y524441D02*
X1301937Y524760D01*
G01X1301925Y525738D02*
X1301672Y525368D01*
G01X1288637Y508640D02*
X1288891Y509010D01*
G01X1288624Y509615D02*
X1288845Y509937D01*
G01X1298006Y524763D02*
X1297785Y524441D01*
G01X1297993Y525738D02*
X1297739Y525368D01*
G01X1284704Y508640D02*
X1284958Y509010D01*
G01X1292796Y509984D02*
X1292787Y509937D01*
G01X1293834Y524394D02*
X1293843Y524441D01*
G01X1288855Y509984D02*
X1288845Y509937D01*
G01X1289901Y524394D02*
X1289911Y524441D01*
G01X1284922Y509984D02*
X1284913Y509937D01*
G01X1285960Y524394D02*
X1285969Y524441D01*
G01X1280981Y509984D02*
X1280971Y509937D01*
G01X1282027Y524394D02*
X1282037Y524441D01*
G01X1277048Y509984D02*
X1277039Y509937D01*
G01X1278086Y524394D02*
X1278095Y524441D01*
G01X1273107Y509984D02*
X1273097Y509937D01*
G01X1274153Y524394D02*
X1274163Y524441D01*
G01X1269174Y509984D02*
X1269165Y509937D01*
G01X1286239Y513379D02*
X1286289Y514365D01*
G01X1286287Y515327D02*
X1286236Y514341D01*
G01X1284595Y519051D02*
X1284646Y520037D01*
G01X1284643Y520999D02*
X1284593Y520013D01*
G01X1282297Y513379D02*
X1282347Y514365D01*
G01X1282345Y515327D02*
X1282295Y514341D01*
G01X1280663Y519051D02*
X1280713Y520037D01*
G01X1280711Y520999D02*
X1280661Y520013D01*
G01X1278365Y513379D02*
X1278415Y514365D01*
G01X1278413Y515327D02*
X1278362Y514341D01*
G01X1276721Y519051D02*
X1276772Y520037D01*
G01X1276769Y520999D02*
X1276719Y520013D01*
G01X1274423Y513379D02*
X1274473Y514365D01*
G01X1274471Y515327D02*
X1274420Y514341D01*
G01X1272789Y519051D02*
X1272839Y520037D01*
G01X1272837Y520999D02*
X1272787Y520013D01*
G01X1270490Y513379D02*
X1270541Y514365D01*
G01X1270539Y515327D02*
X1270488Y514341D01*
G01X1268847Y519051D02*
X1268898Y520037D01*
G01X1268895Y520999D02*
X1268845Y520013D01*
G01X1266549Y513379D02*
X1266599Y514365D01*
G01X1266597Y515327D02*
X1266546Y514341D01*
G01X1264915Y519051D02*
X1264965Y520037D01*
G01X1264963Y520999D02*
X1264912Y520013D01*
G01X1262616Y513379D02*
X1262667Y514365D01*
G01X1262665Y515327D02*
X1262614Y514341D01*
G01X1284435Y508231D02*
X1284572Y514139D01*
G01X1284567Y515025D02*
X1284431Y509117D01*
G01X1282383Y519353D02*
X1282519Y525261D01*
G01X1282514Y526147D02*
X1282378Y520239D01*
G01X1280494Y508231D02*
X1280630Y514139D01*
G01X1280625Y515025D02*
X1280489Y509117D01*
G01X1278441Y519353D02*
X1278577Y525261D01*
G01X1278573Y526147D02*
X1278436Y520239D01*
G01X1276561Y508231D02*
X1276698Y514139D01*
G01X1276693Y515025D02*
X1276557Y509117D01*
G01X1274509Y519353D02*
X1274645Y525261D01*
G01X1274640Y526147D02*
X1274504Y520239D01*
G01X1272620Y508231D02*
X1272756Y514139D01*
G01X1272751Y515025D02*
X1272615Y509117D01*
G01X1270567Y519353D02*
X1270703Y525261D01*
G01X1270699Y526147D02*
X1270562Y520239D01*
G01X1268687Y508231D02*
X1268824Y514139D01*
G01X1268819Y515025D02*
X1268682Y509117D01*
G01X1266635Y519353D02*
X1266771Y525261D01*
G01X1266766Y526147D02*
X1266630Y520239D01*
G01X1264746Y508231D02*
X1264882Y514139D01*
G01X1264877Y515025D02*
X1264741Y509117D01*
G01X1262693Y519353D02*
X1262829Y525261D01*
G01X1262825Y526147D02*
X1262688Y520239D01*
G01X1284945Y524394D02*
X1284958Y525368D01*
G01X1281995Y509984D02*
X1281982Y509010D01*
G01X1281013Y524394D02*
X1281026Y525368D01*
G01X1278063Y509984D02*
X1278050Y509010D01*
G01X1277071Y524394D02*
X1277084Y525368D01*
G01X1274121Y509984D02*
X1274108Y509010D01*
G01X1273139Y524394D02*
X1273152Y525368D01*
G01X1270189Y509984D02*
X1270176Y509010D01*
G01X1269197Y524394D02*
X1269210Y525368D01*
G01X1266247Y509984D02*
X1266234Y509010D01*
G01X1265265Y524394D02*
X1265278Y525368D01*
G01X1262315Y509984D02*
X1262302Y509010D01*
G01X1261323Y524394D02*
X1261336Y525368D01*
G01X1284063Y508823D02*
Y507839D01*
G01Y526539D02*
Y525555D01*
G01X1284058Y526539D02*
Y525555D01*
G01X1284024Y510516D02*
Y506343D01*
G01Y528035D02*
Y523862D01*
G01X1282921D02*
Y528035D01*
G01Y506343D02*
Y510516D01*
G01X1282887Y526539D02*
Y525555D01*
G01X1282882Y508823D02*
Y507839D01*
G01X1282877Y508823D02*
Y507839D01*
G01X1282685Y509984D02*
Y503902D01*
G01Y530476D02*
Y524394D01*
G01X1282606Y507839D02*
Y526539D01*
G01X1282532Y526538D02*
Y525553D01*
G01X1282523Y508825D02*
Y507840D01*
G01X1282331Y521698D02*
Y526539D01*
G01Y507839D02*
Y512680D01*
G01X1282257Y524760D02*
Y525751D01*
G01X1282247Y508627D02*
Y509618D01*
G01X1282173Y512760D02*
Y511696D01*
G01Y522681D02*
Y521618D01*
G01X1281898D02*
Y522602D01*
G01Y512760D02*
Y511776D01*
G01X1281110Y521618D02*
Y522602D01*
G01Y511776D02*
Y512760D01*
G01X1280835D02*
Y511696D01*
G01Y522682D02*
Y521618D01*
G01X1280761Y525751D02*
Y524760D01*
G01X1280751Y509618D02*
Y508627D01*
G01X1280677Y521698D02*
Y526539D01*
G01Y507839D02*
Y512680D01*
G01X1280485Y525553D02*
Y526538D01*
G01X1280476Y507840D02*
Y508825D01*
G01X1280402Y526539D02*
Y507839D01*
G01X1280323Y509984D02*
Y503902D01*
G01Y530476D02*
Y524394D01*
G01X1280131Y526539D02*
Y525555D01*
G01X1280126Y526539D02*
Y525555D01*
G01X1280121Y508823D02*
Y507839D01*
G01X1280087Y510516D02*
Y506343D01*
G01Y528035D02*
Y523862D01*
G01X1278984D02*
Y528035D01*
G01Y506343D02*
Y510516D01*
G01X1278950Y508823D02*
Y507839D01*
G01X1278945Y508823D02*
Y507839D01*
G01Y526539D02*
Y525555D01*
G01X1278748Y509984D02*
Y503902D01*
G01Y530476D02*
Y524394D01*
G01X1278669Y507839D02*
Y526539D01*
G01X1278591Y508825D02*
Y507840D01*
G01Y526538D02*
Y525553D01*
G01X1278394Y525555D02*
Y530396D01*
G01Y503982D02*
Y508823D01*
G01X1278315Y524760D02*
Y525751D01*
G01Y508627D02*
Y509618D01*
G01X1278236Y504965D02*
Y503902D01*
G01Y530476D02*
Y529413D01*
G01X1277961Y504886D02*
Y503902D01*
G01Y530476D02*
Y529492D01*
G01X1277173D02*
Y530476D01*
G01Y504886D02*
Y503902D01*
G01X1276898Y504965D02*
Y503902D01*
G01Y530476D02*
Y529413D01*
G01X1276819Y509618D02*
Y508627D01*
G01Y525751D02*
Y524760D01*
G01X1276740Y525555D02*
Y530396D01*
G01Y503982D02*
Y508823D01*
G01X1276543Y507840D02*
Y508825D01*
G01Y525553D02*
Y526538D01*
G01X1276465Y526539D02*
Y507839D01*
G01X1276386Y509984D02*
Y503902D01*
G01Y530476D02*
Y524394D01*
G01X1276189Y508823D02*
Y507839D01*
G01Y526539D02*
Y525555D01*
G01X1276184Y526539D02*
Y525555D01*
G01X1276150Y510516D02*
Y506343D01*
G01Y528035D02*
Y523862D01*
G01X1275047D02*
Y528035D01*
G01Y506343D02*
Y510516D01*
G01X1275013Y526539D02*
Y525555D01*
G01X1275008Y508823D02*
Y507839D01*
G01X1275003Y508823D02*
Y507839D01*
G01X1274811Y509984D02*
Y503902D01*
G01Y530476D02*
Y524394D01*
G01X1274732Y507839D02*
Y526539D01*
G01X1274658Y526538D02*
Y525553D01*
G01X1274649Y508825D02*
Y507840D01*
G01X1274457Y521698D02*
Y526539D01*
G01Y507839D02*
Y512680D01*
G01X1274383Y524760D02*
Y525751D01*
G01X1274373Y508627D02*
Y509618D01*
G01X1274299Y512760D02*
Y511696D01*
G01Y522681D02*
Y521618D01*
G01X1274024D02*
Y522602D01*
G01Y512760D02*
Y511776D01*
G01X1273236Y521618D02*
Y522602D01*
G01Y511776D02*
Y512760D01*
G01X1272961D02*
Y511696D01*
G01Y522682D02*
Y521618D01*
G01X1272887Y525751D02*
Y524760D01*
G01X1272877Y509618D02*
Y508627D01*
G01X1272803Y521698D02*
Y526539D01*
G01Y507839D02*
Y512680D01*
G01X1272611Y525553D02*
Y526538D01*
G01X1272602Y507840D02*
Y508825D01*
G01X1272528Y526539D02*
Y507839D01*
G01X1272449Y509984D02*
Y503902D01*
G01Y530476D02*
Y524394D01*
G01X1272257Y526539D02*
Y525555D01*
G01X1272252Y526539D02*
Y525555D01*
G01X1272247Y508823D02*
Y507839D01*
G01X1272213Y510516D02*
Y506343D01*
G01Y528035D02*
Y523862D01*
G01X1271110D02*
Y528035D01*
G01Y506343D02*
Y510516D01*
G01X1271076Y508823D02*
Y507839D01*
G01X1271071Y508823D02*
Y507839D01*
G01Y526539D02*
Y525555D01*
G01X1270874Y509984D02*
Y503902D01*
G01Y530476D02*
Y524394D01*
G01X1270795Y507839D02*
Y526539D01*
G01X1270717Y508825D02*
Y507840D01*
G01Y526538D02*
Y525553D01*
G01X1270520Y525555D02*
Y530396D01*
G01Y503982D02*
Y508823D01*
G01X1270441Y524760D02*
Y525751D01*
G01Y508627D02*
Y509618D01*
G01X1270362Y504965D02*
Y503902D01*
G01Y530476D02*
Y529413D01*
G01X1270087Y504886D02*
Y503902D01*
G01Y530476D02*
Y529492D01*
G01X1269299D02*
Y530476D01*
G01Y504886D02*
Y503902D01*
G01X1269024Y504965D02*
Y503902D01*
G01Y530476D02*
Y529413D01*
G01X1268945Y509618D02*
Y508627D01*
G01Y525751D02*
Y524760D01*
G01X1268866Y525555D02*
Y530396D01*
G01Y503982D02*
Y508823D01*
G01X1268669Y507840D02*
Y508825D01*
G01Y525553D02*
Y526538D01*
G01X1268591Y526539D02*
Y507839D01*
G01X1268512Y509984D02*
Y503902D01*
G01Y530476D02*
Y524394D01*
G01X1268315Y508823D02*
Y507839D01*
G01Y526539D02*
Y525555D01*
G01X1268310Y526539D02*
Y525555D01*
G01X1268276Y510516D02*
Y506343D01*
G01Y528035D02*
Y523862D01*
G01X1267173D02*
Y528035D01*
G01Y506343D02*
Y510516D01*
G01X1267139Y526539D02*
Y525555D01*
G01X1267134Y508823D02*
Y507839D01*
G01X1267129Y508823D02*
Y507839D01*
G01X1266937Y509984D02*
Y503902D01*
G01Y530476D02*
Y524394D01*
G01X1266858Y507839D02*
Y526539D01*
G01X1266784Y526538D02*
Y525553D01*
G01X1266775Y508825D02*
Y507840D01*
G01X1266583Y521698D02*
Y526539D01*
G01Y507839D02*
Y512680D01*
G01X1266509Y524760D02*
Y525751D01*
G01X1266499Y508627D02*
Y509618D01*
G01X1266425Y512760D02*
Y511696D01*
G01Y522681D02*
Y521618D01*
G01X1266150Y512760D02*
Y511776D01*
G01Y522602D02*
Y521618D01*
G01X1265362Y512760D02*
Y511776D01*
G01Y522602D02*
Y521618D01*
G01X1265087Y512760D02*
Y511696D01*
G01Y522682D02*
Y521618D01*
G01X1265013Y525751D02*
Y524760D01*
G01X1265003Y509618D02*
Y508627D01*
G01X1264929Y521698D02*
Y526539D01*
G01Y507839D02*
Y512680D01*
G01X1264737Y525553D02*
Y526538D01*
G01X1264728Y507840D02*
Y508825D01*
G01X1264654Y526539D02*
Y507839D01*
G01X1264575Y509984D02*
Y503902D01*
G01Y530476D02*
Y524394D01*
G01X1264383Y526539D02*
Y525555D01*
G01X1264378Y526539D02*
Y525555D01*
G01X1264373Y508823D02*
Y507839D01*
G01X1264339Y510516D02*
Y506343D01*
G01Y528035D02*
Y523862D01*
G01X1263236D02*
Y528035D01*
G01Y506343D02*
Y510516D01*
G01X1263202Y508823D02*
Y507839D01*
G01X1263197Y508823D02*
Y507839D01*
G01Y526539D02*
Y525555D01*
G01X1263000Y509984D02*
Y503902D01*
G01Y530476D02*
Y524394D01*
G01X1262921Y507839D02*
Y526539D01*
G01X1262843Y508825D02*
Y507840D01*
G01Y526538D02*
Y525553D01*
G01X1262646Y525555D02*
Y530396D01*
G01Y503982D02*
Y508823D01*
G01X1262567Y524760D02*
Y525751D01*
G01Y508627D02*
Y509618D01*
G01X1262488Y504965D02*
Y503902D01*
G01Y530476D02*
Y529413D01*
G01X1262213Y504886D02*
Y503902D01*
G01Y530476D02*
Y529492D01*
G01X1261425D02*
Y530476D01*
G01Y504886D02*
Y503902D01*
G01X1261150Y504965D02*
Y503902D01*
G01Y530476D02*
Y529413D01*
G01X1261071Y509618D02*
Y508627D01*
G01Y525751D02*
Y524760D01*
G01X1260992Y525555D02*
Y530396D01*
G01Y503982D02*
Y508823D01*
G01X1260795Y507840D02*
Y508825D01*
G01Y525553D02*
Y526538D01*
G01X1260717Y526539D02*
Y507839D01*
G01X1260638Y509984D02*
Y503902D01*
G01Y530476D02*
Y524394D01*
G01X1260441Y508823D02*
Y507839D01*
G01Y526539D02*
Y525555D01*
G01X1260436Y526539D02*
Y525555D01*
G01X1260402Y510516D02*
Y506343D01*
G01Y528035D02*
Y523862D01*
G01X1281991Y525368D02*
X1282004Y524394D01*
G01X1281017Y509010D02*
X1281003Y509984D01*
G01X1278050Y525368D02*
X1278063Y524394D01*
G01X1277084Y509010D02*
X1277071Y509984D01*
G01X1274117Y525368D02*
X1274130Y524394D01*
G01X1273143Y509010D02*
X1273129Y509984D01*
G01X1270176Y525368D02*
X1270189Y524394D01*
G01X1269210Y509010D02*
X1269197Y509984D01*
G01X1266243Y525368D02*
X1266256Y524394D01*
G01X1265269Y509010D02*
X1265255Y509984D01*
G01X1262302Y525368D02*
X1262315Y524394D01*
G01X1261336Y509010D02*
X1261323Y509984D01*
G01X1282510Y509117D02*
X1282373Y515025D01*
G01X1282369Y514139D02*
X1282505Y508231D01*
G01X1280639Y520239D02*
X1280503Y526147D01*
G01X1280498Y525261D02*
X1280634Y519353D01*
G01X1278577Y509117D02*
X1278441Y515025D01*
G01X1278436Y514139D02*
X1278573Y508231D01*
G01X1276698Y520239D02*
X1276561Y526147D01*
G01X1276557Y525261D02*
X1276693Y519353D01*
G01X1274636Y509117D02*
X1274499Y515025D01*
G01X1274495Y514139D02*
X1274631Y508231D01*
G01X1272765Y520239D02*
X1272629Y526147D01*
G01X1272624Y525261D02*
X1272760Y519353D01*
G01X1270703Y509117D02*
X1270567Y515025D01*
G01X1270562Y514139D02*
X1270699Y508231D01*
G01X1268824Y520239D02*
X1268687Y526147D01*
G01X1268682Y525261D02*
X1268819Y519353D01*
G01X1266762Y509117D02*
X1266625Y515025D01*
G01X1266621Y514139D02*
X1266757Y508231D01*
G01X1264891Y520239D02*
X1264755Y526147D01*
G01X1264750Y525261D02*
X1264886Y519353D01*
G01X1262829Y509117D02*
X1262693Y515025D01*
G01X1262688Y514139D02*
X1262825Y508231D01*
G01X1260949Y520239D02*
X1260813Y526147D01*
G01X1260808Y525261D02*
X1260945Y519353D01*
G01X1258888Y509117D02*
X1258751Y515025D01*
G01X1258747Y514139D02*
X1258883Y508231D01*
G01X1280704Y514341D02*
X1280654Y515327D01*
G01X1280651Y514365D02*
X1280702Y513379D01*
G01X1278415Y520013D02*
X1278365Y520999D01*
G01X1278362Y520037D02*
X1278413Y519051D01*
G01X1276772Y514341D02*
X1276721Y515327D01*
G01X1276719Y514365D02*
X1276769Y513379D01*
G01X1274483Y520013D02*
X1274432Y520999D01*
G01X1274430Y520037D02*
X1274480Y519051D01*
G01X1272830Y514341D02*
X1272780Y515327D01*
G01X1272777Y514365D02*
X1272828Y513379D01*
G01X1270541Y520013D02*
X1270490Y520999D01*
G01X1270488Y520037D02*
X1270539Y519051D01*
G01X1268898Y514341D02*
X1268847Y515327D01*
G01X1268845Y514365D02*
X1268895Y513379D01*
G01X1266609Y520013D02*
X1266558Y520999D01*
G01X1266556Y520037D02*
X1266606Y519051D01*
G01X1264956Y514341D02*
X1264905Y515327D01*
G01X1264903Y514365D02*
X1264954Y513379D01*
G01X1262667Y520013D02*
X1262616Y520999D01*
G01X1262614Y520037D02*
X1262665Y519051D01*
G01X1261024Y514341D02*
X1260973Y515327D01*
G01X1260971Y514365D02*
X1261021Y513379D01*
G01X1258735Y520013D02*
X1258684Y520999D01*
G01X1258682Y520037D02*
X1258732Y519051D01*
G01X1257082Y514341D02*
X1257031Y515327D01*
G01X1257029Y514365D02*
X1257080Y513379D01*
G01X1246599Y509937D02*
X1246590Y509984D01*
G01X1241610Y524441D02*
X1241620Y524394D01*
G01X1242657Y509937D02*
X1242648Y509984D01*
G01X1284691Y509615D02*
X1284913Y509937D01*
G01X1294065Y524763D02*
X1293843Y524441D01*
G01X1294051Y525738D02*
X1293798Y525368D01*
G01X1280763Y508640D02*
X1281017Y509010D01*
G01X1280750Y509615D02*
X1280971Y509937D01*
G01X1290132Y524763D02*
X1289911Y524441D01*
G01X1290119Y525738D02*
X1289865Y525368D01*
G01X1276830Y508640D02*
X1277084Y509010D01*
G01X1276817Y509615D02*
X1277039Y509937D01*
G01X1286191Y524763D02*
X1285969Y524441D01*
G01X1286177Y525738D02*
X1285924Y525368D01*
G01X1272889Y508640D02*
X1273143Y509010D01*
G01X1272876Y509615D02*
X1273097Y509937D01*
G01X1282258Y524763D02*
X1282037Y524441D01*
G01X1282245Y525738D02*
X1281991Y525368D01*
G01X1268956Y508640D02*
X1269210Y509010D01*
G01X1268943Y509615D02*
X1269165Y509937D01*
G01X1278317Y524763D02*
X1278095Y524441D01*
G01X1278303Y525738D02*
X1278050Y525368D01*
G01X1265015Y508640D02*
X1265269Y509010D01*
G01X1265002Y509615D02*
X1265223Y509937D01*
G01X1274384Y524763D02*
X1274163Y524441D01*
G01X1274371Y525738D02*
X1274117Y525368D01*
G01X1261082Y508640D02*
X1261336Y509010D01*
G01X1261069Y509615D02*
X1261291Y509937D01*
G01X1270443Y524763D02*
X1270221Y524441D01*
G01X1270429Y525738D02*
X1270176Y525368D01*
G01X1257141Y508640D02*
X1257395Y509010D01*
G01X1257128Y509615D02*
X1257349Y509937D01*
G01X1266510Y524763D02*
X1266289Y524441D01*
G01X1266497Y525738D02*
X1266243Y525368D01*
G01X1270212Y524394D02*
X1270221Y524441D01*
G01X1265233Y509984D02*
X1265223Y509937D01*
G01X1266279Y524394D02*
X1266289Y524441D01*
G01X1261300Y509984D02*
X1261291Y509937D01*
G01X1262338Y524394D02*
X1262347Y524441D01*
G01X1257359Y509984D02*
X1257349Y509937D01*
G01X1258405Y524394D02*
X1258415Y524441D01*
G01X1253426Y509984D02*
X1253417Y509937D01*
G01X1254464Y524394D02*
X1254473Y524441D01*
G01X1249484Y509984D02*
X1249475Y509937D01*
G01X1250531Y524394D02*
X1250541Y524441D01*
G01X1245552Y509984D02*
X1245543Y509937D01*
G01X1260973Y519051D02*
X1261024Y520037D01*
G01X1261021Y520999D02*
X1260971Y520013D01*
G01X1258675Y513379D02*
X1258725Y514365D01*
G01X1258723Y515327D02*
X1258672Y514341D01*
G01X1257041Y519051D02*
X1257091Y520037D01*
G01X1257089Y520999D02*
X1257038Y520013D01*
G01X1254742Y513379D02*
X1254793Y514365D01*
G01X1254791Y515327D02*
X1254740Y514341D01*
G01X1253099Y519051D02*
X1253150Y520037D01*
G01X1253147Y520999D02*
X1253097Y520013D01*
G01X1250801Y513379D02*
X1250851Y514365D01*
G01X1250849Y515327D02*
X1250798Y514341D01*
G01X1249167Y519051D02*
X1249217Y520037D01*
G01X1249215Y520999D02*
X1249164Y520013D01*
G01X1246868Y513379D02*
X1246919Y514365D01*
G01X1246917Y515327D02*
X1246866Y514341D01*
G01X1245225Y519051D02*
X1245276Y520037D01*
G01X1245273Y520999D02*
X1245223Y520013D01*
G01X1242927Y513379D02*
X1242977Y514365D01*
G01X1242975Y515327D02*
X1242924Y514341D01*
G01X1241293Y519051D02*
X1241343Y520037D01*
G01X1241341Y520999D02*
X1241290Y520013D01*
G01X1260813Y508231D02*
X1260949Y514139D01*
G01X1260945Y515025D02*
X1260808Y509117D01*
G01X1258761Y519353D02*
X1258897Y525261D01*
G01X1258892Y526147D02*
X1258756Y520239D01*
G01X1256872Y508231D02*
X1257008Y514139D01*
G01X1257003Y515025D02*
X1256867Y509117D01*
G01X1254819Y519353D02*
X1254955Y525261D01*
G01X1254951Y526147D02*
X1254814Y520239D01*
G01X1252939Y508231D02*
X1253075Y514139D01*
G01X1253071Y515025D02*
X1252934Y509117D01*
G01X1250887Y519353D02*
X1251023Y525261D01*
G01X1251018Y526147D02*
X1250882Y520239D01*
G01X1248998Y508231D02*
X1249134Y514139D01*
G01X1249129Y515025D02*
X1248993Y509117D01*
G01X1246945Y519353D02*
X1247081Y525261D01*
G01X1247076Y526147D02*
X1246940Y520239D01*
G01X1245065Y508231D02*
X1245201Y514139D01*
G01X1245197Y515025D02*
X1245060Y509117D01*
G01X1243013Y519353D02*
X1243149Y525261D01*
G01X1243144Y526147D02*
X1243008Y520239D01*
G01X1241124Y508231D02*
X1241260Y514139D01*
G01X1241255Y515025D02*
X1241119Y509117D01*
G01X1258373Y509984D02*
X1258360Y509010D01*
G01X1257391Y524394D02*
X1257404Y525368D01*
G01X1254441Y509984D02*
X1254428Y509010D01*
G01X1253449Y524394D02*
X1253462Y525368D01*
G01X1250499Y509984D02*
X1250486Y509010D01*
G01X1249517Y524394D02*
X1249530Y525368D01*
G01X1246567Y509984D02*
X1246554Y509010D01*
G01X1245575Y524394D02*
X1245588Y525368D01*
G01X1242625Y509984D02*
X1242612Y509010D01*
G01X1241643Y524394D02*
X1241656Y525368D01*
G01X1259299Y523862D02*
Y528035D01*
G01Y506343D02*
Y510516D01*
G01X1259265Y526539D02*
Y525555D01*
G01X1259260Y508823D02*
Y507839D01*
G01X1259255Y508823D02*
Y507839D01*
G01X1259063Y509984D02*
Y503902D01*
G01Y530476D02*
Y524394D01*
G01X1258984Y507839D02*
Y526539D01*
G01X1258910Y526538D02*
Y525553D01*
G01X1258901Y508825D02*
Y507840D01*
G01X1258709Y521698D02*
Y526539D01*
G01Y507839D02*
Y512680D01*
G01X1258635Y524760D02*
Y525751D01*
G01X1258625Y508627D02*
Y509618D01*
G01X1258551Y512760D02*
Y511696D01*
G01Y522681D02*
Y521618D01*
G01X1258276Y512760D02*
Y511776D01*
G01Y522602D02*
Y521618D01*
G01X1257488Y512760D02*
Y511776D01*
G01Y522602D02*
Y521618D01*
G01X1257213Y512760D02*
Y511696D01*
G01Y522682D02*
Y521618D01*
G01X1257139Y525751D02*
Y524760D01*
G01X1257129Y509618D02*
Y508627D01*
G01X1257055Y521698D02*
Y526539D01*
G01Y507839D02*
Y512680D01*
G01X1256863Y525553D02*
Y526538D01*
G01X1256854Y507840D02*
Y508825D01*
G01X1256780Y526539D02*
Y507839D01*
G01X1256701Y509984D02*
Y503902D01*
G01Y530476D02*
Y524394D01*
G01X1256509Y526539D02*
Y525555D01*
G01X1256504Y526539D02*
Y525555D01*
G01X1256499Y508823D02*
Y507839D01*
G01X1256465Y510516D02*
Y506343D01*
G01Y528035D02*
Y523862D01*
G01X1255362D02*
Y528035D01*
G01Y506343D02*
Y510516D01*
G01X1255328Y508823D02*
Y507839D01*
G01X1255323Y508823D02*
Y507839D01*
G01Y526539D02*
Y525555D01*
G01X1255126Y509984D02*
Y503902D01*
G01Y530476D02*
Y524394D01*
G01X1255047Y507839D02*
Y526539D01*
G01X1254968Y508825D02*
Y507840D01*
G01Y526538D02*
Y525553D01*
G01X1254772Y525555D02*
Y530396D01*
G01Y503982D02*
Y508823D01*
G01X1254693Y524760D02*
Y525751D01*
G01Y508627D02*
Y509618D01*
G01X1254614Y504965D02*
Y503902D01*
G01Y530476D02*
Y529413D01*
G01X1254339Y504886D02*
Y503902D01*
G01Y530476D02*
Y529492D01*
G01X1253551D02*
Y530476D01*
G01Y504886D02*
Y503902D01*
G01X1253276Y504965D02*
Y503902D01*
G01Y530476D02*
Y529413D01*
G01X1253197Y509618D02*
Y508627D01*
G01Y525751D02*
Y524760D01*
G01X1253118Y525555D02*
Y530396D01*
G01Y503982D02*
Y508823D01*
G01X1252921Y525553D02*
Y526538D01*
G01Y507840D02*
Y508825D01*
G01X1252843Y526539D02*
Y507839D01*
G01X1252764Y509984D02*
Y503902D01*
G01Y530476D02*
Y524394D01*
G01X1252567Y508823D02*
Y507839D01*
G01Y526539D02*
Y525555D01*
G01X1252562Y526539D02*
Y525555D01*
G01X1252528Y510516D02*
Y506343D01*
G01Y528035D02*
Y523862D01*
G01X1251425D02*
Y528035D01*
G01Y506343D02*
Y510516D01*
G01X1251390Y526539D02*
Y525555D01*
G01X1251386Y508823D02*
Y507839D01*
G01X1251381Y508823D02*
Y507839D01*
G01X1251189Y509984D02*
Y503902D01*
G01Y530476D02*
Y524394D01*
G01X1251110Y507839D02*
Y526539D01*
G01X1251036Y526538D02*
Y525553D01*
G01X1251027Y508825D02*
Y507840D01*
G01X1250835Y521698D02*
Y526539D01*
G01Y507839D02*
Y512680D01*
G01X1250761Y524760D02*
Y525751D01*
G01X1250751Y508627D02*
Y509618D01*
G01X1250677Y512760D02*
Y511696D01*
G01Y522681D02*
Y521618D01*
G01X1250402D02*
Y522602D01*
G01Y512760D02*
Y511776D01*
G01X1249614Y521618D02*
Y522602D01*
G01Y511776D02*
Y512760D01*
G01X1249339D02*
Y511696D01*
G01Y522682D02*
Y521618D01*
G01X1249265Y525751D02*
Y524760D01*
G01X1249255Y509618D02*
Y508627D01*
G01X1249181Y521698D02*
Y526539D01*
G01Y507839D02*
Y512680D01*
G01X1248989Y525553D02*
Y526538D01*
G01X1248980Y507840D02*
Y508825D01*
G01X1248906Y526539D02*
Y507839D01*
G01X1248827Y509984D02*
Y503902D01*
G01Y530476D02*
Y524394D01*
G01X1248635Y526539D02*
Y525555D01*
G01X1248630Y526539D02*
Y525555D01*
G01X1248625Y508823D02*
Y507839D01*
G01X1248591Y510516D02*
Y506343D01*
G01Y528035D02*
Y523862D01*
G01X1247488D02*
Y528035D01*
G01Y506343D02*
Y510516D01*
G01X1247453Y508823D02*
Y507839D01*
G01X1247449Y508823D02*
Y507839D01*
G01Y526539D02*
Y525555D01*
G01X1247252Y509984D02*
Y503902D01*
G01Y530476D02*
Y524394D01*
G01X1247173Y507839D02*
Y526539D01*
G01X1247094Y508825D02*
Y507840D01*
G01Y526538D02*
Y525553D01*
G01X1246898Y525555D02*
Y530396D01*
G01Y503982D02*
Y508823D01*
G01X1246819Y524760D02*
Y525751D01*
G01Y508627D02*
Y509618D01*
G01X1246740Y504965D02*
Y503902D01*
G01Y530476D02*
Y529413D01*
G01X1246465Y504886D02*
Y503902D01*
G01Y530476D02*
Y529492D01*
G01X1245677D02*
Y530476D01*
G01Y504886D02*
Y503902D01*
G01X1245402Y504965D02*
Y503902D01*
G01Y530476D02*
Y529413D01*
G01X1245323Y509618D02*
Y508627D01*
G01Y525751D02*
Y524760D01*
G01X1245244Y525555D02*
Y530396D01*
G01Y503982D02*
Y508823D01*
G01X1245047Y525553D02*
Y526538D01*
G01Y507840D02*
Y508825D01*
G01X1244968Y526539D02*
Y507839D01*
G01X1244890Y509984D02*
Y503902D01*
G01Y530476D02*
Y524394D01*
G01X1244693Y508823D02*
Y507839D01*
G01Y526539D02*
Y525555D01*
G01X1244688Y526539D02*
Y525555D01*
G01X1244654Y510516D02*
Y506343D01*
G01Y528035D02*
Y523862D01*
G01X1243551D02*
Y528035D01*
G01Y506343D02*
Y510516D01*
G01X1243516Y526539D02*
Y525555D01*
G01X1243512Y508823D02*
Y507839D01*
G01X1243507Y508823D02*
Y507839D01*
G01X1243315Y509984D02*
Y503902D01*
G01Y530476D02*
Y524394D01*
G01X1243236Y507839D02*
Y526539D01*
G01X1243162Y526538D02*
Y525553D01*
G01X1243153Y508825D02*
Y507840D01*
G01X1242961Y521698D02*
Y526539D01*
G01Y507839D02*
Y512680D01*
G01X1242887Y524760D02*
Y525751D01*
G01X1242877Y508627D02*
Y509618D01*
G01X1242803Y512760D02*
Y511696D01*
G01Y522681D02*
Y521618D01*
G01X1242528D02*
Y522602D01*
G01Y512760D02*
Y511776D01*
G01X1241740Y521618D02*
Y522602D01*
G01Y511776D02*
Y512760D01*
G01X1241465D02*
Y511696D01*
G01Y522682D02*
Y521618D01*
G01X1241390Y525751D02*
Y524760D01*
G01X1241381Y509618D02*
Y508627D01*
G01X1241307Y521698D02*
Y526539D01*
G01Y507839D02*
Y512680D01*
G01X1241115Y525553D02*
Y526538D01*
G01X1241106Y507840D02*
Y508825D01*
G01X1241031Y526539D02*
Y507839D01*
G01X1240953Y509984D02*
Y503902D01*
G01Y530476D02*
Y524394D01*
G01X1240761Y526539D02*
Y525555D01*
G01X1240756Y526539D02*
Y525555D01*
G01X1240751Y508823D02*
Y507839D01*
G01X1240717Y510516D02*
Y506343D01*
G01Y528035D02*
Y523862D01*
G01X1258369Y525368D02*
X1258382Y524394D01*
G01X1257395Y509010D02*
X1257381Y509984D01*
G01X1254428Y525368D02*
X1254441Y524394D01*
G01X1253462Y509010D02*
X1253449Y509984D01*
G01X1250495Y525368D02*
X1250508Y524394D01*
G01X1249521Y509010D02*
X1249507Y509984D01*
G01X1246554Y525368D02*
X1246567Y524394D01*
G01X1245588Y509010D02*
X1245575Y509984D01*
G01X1242621Y525368D02*
X1242634Y524394D01*
G01X1241647Y509010D02*
X1241633Y509984D01*
G01X1257017Y520239D02*
X1256881Y526147D01*
G01X1256876Y525261D02*
X1257012Y519353D01*
G01X1254955Y509117D02*
X1254819Y515025D01*
G01X1254814Y514139D02*
X1254951Y508231D01*
G01X1253075Y520239D02*
X1252939Y526147D01*
G01X1252934Y525261D02*
X1253071Y519353D01*
G01X1251014Y509117D02*
X1250877Y515025D01*
G01X1250873Y514139D02*
X1251009Y508231D01*
G01X1249143Y520239D02*
X1249007Y526147D01*
G01X1249002Y525261D02*
X1249138Y519353D01*
G01X1247081Y509117D02*
X1246945Y515025D01*
G01X1246940Y514139D02*
X1247076Y508231D01*
G01X1245201Y520239D02*
X1245065Y526147D01*
G01X1245060Y525261D02*
X1245197Y519353D01*
G01X1243140Y509117D02*
X1243003Y515025D01*
G01X1242999Y514139D02*
X1243135Y508231D01*
G01X1241269Y520239D02*
X1241133Y526147D01*
G01X1241128Y525261D02*
X1241264Y519353D01*
G01X1254793Y520013D02*
X1254742Y520999D01*
G01X1254740Y520037D02*
X1254791Y519051D01*
G01X1253150Y514341D02*
X1253099Y515327D01*
G01X1253097Y514365D02*
X1253147Y513379D01*
G01X1250861Y520013D02*
X1250810Y520999D01*
G01X1250808Y520037D02*
X1250858Y519051D01*
G01X1249208Y514341D02*
X1249157Y515327D01*
G01X1249155Y514365D02*
X1249206Y513379D01*
G01X1246919Y520013D02*
X1246868Y520999D01*
G01X1246866Y520037D02*
X1246917Y519051D01*
G01X1245276Y514341D02*
X1245225Y515327D01*
G01X1245223Y514365D02*
X1245273Y513379D01*
G01X1242987Y520013D02*
X1242936Y520999D01*
G01X1242934Y520037D02*
X1242984Y519051D01*
G01X1241334Y514341D02*
X1241283Y515327D01*
G01X1241281Y514365D02*
X1241332Y513379D01*
G01X1253208Y508640D02*
X1253462Y509010D01*
G01X1253195Y509615D02*
X1253417Y509937D01*
G01X1262569Y524763D02*
X1262347Y524441D01*
G01X1262555Y525738D02*
X1262302Y525368D01*
G01X1249267Y508640D02*
X1249521Y509010D01*
G01X1249254Y509615D02*
X1249475Y509937D01*
G01X1258636Y524763D02*
X1258415Y524441D01*
G01X1258623Y525738D02*
X1258369Y525368D01*
G01X1245334Y508640D02*
X1245588Y509010D01*
G01X1245321Y509615D02*
X1245543Y509937D01*
G01X1254695Y524763D02*
X1254473Y524441D01*
G01X1254681Y525738D02*
X1254428Y525368D01*
G01X1241393Y508640D02*
X1241647Y509010D01*
G01X1241380Y509615D02*
X1241601Y509937D01*
G01X1250762Y524763D02*
X1250541Y524441D01*
G01X1250749Y525738D02*
X1250495Y525368D01*
G01X1246820Y524763D02*
X1246599Y524441D01*
G01X1246807Y525738D02*
X1246554Y525368D01*
G01X1242888Y524763D02*
X1242667Y524441D01*
G01X1242875Y525738D02*
X1242621Y525368D01*
G01X1246590Y524394D02*
X1246599Y524441D01*
G01X1241610Y509984D02*
X1241601Y509937D01*
G01X1242657Y524394D02*
X1242667Y524441D01*
G01X1301189Y577012D02*
X1320874D01*
G01X1277567D02*
X1297252D01*
G01X1304339Y582524D02*
Y577012D01*
G01X1301189Y582524D02*
Y577012D01*
G01X1297252Y582524D02*
Y577012D01*
G01X1294102Y582524D02*
Y577012D01*
G01X1280717Y582524D02*
Y577012D01*
G01X1277567Y582524D02*
Y577012D01*
G01X1273630Y582524D02*
Y577012D01*
G01X1270480Y582524D02*
Y577012D01*
G01X1231071Y605754D02*
Y605751D01*
G01X1231072Y605756D02*
X1231071Y605754D01*
G01X1231073Y605757D02*
X1231072Y605756D01*
G01X1238945Y605754D02*
Y605751D01*
G01X1238946Y605756D02*
X1238945Y605754D01*
G01X1238947Y605757D02*
X1238946Y605756D01*
G01X1229574Y588624D02*
X1229575Y588627D01*
G01X1229574Y588622D02*
Y588624D01*
G01X1229573Y588621D02*
X1229574Y588622D01*
G01X1237448Y588624D02*
X1237449Y588627D01*
G01X1237448Y588622D02*
Y588624D01*
G01X1237447Y588621D02*
X1237448Y588622D01*
G01X1229305Y606485D02*
X1229299Y606538D01*
G01X1229311Y606353D02*
X1229305Y606485D01*
G01X1229317Y606147D02*
X1229311Y606353D01*
G01X1231340Y587893D02*
X1231346Y587840D01*
G01X1231334Y588025D02*
X1231340Y587893D01*
G01X1231328Y588231D02*
X1231334Y588025D01*
G01X1229304Y605511D02*
X1229299Y605553D01*
G01X1229308Y605413D02*
X1229304Y605511D01*
G01X1229312Y605261D02*
X1229308Y605413D01*
G01X1231342Y588867D02*
X1231346Y588825D01*
G01X1231337Y588965D02*
X1231342Y588867D01*
G01X1231333Y589117D02*
X1231337Y588965D01*
G01X1233502Y589645D02*
X1233507Y589615D01*
G01X1233498Y589841D02*
X1233502Y589645D01*
G01X1233496Y590169D02*
X1233498Y589841D01*
G01X1233494Y590571D02*
X1233496Y590169D01*
G01X1229565Y588770D02*
X1229573Y588621D01*
G01X1229558Y589184D02*
X1229565Y588770D01*
G01X1229553Y589804D02*
X1229558Y589184D01*
G01X1229551Y590552D02*
X1229553Y589804D01*
G01X1231081Y605608D02*
X1231073Y605757D01*
G01X1231088Y605193D02*
X1231081Y605608D01*
G01X1231093Y604573D02*
X1231088Y605193D01*
G01X1231095Y603826D02*
X1231093Y604573D01*
G01X1229569Y604698D02*
X1229573Y604772D01*
G01X1229565Y604491D02*
X1229569Y604698D01*
G01X1229563Y604181D02*
X1229565Y604491D01*
G01X1229562Y603807D02*
X1229563Y604181D01*
G01X1231077Y589680D02*
X1231073Y589606D01*
G01X1231080Y589887D02*
X1231077Y589680D01*
G01X1231083Y590197D02*
X1231080Y589887D01*
G01X1231084Y590571D02*
X1231083Y590197D01*
G01X1229553Y604573D02*
X1229551Y603826D01*
G01X1229558Y605193D02*
X1229553Y604573D01*
G01X1229565Y605608D02*
X1229558Y605193D01*
G01X1229573Y605757D02*
X1229565Y605608D01*
G01X1231093Y589804D02*
X1231095Y590552D01*
G01X1231088Y589184D02*
X1231093Y589804D01*
G01X1231081Y588770D02*
X1231088Y589184D01*
G01X1231073Y588621D02*
X1231081Y588770D01*
G01X1237427Y604573D02*
X1237425Y603826D01*
G01X1237432Y605193D02*
X1237427Y604573D01*
G01X1237439Y605608D02*
X1237432Y605193D01*
G01X1237447Y605757D02*
X1237439Y605608D01*
G01X1238967Y589804D02*
X1238969Y590552D01*
G01X1238962Y589184D02*
X1238967Y589804D01*
G01X1238955Y588770D02*
X1238962Y589184D01*
G01X1238947Y588621D02*
X1238955Y588770D01*
G01X1229574Y589607D02*
X1229573Y589606D01*
G01X1229574Y589610D02*
Y589607D01*
G01X1229575Y589617D02*
X1229574Y589610D01*
G01X1231072Y604771D02*
X1231073Y604772D01*
G01X1231072Y604768D02*
Y604771D01*
G01X1231071Y604761D02*
X1231072Y604768D01*
G01X1237448Y589607D02*
X1237447Y589606D01*
G01X1237448Y589610D02*
Y589607D01*
G01X1237449Y589617D02*
X1237448Y589610D01*
G01X1238946Y604771D02*
X1238947Y604772D01*
G01X1238946Y604768D02*
Y604771D01*
G01X1238945Y604761D02*
X1238946Y604768D01*
G01X1229308Y588965D02*
X1229312Y589117D01*
G01X1229304Y588867D02*
X1229308Y588965D01*
G01X1229299Y588825D02*
X1229304Y588867D01*
G01X1231337Y605413D02*
X1231333Y605261D01*
G01X1231342Y605511D02*
X1231337Y605413D01*
G01X1231346Y605553D02*
X1231342Y605511D01*
G01X1233241Y588965D02*
X1233245Y589117D01*
G01X1233236Y588867D02*
X1233241Y588965D01*
G01X1233232Y588825D02*
X1233236Y588867D01*
G01X1235279Y605413D02*
X1235275Y605261D01*
G01X1235284Y605511D02*
X1235279Y605413D01*
G01X1235288Y605553D02*
X1235284Y605511D01*
G01X1237182Y588965D02*
X1237186Y589117D01*
G01X1237178Y588867D02*
X1237182Y588965D01*
G01X1237173Y588825D02*
X1237178Y588867D01*
G01X1239211Y605413D02*
X1239207Y605261D01*
G01X1239216Y605511D02*
X1239211Y605413D01*
G01X1239220Y605553D02*
X1239216Y605511D01*
G01X1231334Y606353D02*
X1231328Y606147D01*
G01X1231340Y606485D02*
X1231334Y606353D01*
G01X1231346Y606538D02*
X1231340Y606485D01*
G01X1229311Y588025D02*
X1229317Y588231D01*
G01X1229305Y587893D02*
X1229311Y588025D01*
G01X1229299Y587840D02*
X1229305Y587893D01*
G01X1235276Y606353D02*
X1235270Y606147D01*
G01X1235282Y606485D02*
X1235276Y606353D01*
G01X1235288Y606538D02*
X1235282Y606485D01*
G01X1233244Y588025D02*
X1233250Y588231D01*
G01X1233238Y587893D02*
X1233244Y588025D01*
G01X1233232Y587840D02*
X1233238Y587893D01*
G01X1239208Y606353D02*
X1239202Y606147D01*
G01X1239214Y606485D02*
X1239208Y606353D01*
G01X1239220Y606538D02*
X1239214Y606485D01*
G01X1237185Y588025D02*
X1237191Y588231D01*
G01X1237179Y587893D02*
X1237185Y588025D01*
G01X1237173Y587840D02*
X1237179Y587893D01*
G01X1233505Y604209D02*
X1233504Y603807D01*
G01X1233508Y604537D02*
X1233505Y604209D01*
G01X1233512Y604733D02*
X1233508Y604537D01*
G01X1233516Y604763D02*
X1233512Y604733D01*
G01X1235015Y590169D02*
X1235016Y590571D01*
G01X1235012Y589841D02*
X1235015Y590169D01*
G01X1235008Y589645D02*
X1235012Y589841D01*
G01X1235003Y589615D02*
X1235008Y589645D01*
G01X1229563Y590197D02*
X1229562Y590571D01*
G01X1229565Y589887D02*
X1229563Y590197D01*
G01X1229569Y589680D02*
X1229565Y589887D01*
G01X1229573Y589606D02*
X1229569Y589680D01*
G01X1231083Y604181D02*
X1231084Y603807D01*
G01X1231080Y604491D02*
X1231083Y604181D01*
G01X1231077Y604698D02*
X1231080Y604491D01*
G01X1231073Y604772D02*
X1231077Y604698D01*
G01X1237437Y590197D02*
X1237436Y590571D01*
G01X1237439Y589887D02*
X1237437Y590197D01*
G01X1237443Y589680D02*
X1237439Y589887D01*
G01X1237447Y589606D02*
X1237443Y589680D01*
G01X1238957Y604181D02*
X1238958Y603807D01*
G01X1238954Y604491D02*
X1238957Y604181D01*
G01X1238951Y604698D02*
X1238954Y604491D01*
G01X1238947Y604772D02*
X1238951Y604698D01*
G01X1233247Y606485D02*
X1233241Y606538D01*
G01X1233253Y606353D02*
X1233247Y606485D01*
G01X1233259Y606147D02*
X1233253Y606353D01*
G01X1235273Y587893D02*
X1235279Y587840D01*
G01X1235267Y588025D02*
X1235273Y587893D01*
G01X1235261Y588231D02*
X1235267Y588025D01*
G01X1237179Y606485D02*
X1237173Y606538D01*
G01X1237185Y606353D02*
X1237179Y606485D01*
G01X1237191Y606147D02*
X1237185Y606353D01*
G01X1239214Y587893D02*
X1239220Y587840D01*
G01X1239208Y588025D02*
X1239214Y587893D01*
G01X1239202Y588231D02*
X1239208Y588025D01*
G01X1233245Y605511D02*
X1233241Y605553D01*
G01X1233250Y605413D02*
X1233245Y605511D01*
G01X1233254Y605261D02*
X1233250Y605413D01*
G01X1235274Y588867D02*
X1235279Y588825D01*
G01X1235270Y588965D02*
X1235274Y588867D01*
G01X1235266Y589117D02*
X1235270Y588965D01*
G01X1237178Y605511D02*
X1237173Y605553D01*
G01X1237182Y605413D02*
X1237178Y605511D01*
G01X1237186Y605261D02*
X1237182Y605413D01*
G01X1239216Y588867D02*
X1239220Y588825D01*
G01X1239211Y588965D02*
X1239216Y588867D01*
G01X1239207Y589117D02*
X1239211Y588965D01*
G01X1235017Y604733D02*
X1235013Y604763D01*
G01X1235021Y604537D02*
X1235017Y604733D01*
G01X1235024Y604209D02*
X1235021Y604537D01*
G01X1235025Y603807D02*
X1235024Y604209D01*
G01X1237439Y588770D02*
X1237447Y588621D01*
G01X1237432Y589184D02*
X1237439Y588770D01*
G01X1237427Y589804D02*
X1237432Y589184D01*
G01X1237425Y590552D02*
X1237427Y589804D01*
G01X1238955Y605608D02*
X1238947Y605757D01*
G01X1238962Y605193D02*
X1238955Y605608D01*
G01X1238967Y604573D02*
X1238962Y605193D01*
G01X1238969Y603826D02*
X1238967Y604573D01*
G01X1237443Y604698D02*
X1237447Y604772D01*
G01X1237439Y604491D02*
X1237443Y604698D01*
G01X1237437Y604181D02*
X1237439Y604491D01*
G01X1237436Y603807D02*
X1237437Y604181D01*
G01X1238951Y589680D02*
X1238947Y589606D01*
G01X1238954Y589887D02*
X1238951Y589680D01*
G01X1238957Y590197D02*
X1238954Y589887D01*
G01X1238958Y590571D02*
X1238957Y590197D01*
G01X1231072Y588622D02*
X1231073Y588621D01*
G01X1231071Y588624D02*
X1231072Y588622D01*
G01X1231071Y588627D02*
Y588624D01*
G01X1229574Y605756D02*
X1229573Y605757D01*
G01X1229574Y605754D02*
Y605756D01*
G01X1229575Y605751D02*
X1229574Y605754D01*
G01X1238946Y588622D02*
X1238947Y588621D01*
G01X1238945Y588624D02*
X1238946Y588622D01*
G01X1238945Y588627D02*
Y588624D01*
G01X1237448Y605756D02*
X1237447Y605757D01*
G01X1237448Y605754D02*
Y605756D01*
G01X1237449Y605751D02*
X1237448Y605754D01*
G01X1231072Y589610D02*
X1231071Y589617D01*
G01X1231072Y589607D02*
Y589610D01*
G01X1231073Y589606D02*
X1231072Y589607D01*
G01X1229574Y604768D02*
X1229575Y604761D01*
G01X1229574Y604771D02*
Y604768D01*
G01X1229573Y604772D02*
X1229574Y604771D01*
G01X1238946Y589610D02*
X1238945Y589617D01*
G01X1238946Y589607D02*
Y589610D01*
G01X1238947Y589606D02*
X1238946Y589607D01*
G01X1237448Y604768D02*
X1237449Y604761D01*
G01X1237448Y604771D02*
Y604768D01*
G01X1237447Y604772D02*
X1237448Y604771D01*
G01X1235309Y588823D02*
X1235324D01*
G01X1235294Y588824D02*
X1235309Y588823D01*
G01X1235279Y588825D02*
X1235294Y588824D01*
G01X1237143Y588823D02*
X1237128D01*
G01X1237158Y588824D02*
X1237143Y588823D01*
G01X1237173Y588825D02*
X1237158Y588824D01*
G01X1229269Y588823D02*
X1229254D01*
G01X1229284Y588824D02*
X1229269Y588823D01*
G01X1229299Y588825D02*
X1229284Y588824D01*
G01X1233202Y587839D02*
X1233187D01*
G01X1233217D02*
X1233202D01*
G01X1233232Y587840D02*
X1233217Y587839D01*
G01X1231361D02*
X1231346Y587840D01*
G01X1231376Y587839D02*
X1231361D01*
G01X1231391D02*
X1231376D01*
G01X1235294D02*
X1235279Y587840D01*
G01X1235309Y587839D02*
X1235294D01*
G01X1235324D02*
X1235309D01*
G01X1239235D02*
X1239220Y587840D01*
G01X1239250Y587839D02*
X1239235D01*
G01X1239265D02*
X1239250D01*
G01X1229284Y606539D02*
X1229299Y606538D01*
G01X1229269Y606539D02*
X1229284D01*
G01X1229254D02*
X1229269D01*
G01X1233226D02*
X1233241Y606538D01*
G01X1233211Y606539D02*
X1233226D01*
G01X1233196D02*
X1233211D01*
G01X1237158D02*
X1237173Y606538D01*
G01X1237143Y606539D02*
X1237158D01*
G01X1237128D02*
X1237143D01*
G01X1231361Y588824D02*
X1231346Y588825D01*
G01X1231376Y588823D02*
X1231361Y588824D01*
G01X1231391Y588823D02*
X1231376D01*
G01X1239235Y588824D02*
X1239220Y588825D01*
G01X1239250Y588823D02*
X1239235Y588824D01*
G01X1239265Y588823D02*
X1239250D01*
G01X1229284Y605554D02*
X1229299Y605553D01*
G01X1229269Y605555D02*
X1229284Y605554D01*
G01X1229254Y605555D02*
X1229269D01*
G01X1233226Y605554D02*
X1233241Y605553D01*
G01X1233211Y605555D02*
X1233226Y605554D01*
G01X1233196Y605555D02*
X1233211D01*
G01X1237158Y605554D02*
X1237173Y605553D01*
G01X1237143Y605555D02*
X1237158Y605554D01*
G01X1237128Y605555D02*
X1237143D01*
G01X1239250D02*
X1239265D01*
G01X1239235Y605554D02*
X1239250Y605555D01*
G01X1239220Y605553D02*
X1239235Y605554D01*
G01X1235318Y605555D02*
X1235333D01*
G01X1235303Y605554D02*
X1235318Y605555D01*
G01X1235288Y605553D02*
X1235303Y605554D01*
G01X1231376Y605555D02*
X1231391D01*
G01X1231361Y605554D02*
X1231376Y605555D01*
G01X1231346Y605553D02*
X1231361Y605554D01*
G01X1231504Y610476D02*
X1229142D01*
G01X1235441D02*
X1233079D01*
G01X1239378D02*
X1237016D01*
G01X1230992Y609492D02*
X1229654D01*
G01X1238866D02*
X1237528D01*
G01X1237370Y609394D02*
X1239024D01*
G01X1229496D02*
X1231150D01*
G01X1231504Y609295D02*
X1229142D01*
G01X1235441D02*
X1233079D01*
G01X1239378D02*
X1237016D01*
G01X1231150Y608902D02*
X1229496D01*
G01X1239024D02*
X1237370D01*
G01X1231740Y608035D02*
X1228906D01*
G01X1235677D02*
X1232843D01*
G01X1239614D02*
X1236780D01*
G01X1231150Y607130D02*
X1229496D01*
G01X1239024D02*
X1237370D01*
G01Y606638D02*
X1239024D01*
G01X1229496D02*
X1231150D01*
G01X1231740Y606539D02*
X1228906D01*
G01X1235677D02*
X1232843D01*
G01X1239614D02*
X1236780D01*
G01X1239024Y606382D02*
X1239614D01*
G01X1236780D02*
X1237370D01*
G01X1235087D02*
X1235677D01*
G01X1232843D02*
X1233433D01*
G01X1231150D02*
X1231740D01*
G01X1228906D02*
X1229496D01*
G01X1237191Y606147D02*
X1239202D01*
G01X1233259D02*
X1235270D01*
G01X1229317D02*
X1231328D01*
G01X1231073Y605757D02*
X1229573D01*
G01X1235014D02*
X1233515D01*
G01X1238947D02*
X1237447D01*
G01X1237460Y605738D02*
X1238933D01*
G01X1233528D02*
X1235001D01*
G01X1229586D02*
X1231059D01*
G01X1229496Y605713D02*
X1228906D01*
G01X1231740D02*
X1231150D01*
G01X1233433D02*
X1232843D01*
G01X1235677D02*
X1235087D01*
G01X1237370D02*
X1236780D01*
G01X1239614D02*
X1239024D01*
G01X1236780Y605555D02*
X1239614D01*
G01X1232843D02*
X1235677D01*
G01X1228906D02*
X1231740D01*
G01X1235087Y605457D02*
X1233433D01*
G01X1230806Y605368D02*
X1229840D01*
G01X1234747D02*
X1233782D01*
G01X1238680D02*
X1237714D01*
G01X1232843Y605358D02*
X1233157D01*
G01X1229220D02*
X1228906D01*
G01X1231740D02*
X1231425D01*
G01X1235677D02*
X1235362D01*
G01X1237094D02*
X1236780D01*
G01X1239614D02*
X1239299D01*
G01X1231333Y605261D02*
X1229312D01*
G01X1235275D02*
X1233254D01*
G01X1239207D02*
X1237186D01*
G01X1233433Y604965D02*
X1235087D01*
G01X1231073Y604772D02*
X1229573D01*
G01X1235014D02*
X1233515D01*
G01X1238947D02*
X1237447D01*
G01X1231071Y604763D02*
X1229575D01*
G01X1235013D02*
X1233516D01*
G01X1238945D02*
X1237449D01*
G01X1237669Y604441D02*
X1238725D01*
G01X1233736D02*
X1234793D01*
G01X1229795D02*
X1230851D01*
G01X1237016Y604394D02*
X1239378D01*
G01X1233079D02*
X1235441D01*
G01X1229142D02*
X1231504D01*
G01X1239299Y603862D02*
X1239614D01*
G01X1236780D02*
X1237094D01*
G01X1235362D02*
X1235677D01*
G01X1232843D02*
X1233157D01*
G01X1231425D02*
X1231740D01*
G01X1228906D02*
X1229220D01*
G01X1237425Y603826D02*
X1238969D01*
G01X1233493D02*
X1235036D01*
G01X1229551D02*
X1231095D01*
G01X1237436Y603807D02*
X1238958D01*
G01X1233504D02*
X1235025D01*
G01X1229562D02*
X1231084D01*
G01X1233433Y603193D02*
X1235087D01*
G01Y602701D02*
X1233433D01*
G01X1234929Y602602D02*
X1233591D01*
G01Y601618D02*
X1234929D01*
G01X1231120Y600999D02*
X1229525D01*
G01X1235062D02*
X1233467D01*
G01X1238994D02*
X1237399D01*
G01X1231425Y600890D02*
X1229220D01*
G01X1235362D02*
X1233157D01*
G01X1239299D02*
X1237094D01*
G01X1231192Y600239D02*
X1229453D01*
G01X1235134D02*
X1233395D01*
G01X1239066D02*
X1237327D01*
G01X1237402Y600037D02*
X1238992D01*
G01X1233469D02*
X1235060D01*
G01X1229528D02*
X1231118D01*
G01X1237349Y600013D02*
X1239045D01*
G01X1233416D02*
X1235113D01*
G01X1229475D02*
X1231171D01*
G01X1231178Y599945D02*
X1229468D01*
G01X1235120D02*
X1233409D01*
G01X1239052D02*
X1237342D01*
G01X1237323Y599353D02*
X1239071D01*
G01X1233390D02*
X1235139D01*
G01X1229449D02*
X1231197D01*
G01X1231169Y599051D02*
X1229477D01*
G01X1235110D02*
X1233419D01*
G01X1239043D02*
X1237351D01*
G01X1231178Y598961D02*
X1229468D01*
G01X1235120D02*
X1233409D01*
G01X1239052D02*
X1237342D01*
G01X1237094Y598635D02*
X1239299D01*
G01X1233157D02*
X1235362D01*
G01X1229220D02*
X1231425D01*
G01X1237094Y598468D02*
X1239299D01*
G01X1233157D02*
X1235362D01*
G01X1229220D02*
X1231425D01*
G01Y595910D02*
X1229220D01*
G01X1235362D02*
X1233157D01*
G01X1239299D02*
X1237094D01*
G01X1231425Y595743D02*
X1229220D01*
G01X1235362D02*
X1233157D01*
G01X1239299D02*
X1237094D01*
G01X1237342Y595417D02*
X1239052D01*
G01X1233400D02*
X1235110D01*
G01X1229468D02*
X1231178D01*
G01X1237351Y595327D02*
X1239043D01*
G01X1233409D02*
X1235101D01*
G01X1229477D02*
X1231169D01*
G01X1231197Y595025D02*
X1229449D01*
G01X1235129D02*
X1233381D01*
G01X1239071D02*
X1237323D01*
G01X1237342Y594433D02*
X1239052D01*
G01X1233400D02*
X1235110D01*
G01X1229468D02*
X1231178D01*
G01X1231171Y594365D02*
X1229475D01*
G01X1235103D02*
X1233407D01*
G01X1239045D02*
X1237349D01*
G01X1231118Y594341D02*
X1229528D01*
G01X1235050D02*
X1233460D01*
G01X1238992D02*
X1237402D01*
G01X1237327Y594139D02*
X1239066D01*
G01X1233386D02*
X1235125D01*
G01X1229453D02*
X1231192D01*
G01X1237094Y593488D02*
X1239299D01*
G01X1233157D02*
X1235362D01*
G01X1229220D02*
X1231425D01*
G01X1237399Y593379D02*
X1238994D01*
G01X1233458D02*
X1235053D01*
G01X1229525D02*
X1231120D01*
G01X1234929Y592760D02*
X1233591D01*
G01X1234929Y591776D02*
X1233591D01*
G01X1233433Y591677D02*
X1235087D01*
G01Y591185D02*
X1233433D01*
G01X1231084Y590571D02*
X1229562D01*
G01X1235016D02*
X1233494D01*
G01X1238958D02*
X1237436D01*
G01X1231095Y590552D02*
X1229551D01*
G01X1235027D02*
X1233483D01*
G01X1238969D02*
X1237425D01*
G01X1229220Y590516D02*
X1228906D01*
G01X1231740D02*
X1231425D01*
G01X1233157D02*
X1232843D01*
G01X1237094D02*
X1236780D01*
G01X1235677D02*
X1235362D01*
G01X1239614D02*
X1239299D01*
G01X1231504Y589984D02*
X1229142D01*
G01X1235441D02*
X1233079D01*
G01X1239378D02*
X1237016D01*
G01X1230851Y589937D02*
X1229795D01*
G01X1234783D02*
X1233727D01*
G01X1238725D02*
X1237669D01*
G01X1237449Y589615D02*
X1238945D01*
G01X1233507D02*
X1235003D01*
G01X1229575D02*
X1231071D01*
G01X1237447Y589606D02*
X1238947D01*
G01X1233505D02*
X1235005D01*
G01X1229573D02*
X1231073D01*
G01X1235087Y589413D02*
X1233433D01*
G01X1237186Y589117D02*
X1239207D01*
G01X1233245D02*
X1235266D01*
G01X1229312D02*
X1231333D01*
G01X1235362Y589020D02*
X1235677D01*
G01X1229220D02*
X1228906D01*
G01X1231740D02*
X1231425D01*
G01X1233157D02*
X1232843D01*
G01X1237094D02*
X1236780D01*
G01X1239614D02*
X1239299D01*
G01X1237714Y589010D02*
X1238680D01*
G01X1233772D02*
X1234738D01*
G01X1229840D02*
X1230806D01*
G01X1233433Y588921D02*
X1235087D01*
G01X1236780Y588823D02*
X1239614D01*
G01X1232843D02*
X1235677D01*
G01X1228906D02*
X1231740D01*
G01X1239024Y588665D02*
X1239614D01*
G01X1236780D02*
X1237370D01*
G01X1235087D02*
X1235677D01*
G01X1232843D02*
X1233433D01*
G01X1231150D02*
X1231740D01*
G01X1228906D02*
X1229496D01*
G01X1231059Y588640D02*
X1229586D01*
G01X1234992D02*
X1233519D01*
G01X1238933D02*
X1237460D01*
G01X1237447Y588621D02*
X1238947D01*
G01X1233505D02*
X1235005D01*
G01X1229573D02*
X1231073D01*
G01X1231328Y588231D02*
X1229317D01*
G01X1235261D02*
X1233250D01*
G01X1239202D02*
X1237191D01*
G01X1229496Y587996D02*
X1228906D01*
G01X1231740D02*
X1231150D01*
G01X1233433D02*
X1232843D01*
G01X1235677D02*
X1235087D01*
G01X1237370D02*
X1236780D01*
G01X1239614D02*
X1239024D01*
G01X1231740Y587839D02*
X1228906D01*
G01X1235677D02*
X1232843D01*
G01X1239614D02*
X1236780D01*
G01X1231150Y587740D02*
X1229496D01*
G01X1239024D02*
X1237370D01*
G01Y587248D02*
X1239024D01*
G01X1229496D02*
X1231150D01*
G01X1236780Y586343D02*
X1239614D01*
G01X1232843D02*
X1235677D01*
G01X1228906D02*
X1231740D01*
G01X1237370Y585476D02*
X1239024D01*
G01X1229496D02*
X1231150D01*
G01X1237016Y585083D02*
X1239378D01*
G01X1233079D02*
X1235441D01*
G01X1229142D02*
X1231504D01*
G01X1231150Y584984D02*
X1229496D01*
G01X1239024D02*
X1237370D01*
G01X1230992Y584886D02*
X1229654D01*
G01X1238866D02*
X1237528D01*
G01X1237016Y583902D02*
X1239378D01*
G01X1233079D02*
X1235441D01*
G01X1229142D02*
X1231504D01*
G01X1237714Y605368D02*
X1237460Y605738D01*
G01X1237449Y604760D02*
X1237669Y604441D01*
G01X1233782Y605368D02*
X1233528Y605738D01*
G01X1233736Y604441D02*
X1233515Y604763D01*
G01X1229840Y605368D02*
X1229586Y605738D01*
G01X1229575Y604760D02*
X1229795Y604441D01*
G01X1238945Y589618D02*
X1238725Y589937D01*
G01X1238680Y589010D02*
X1238933Y588640D01*
G01X1234783Y589937D02*
X1235005Y589615D01*
G01X1234738Y589010D02*
X1234992Y588640D01*
G01X1231071Y589618D02*
X1230851Y589937D01*
G01X1230806Y589010D02*
X1231059Y588640D01*
G01X1237678Y604394D02*
X1237669Y604441D01*
G01X1238716Y589984D02*
X1238725Y589937D01*
G01X1233736Y604441D02*
X1233746Y604394D01*
G01X1234783Y589937D02*
X1234774Y589984D01*
G01X1229804Y604394D02*
X1229795Y604441D01*
G01X1230842Y589984D02*
X1230851Y589937D01*
G01X1239071Y599353D02*
X1239207Y605261D01*
G01X1239202Y606147D02*
X1239066Y600239D01*
G01X1238693Y589984D02*
X1238680Y589010D01*
G01X1237701Y604394D02*
X1237714Y605368D01*
G01X1239614Y603862D02*
Y608035D01*
G01Y586343D02*
Y590516D01*
G01X1239579Y588823D02*
Y587839D01*
G01X1239575Y588823D02*
Y587839D01*
G01Y606539D02*
Y605555D01*
G01X1239378Y589984D02*
Y583902D01*
G01Y610476D02*
Y604394D01*
G01X1239299Y587839D02*
Y606539D01*
G01X1239220Y588825D02*
Y587840D01*
G01Y606538D02*
Y605553D01*
G01X1239024Y605555D02*
Y610396D01*
G01Y583982D02*
Y588823D01*
G01X1238945Y604760D02*
Y605751D01*
G01Y588627D02*
Y589618D01*
G01X1238866Y584965D02*
Y583902D01*
G01Y610476D02*
Y609413D01*
G01X1238591Y583902D02*
Y584886D01*
G01Y610476D02*
Y609492D01*
G01X1237803Y584886D02*
Y583902D01*
G01Y610476D02*
Y609492D01*
G01X1237528Y584965D02*
Y583902D01*
G01Y610476D02*
Y609413D01*
G01X1237449Y589618D02*
Y588627D01*
G01Y605751D02*
Y604760D01*
G01X1237370Y605555D02*
Y610396D01*
G01Y583982D02*
Y588823D01*
G01X1237173Y587840D02*
Y588825D01*
G01Y605553D02*
Y606538D01*
G01X1237094Y606539D02*
Y587839D01*
G01X1237016Y589984D02*
Y583902D01*
G01Y610476D02*
Y604394D01*
G01X1236819Y588823D02*
Y587839D01*
G01Y606539D02*
Y605555D01*
G01X1236814Y606539D02*
Y605555D01*
G01X1236780Y590516D02*
Y586343D01*
G01Y608035D02*
Y603862D01*
G01X1235677D02*
Y608035D01*
G01Y586343D02*
Y590516D01*
G01X1235642Y606539D02*
Y605555D01*
G01X1235638Y588823D02*
Y587839D01*
G01X1235633Y588823D02*
Y587839D01*
G01X1235441Y589984D02*
Y583902D01*
G01Y610476D02*
Y604394D01*
G01X1235362Y587839D02*
Y606539D01*
G01X1235288Y606538D02*
Y605553D01*
G01X1235279Y588825D02*
Y587840D01*
G01X1238680Y605368D02*
X1238693Y604394D01*
G01X1237714Y589010D02*
X1237701Y589984D01*
G01X1234747Y605368D02*
X1234760Y604394D01*
G01X1233772Y589010D02*
X1233759Y589984D01*
G01X1239207Y589117D02*
X1239071Y595025D01*
G01X1239066Y594139D02*
X1239202Y588231D01*
G01X1237327Y600239D02*
X1237191Y606147D01*
G01X1237186Y605261D02*
X1237323Y599353D01*
G01X1235266Y589117D02*
X1235129Y595025D01*
G01X1235125Y594139D02*
X1235261Y588231D01*
G01X1233395Y600239D02*
X1233259Y606147D01*
G01X1233254Y605261D02*
X1233390Y599353D01*
G01X1239045Y600013D02*
X1238994Y600999D01*
G01X1238992Y600037D02*
X1239043Y599051D01*
G01X1237402Y594341D02*
X1237351Y595327D01*
G01X1237349Y594365D02*
X1237399Y593379D01*
G01X1235113Y600013D02*
X1235062Y600999D01*
G01X1235060Y600037D02*
X1235110Y599051D01*
G01X1233460Y594341D02*
X1233409Y595327D01*
G01X1233407Y594365D02*
X1233458Y593379D01*
G01X1231171Y600013D02*
X1231120Y600999D01*
G01X1231118Y600037D02*
X1231169Y599051D01*
G01X1229528Y594341D02*
X1229477Y595327D01*
G01X1229475Y594365D02*
X1229525Y593379D01*
G01X1237669Y589937D02*
X1237678Y589984D01*
G01X1238725Y604441D02*
X1238716Y604394D01*
G01X1238994Y593379D02*
X1239045Y594365D01*
G01X1239043Y595327D02*
X1238992Y594341D01*
G01X1237351Y599051D02*
X1237402Y600037D01*
G01X1237399Y600999D02*
X1237349Y600013D01*
G01X1235053Y593379D02*
X1235103Y594365D01*
G01X1235101Y595327D02*
X1235050Y594341D01*
G01X1233419Y599051D02*
X1233469Y600037D01*
G01X1233467Y600999D02*
X1233416Y600013D01*
G01X1231120Y593379D02*
X1231171Y594365D01*
G01X1231169Y595327D02*
X1231118Y594341D01*
G01X1229477Y599051D02*
X1229528Y600037D01*
G01X1229525Y600999D02*
X1229475Y600013D01*
G01X1237191Y588231D02*
X1237327Y594139D01*
G01X1237323Y595025D02*
X1237186Y589117D01*
G01X1235139Y599353D02*
X1235275Y605261D01*
G01X1235270Y606147D02*
X1235134Y600239D01*
G01X1233250Y588231D02*
X1233386Y594139D01*
G01X1233381Y595025D02*
X1233245Y589117D01*
G01X1231197Y599353D02*
X1231333Y605261D01*
G01X1231328Y606147D02*
X1231192Y600239D01*
G01X1229317Y588231D02*
X1229453Y594139D01*
G01X1229449Y595025D02*
X1229312Y589117D01*
G01X1234751Y589984D02*
X1234738Y589010D01*
G01X1233769Y604394D02*
X1233782Y605368D01*
G01X1230819Y589984D02*
X1230806Y589010D01*
G01X1229827Y604394D02*
X1229840Y605368D01*
G01X1235087Y601698D02*
Y606539D01*
G01Y587839D02*
Y592680D01*
G01X1235013Y604760D02*
Y605751D01*
G01X1235003Y588627D02*
Y589618D01*
G01X1234929Y592760D02*
Y591696D01*
G01Y602681D02*
Y601618D01*
G01X1234654D02*
Y602602D01*
G01Y592760D02*
Y591776D01*
G01X1233866Y601618D02*
Y602602D01*
G01Y592760D02*
Y591776D01*
G01X1233591Y592760D02*
Y591696D01*
G01Y602682D02*
Y601618D01*
G01X1233516Y605751D02*
Y604760D01*
G01X1233507Y589618D02*
Y588627D01*
G01X1233433Y601698D02*
Y606539D01*
G01Y587839D02*
Y592680D01*
G01X1233241Y605553D02*
Y606538D01*
G01X1233232Y587840D02*
Y588825D01*
G01X1233157Y606539D02*
Y587839D01*
G01X1233079Y589984D02*
Y583902D01*
G01Y610476D02*
Y604394D01*
G01X1232887Y606539D02*
Y605555D01*
G01X1232882Y606539D02*
Y605555D01*
G01X1232877Y588823D02*
Y587839D01*
G01X1232843Y590516D02*
Y586343D01*
G01Y608035D02*
Y603862D01*
G01X1231740D02*
Y608035D01*
G01Y586343D02*
Y590516D01*
G01X1231705Y588823D02*
Y587839D01*
G01X1231701Y588823D02*
Y587839D01*
G01Y606539D02*
Y605555D01*
G01X1231504Y589984D02*
Y583902D01*
G01Y610476D02*
Y604394D01*
G01X1231425Y587839D02*
Y606539D01*
G01X1231346Y588825D02*
Y587840D01*
G01Y606538D02*
Y605553D01*
G01X1231150Y605555D02*
Y610396D01*
G01Y583982D02*
Y588823D01*
G01X1231071Y604760D02*
Y605751D01*
G01Y588627D02*
Y589618D01*
G01X1230992Y584965D02*
Y583902D01*
G01Y610476D02*
Y609413D01*
G01X1230717Y583902D02*
Y584886D01*
G01Y610476D02*
Y609492D01*
G01X1229929Y584886D02*
Y583902D01*
G01Y610476D02*
Y609492D01*
G01X1229654Y584965D02*
Y583902D01*
G01Y610476D02*
Y609413D01*
G01X1229575Y589618D02*
Y588627D01*
G01Y605751D02*
Y604760D01*
G01X1229496Y605555D02*
Y610396D01*
G01Y583982D02*
Y588823D01*
G01X1229299Y587840D02*
Y588825D01*
G01Y605553D02*
Y606538D01*
G01X1229220Y606539D02*
Y587839D01*
G01X1229142Y589984D02*
Y583902D01*
G01Y610476D02*
Y604394D01*
G01X1228945Y588823D02*
Y587839D01*
G01Y606539D02*
Y605555D01*
G01X1228940Y606539D02*
Y605555D01*
G01X1228906Y590516D02*
Y586343D01*
G01Y608035D02*
Y603862D01*
G01X1227803D02*
Y608035D01*
G01Y586343D02*
Y590516D01*
G01X1227768Y606539D02*
Y605555D01*
G01X1227764Y588823D02*
Y587839D01*
G01X1227759Y588823D02*
Y587839D01*
G01X1230806Y605368D02*
X1230819Y604394D01*
G01X1229840Y589010D02*
X1229827Y589984D01*
G01X1231333Y589117D02*
X1231197Y595025D01*
G01X1231192Y594139D02*
X1231328Y588231D01*
G01X1229453Y600239D02*
X1229317Y606147D01*
G01X1229312Y605261D02*
X1229449Y599353D01*
G01X1233736Y589984D02*
X1233727Y589937D01*
G01X1234783Y604394D02*
X1234793Y604441D01*
G01X1229795Y589937D02*
X1229804Y589984D01*
G01X1230851Y604441D02*
X1230842Y604394D01*
G01X1237460Y588640D02*
X1237714Y589010D01*
G01X1237669Y589937D02*
X1237449Y589618D01*
G01X1233519Y588640D02*
X1233772Y589010D01*
G01X1233506Y589615D02*
X1233727Y589937D01*
G01X1229586Y588640D02*
X1229840Y589010D01*
G01X1229795Y589937D02*
X1229575Y589618D01*
G01X1238725Y604441D02*
X1238945Y604760D01*
G01X1238933Y605738D02*
X1238680Y605368D01*
G01X1235014Y604763D02*
X1234793Y604441D01*
G01X1235001Y605738D02*
X1234747Y605368D01*
G01X1230851Y604441D02*
X1231071Y604760D01*
G01X1231059Y605738D02*
X1230806Y605368D01*
G01X1246819Y605754D02*
Y605751D01*
G01X1246820Y605756D02*
X1246819Y605754D01*
G01X1246821Y605757D02*
X1246820Y605756D01*
G01X1254693Y605754D02*
Y605751D01*
G01X1254694Y605756D02*
X1254693Y605754D01*
G01X1254695Y605757D02*
X1254694Y605756D01*
G01X1245322Y588624D02*
X1245323Y588627D01*
G01X1245322Y588622D02*
Y588624D01*
G01X1245321Y588621D02*
X1245322Y588622D01*
G01X1253196Y588624D02*
X1253197Y588627D01*
G01X1253196Y588622D02*
Y588624D01*
G01X1253195Y588621D02*
X1253196Y588622D01*
G01X1246820Y604768D02*
X1246819Y604763D01*
G01X1246820Y604771D02*
Y604768D01*
G01X1246821Y604772D02*
X1246820Y604771D01*
G01X1245322Y589610D02*
X1245323Y589615D01*
G01X1245322Y589607D02*
Y589610D01*
G01X1245321Y589606D02*
X1245322Y589607D01*
G01X1254694Y604768D02*
X1254693Y604763D01*
G01X1254694Y604771D02*
Y604768D01*
G01X1254695Y604772D02*
X1254694Y604771D01*
G01X1253196Y589610D02*
X1253197Y589615D01*
G01X1253196Y589607D02*
Y589610D01*
G01X1253195Y589606D02*
X1253196Y589607D01*
G01X1261070Y589610D02*
X1261071Y589615D01*
G01X1261070Y589607D02*
Y589610D01*
G01X1261069Y589606D02*
X1261070Y589607D01*
G01Y588624D02*
X1261071Y588627D01*
G01X1261070Y588622D02*
Y588624D01*
G01X1261069Y588621D02*
X1261070Y588622D01*
G01X1241115Y588965D02*
X1241119Y589117D01*
G01X1241110Y588867D02*
X1241115Y588965D01*
G01X1241106Y588825D02*
X1241110Y588867D01*
G01X1243153Y605413D02*
X1243149Y605261D01*
G01X1243158Y605511D02*
X1243153Y605413D01*
G01X1243162Y605553D02*
X1243158Y605511D01*
G01X1245056Y588965D02*
X1245060Y589117D01*
G01X1245052Y588867D02*
X1245056Y588965D01*
G01X1245047Y588825D02*
X1245052Y588867D01*
G01X1247086Y605413D02*
X1247081Y605261D01*
G01X1247090Y605511D02*
X1247086Y605413D01*
G01X1247094Y605553D02*
X1247090Y605511D01*
G01X1243150Y606353D02*
X1243144Y606147D01*
G01X1243156Y606485D02*
X1243150Y606353D01*
G01X1243162Y606538D02*
X1243156Y606485D01*
G01X1241118Y588025D02*
X1241124Y588231D01*
G01X1241112Y587893D02*
X1241118Y588025D01*
G01X1241106Y587840D02*
X1241112Y587893D01*
G01X1247082Y606353D02*
X1247076Y606147D01*
G01X1247088Y606485D02*
X1247082Y606353D01*
G01X1247094Y606538D02*
X1247088Y606485D01*
G01X1245059Y588025D02*
X1245065Y588231D01*
G01X1245053Y587893D02*
X1245059Y588025D01*
G01X1245047Y587840D02*
X1245053Y587893D01*
G01X1251024Y606353D02*
X1251018Y606147D01*
G01X1251030Y606485D02*
X1251024Y606353D01*
G01X1251036Y606538D02*
X1251030Y606485D01*
G01X1248992Y588025D02*
X1248998Y588231D01*
G01X1248986Y587893D02*
X1248992Y588025D01*
G01X1248980Y587840D02*
X1248986Y587893D01*
G01X1241379Y604209D02*
X1241378Y603807D01*
G01X1241382Y604537D02*
X1241379Y604209D01*
G01X1241386Y604733D02*
X1241382Y604537D01*
G01X1241390Y604763D02*
X1241386Y604733D01*
G01X1242889Y590169D02*
X1242890Y590571D01*
G01X1242886Y589841D02*
X1242889Y590169D01*
G01X1242882Y589645D02*
X1242886Y589841D01*
G01X1242877Y589615D02*
X1242882Y589645D01*
G01X1249253Y604209D02*
X1249252Y603807D01*
G01X1249256Y604537D02*
X1249253Y604209D01*
G01X1249260Y604733D02*
X1249256Y604537D01*
G01X1249264Y604763D02*
X1249260Y604733D01*
G01X1250763Y590169D02*
X1250764Y590571D01*
G01X1250760Y589841D02*
X1250763Y590169D01*
G01X1250756Y589645D02*
X1250760Y589841D01*
G01X1250751Y589615D02*
X1250756Y589645D01*
G01X1245322Y604771D02*
X1245321Y604772D01*
G01X1245322Y604768D02*
Y604771D01*
G01X1245323Y604763D02*
X1245322Y604768D01*
G01X1246820Y589607D02*
X1246821Y589606D01*
G01X1246820Y589610D02*
Y589607D01*
G01X1246819Y589615D02*
X1246820Y589610D01*
G01X1241121Y606485D02*
X1241115Y606538D01*
G01X1241127Y606353D02*
X1241121Y606485D01*
G01X1241133Y606147D02*
X1241127Y606353D01*
G01X1243147Y587893D02*
X1243153Y587840D01*
G01X1243141Y588025D02*
X1243147Y587893D01*
G01X1243135Y588231D02*
X1243141Y588025D01*
G01X1245053Y606485D02*
X1245047Y606538D01*
G01X1245059Y606353D02*
X1245053Y606485D01*
G01X1245065Y606147D02*
X1245059Y606353D01*
G01X1247088Y587893D02*
X1247094Y587840D01*
G01X1247082Y588025D02*
X1247088Y587893D01*
G01X1247076Y588231D02*
X1247082Y588025D01*
G01X1248995Y606485D02*
X1248989Y606538D01*
G01X1249001Y606353D02*
X1248995Y606485D01*
G01X1249007Y606147D02*
X1249001Y606353D01*
G01X1251021Y587893D02*
X1251027Y587840D01*
G01X1251015Y588025D02*
X1251021Y587893D01*
G01X1251009Y588231D02*
X1251015Y588025D01*
G01X1252927Y606485D02*
X1252921Y606538D01*
G01X1252933Y606353D02*
X1252927Y606485D01*
G01X1252939Y606147D02*
X1252933Y606353D01*
G01X1254962Y587893D02*
X1254968Y587840D01*
G01X1254956Y588025D02*
X1254962Y587893D01*
G01X1254951Y588231D02*
X1254956Y588025D01*
G01X1241119Y605511D02*
X1241115Y605553D01*
G01X1241124Y605413D02*
X1241119Y605511D01*
G01X1241128Y605261D02*
X1241124Y605413D01*
G01X1243148Y588867D02*
X1243153Y588825D01*
G01X1243144Y588965D02*
X1243148Y588867D01*
G01X1243140Y589117D02*
X1243144Y588965D01*
G01X1245052Y605511D02*
X1245047Y605553D01*
G01X1245056Y605413D02*
X1245052Y605511D01*
G01X1245060Y605261D02*
X1245056Y605413D01*
G01X1247090Y588867D02*
X1247094Y588825D01*
G01X1247086Y588965D02*
X1247090Y588867D01*
G01X1247081Y589117D02*
X1247086Y588965D01*
G01X1248993Y605511D02*
X1248989Y605553D01*
G01X1248998Y605413D02*
X1248993Y605511D01*
G01X1249002Y605261D02*
X1248998Y605413D01*
G01X1251022Y588867D02*
X1251027Y588825D01*
G01X1251018Y588965D02*
X1251022Y588867D01*
G01X1251014Y589117D02*
X1251018Y588965D01*
G01X1252926Y605511D02*
X1252921Y605553D01*
G01X1252930Y605413D02*
X1252926Y605511D01*
G01X1252934Y605261D02*
X1252930Y605413D01*
G01X1254964Y588867D02*
X1254969Y588825D01*
G01X1254960Y588965D02*
X1254964Y588867D01*
G01X1254955Y589117D02*
X1254960Y588965D01*
G01X1241376Y589645D02*
X1241381Y589615D01*
G01X1241372Y589841D02*
X1241376Y589645D01*
G01X1241370Y590169D02*
X1241372Y589841D01*
G01X1241368Y590571D02*
X1241370Y590169D01*
G01X1242891Y604733D02*
X1242887Y604763D01*
G01X1242895Y604537D02*
X1242891Y604733D01*
G01X1242898Y604209D02*
X1242895Y604537D01*
G01X1242899Y603807D02*
X1242898Y604209D01*
G01X1249250Y589645D02*
X1249255Y589615D01*
G01X1249246Y589841D02*
X1249250Y589645D01*
G01X1249244Y590169D02*
X1249246Y589841D01*
G01X1249242Y590571D02*
X1249244Y590169D01*
G01X1250765Y604733D02*
X1250761Y604763D01*
G01X1250769Y604537D02*
X1250765Y604733D01*
G01X1250772Y604209D02*
X1250769Y604537D01*
G01X1250773Y603807D02*
X1250772Y604209D01*
G01X1257124Y589645D02*
X1257129Y589615D01*
G01X1257120Y589841D02*
X1257124Y589645D01*
G01X1257118Y590169D02*
X1257120Y589841D01*
G01X1257117Y590571D02*
X1257118Y590169D01*
G01X1258639Y604733D02*
X1258635Y604763D01*
G01X1258643Y604537D02*
X1258639Y604733D01*
G01X1258646Y604209D02*
X1258643Y604537D01*
G01X1258647Y603807D02*
X1258646Y604209D01*
G01X1245313Y588770D02*
X1245321Y588621D01*
G01X1245306Y589184D02*
X1245313Y588770D01*
G01X1245301Y589804D02*
X1245306Y589184D01*
G01X1245299Y590552D02*
X1245301Y589804D01*
G01X1245317Y589679D02*
X1245321Y589606D01*
G01X1245313Y589887D02*
X1245317Y589679D01*
G01X1245311Y590200D02*
X1245313Y589887D01*
G01X1245310Y590571D02*
X1245311Y590200D01*
G01X1246825Y604699D02*
X1246821Y604772D01*
G01X1246828Y604491D02*
X1246825Y604699D01*
G01X1246831Y604178D02*
X1246828Y604491D01*
G01X1246832Y603807D02*
X1246831Y604178D01*
G01X1246829Y605608D02*
X1246821Y605757D01*
G01X1246836Y605193D02*
X1246829Y605608D01*
G01X1246841Y604573D02*
X1246836Y605193D01*
G01X1246843Y603826D02*
X1246841Y604573D01*
G01X1253187Y588770D02*
X1253195Y588621D01*
G01X1253180Y589184D02*
X1253187Y588770D01*
G01X1253175Y589804D02*
X1253180Y589184D01*
G01X1253173Y590552D02*
X1253175Y589804D01*
G01X1253191Y589679D02*
X1253195Y589606D01*
G01X1253187Y589887D02*
X1253191Y589679D01*
G01X1253185Y590200D02*
X1253187Y589887D01*
G01X1253184Y590571D02*
X1253185Y590200D01*
G01X1254699Y604699D02*
X1254695Y604772D01*
G01X1254702Y604491D02*
X1254699Y604699D01*
G01X1254705Y604178D02*
X1254702Y604491D01*
G01X1254706Y603807D02*
X1254705Y604178D01*
G01X1254703Y605608D02*
X1254695Y605757D01*
G01X1254710Y605193D02*
X1254703Y605608D01*
G01X1254715Y604573D02*
X1254710Y605193D01*
G01X1254717Y603826D02*
X1254715Y604573D01*
G01X1245301D02*
X1245299Y603826D01*
G01X1245306Y605193D02*
X1245301Y604573D01*
G01X1245313Y605608D02*
X1245306Y605193D01*
G01X1245321Y605757D02*
X1245313Y605608D01*
G01X1246841Y589804D02*
X1246843Y590552D01*
G01X1246836Y589184D02*
X1246841Y589804D01*
G01X1246829Y588770D02*
X1246836Y589184D01*
G01X1246821Y588621D02*
X1246829Y588770D01*
G01X1253175Y604573D02*
X1253173Y603826D01*
G01X1253180Y605193D02*
X1253175Y604573D01*
G01X1253187Y605608D02*
X1253180Y605193D01*
G01X1253195Y605757D02*
X1253187Y605608D01*
G01X1254715Y589804D02*
X1254717Y590552D01*
G01X1254710Y589184D02*
X1254715Y589804D01*
G01X1254703Y588770D02*
X1254710Y589184D01*
G01X1254695Y588621D02*
X1254703Y588770D01*
G01X1261049Y604573D02*
X1261047Y603826D01*
G01X1261054Y605193D02*
X1261049Y604573D01*
G01X1261061Y605608D02*
X1261054Y605193D01*
G01X1261069Y605757D02*
X1261061Y605608D01*
G01X1245311Y604178D02*
X1245310Y603807D01*
G01X1245313Y604491D02*
X1245311Y604178D01*
G01X1245317Y604699D02*
X1245313Y604491D01*
G01X1245321Y604772D02*
X1245317Y604699D01*
G01X1246831Y590200D02*
X1246832Y590571D01*
G01X1246828Y589887D02*
X1246831Y590200D01*
G01X1246825Y589679D02*
X1246828Y589887D01*
G01X1246821Y589606D02*
X1246825Y589679D01*
G01X1253185Y604178D02*
X1253184Y603807D01*
G01X1253187Y604491D02*
X1253185Y604178D01*
G01X1253191Y604699D02*
X1253187Y604491D01*
G01X1253195Y604772D02*
X1253191Y604699D01*
G01X1254705Y590200D02*
X1254706Y590571D01*
G01X1254702Y589887D02*
X1254705Y590200D01*
G01X1254699Y589679D02*
X1254702Y589887D01*
G01X1254695Y589606D02*
X1254699Y589679D01*
G01X1261059Y604178D02*
X1261058Y603807D01*
G01X1261061Y604491D02*
X1261059Y604178D01*
G01X1261065Y604699D02*
X1261061Y604491D01*
G01X1261069Y604772D02*
X1261065Y604699D01*
G01X1248989Y588965D02*
X1248993Y589117D01*
G01X1248984Y588867D02*
X1248989Y588965D01*
G01X1248980Y588825D02*
X1248984Y588867D01*
G01X1251027Y605413D02*
X1251023Y605261D01*
G01X1251032Y605511D02*
X1251027Y605413D01*
G01X1251036Y605553D02*
X1251032Y605511D01*
G01X1252930Y588965D02*
X1252934Y589117D01*
G01X1252926Y588867D02*
X1252930Y588965D01*
G01X1252921Y588825D02*
X1252926Y588867D01*
G01X1254960Y605413D02*
X1254955Y605261D01*
G01X1254964Y605511D02*
X1254960Y605413D01*
G01X1254968Y605553D02*
X1254964Y605511D01*
G01X1256863Y588965D02*
X1256867Y589117D01*
G01X1256858Y588867D02*
X1256863Y588965D01*
G01X1256854Y588825D02*
X1256858Y588867D01*
G01X1258901Y605413D02*
X1258897Y605261D01*
G01X1258906Y605511D02*
X1258901Y605413D01*
G01X1258910Y605553D02*
X1258906Y605511D01*
G01X1260804Y588965D02*
X1260808Y589117D01*
G01X1260800Y588867D02*
X1260804Y588965D01*
G01X1260795Y588825D02*
X1260800Y588867D01*
G01X1254956Y606353D02*
X1254951Y606147D01*
G01X1254962Y606485D02*
X1254956Y606353D01*
G01X1254968Y606538D02*
X1254962Y606485D01*
G01X1252933Y588025D02*
X1252939Y588231D01*
G01X1252927Y587893D02*
X1252933Y588025D01*
G01X1252921Y587840D02*
X1252927Y587893D01*
G01X1258898Y606353D02*
X1258892Y606147D01*
G01X1258904Y606485D02*
X1258898Y606353D01*
G01X1258910Y606538D02*
X1258904Y606485D01*
G01X1256866Y588025D02*
X1256872Y588231D01*
G01X1256860Y587893D02*
X1256866Y588025D01*
G01X1256854Y587840D02*
X1256860Y587893D01*
G01X1260807Y588025D02*
X1260813Y588231D01*
G01X1260801Y587893D02*
X1260807Y588025D01*
G01X1260795Y587840D02*
X1260801Y587893D01*
G01X1257127Y604209D02*
X1257126Y603807D01*
G01X1257130Y604537D02*
X1257127Y604209D01*
G01X1257134Y604733D02*
X1257130Y604537D01*
G01X1257138Y604763D02*
X1257134Y604733D01*
G01X1258637Y590169D02*
X1258638Y590571D01*
G01X1258634Y589841D02*
X1258637Y590169D01*
G01X1258630Y589645D02*
X1258634Y589841D01*
G01X1258625Y589615D02*
X1258630Y589645D01*
G01X1253196Y604771D02*
X1253195Y604772D01*
G01X1253196Y604768D02*
Y604771D01*
G01X1253197Y604763D02*
X1253196Y604768D01*
G01X1254694Y589607D02*
X1254695Y589606D01*
G01X1254694Y589610D02*
Y589607D01*
G01X1254693Y589615D02*
X1254694Y589610D01*
G01X1261070Y604771D02*
X1261069Y604772D01*
G01X1261070Y604768D02*
Y604771D01*
G01X1261071Y604763D02*
X1261070Y604768D01*
G01X1256869Y606485D02*
X1256863Y606538D01*
G01X1256875Y606353D02*
X1256869Y606485D01*
G01X1256881Y606147D02*
X1256875Y606353D01*
G01X1258895Y587893D02*
X1258901Y587840D01*
G01X1258889Y588025D02*
X1258895Y587893D01*
G01X1258883Y588231D02*
X1258889Y588025D01*
G01X1260801Y606485D02*
X1260795Y606538D01*
G01X1260807Y606353D02*
X1260801Y606485D01*
G01X1260813Y606147D02*
X1260807Y606353D01*
G01X1256867Y605511D02*
X1256863Y605553D01*
G01X1256872Y605413D02*
X1256867Y605511D01*
G01X1256876Y605261D02*
X1256872Y605413D01*
G01X1258896Y588867D02*
X1258901Y588825D01*
G01X1258892Y588965D02*
X1258896Y588867D01*
G01X1258888Y589117D02*
X1258892Y588965D01*
G01X1260800Y605511D02*
X1260795Y605553D01*
G01X1260804Y605413D02*
X1260800Y605511D01*
G01X1260808Y605261D02*
X1260804Y605413D01*
G01X1261061Y588770D02*
X1261069Y588621D01*
G01X1261054Y589184D02*
X1261061Y588770D01*
G01X1261049Y589804D02*
X1261054Y589184D01*
G01X1261047Y590552D02*
X1261049Y589804D01*
G01X1261065Y589679D02*
X1261069Y589606D01*
G01X1261061Y589887D02*
X1261065Y589679D01*
G01X1261059Y590200D02*
X1261061Y589887D01*
G01X1261058Y590571D02*
X1261059Y590200D01*
G01X1246820Y588622D02*
X1246821Y588621D01*
G01X1246819Y588624D02*
X1246820Y588622D01*
G01X1246819Y588627D02*
Y588624D01*
G01X1245322Y605756D02*
X1245321Y605757D01*
G01X1245322Y605754D02*
Y605756D01*
G01X1245323Y605751D02*
X1245322Y605754D01*
G01X1254694Y588622D02*
X1254695Y588621D01*
G01X1254693Y588624D02*
X1254694Y588622D01*
G01X1254693Y588627D02*
Y588624D01*
G01X1253196Y605756D02*
X1253195Y605757D01*
G01X1253196Y605754D02*
Y605756D01*
G01X1253197Y605751D02*
X1253196Y605754D01*
G01X1261070Y605756D02*
X1261069Y605757D01*
G01X1261070Y605754D02*
Y605756D01*
G01X1261071Y605751D02*
X1261070Y605754D01*
G01X1260765Y588823D02*
X1260750D01*
G01X1260780Y588824D02*
X1260765Y588823D01*
G01X1260795Y588825D02*
X1260780Y588824D01*
G01X1256824Y588823D02*
X1256809D01*
G01X1256839Y588824D02*
X1256824Y588823D01*
G01X1256854Y588825D02*
X1256839Y588824D01*
G01X1252891Y588823D02*
X1252876D01*
G01X1252906Y588824D02*
X1252891Y588823D01*
G01X1252921Y588825D02*
X1252906Y588824D01*
G01X1248950Y588823D02*
X1248935D01*
G01X1248965Y588824D02*
X1248950Y588823D01*
G01X1248980Y588825D02*
X1248965Y588824D01*
G01X1245017Y588823D02*
X1245002D01*
G01X1245032Y588824D02*
X1245017Y588823D01*
G01X1245047Y588825D02*
X1245032Y588824D01*
G01X1241076Y588823D02*
X1241061D01*
G01X1241091Y588824D02*
X1241076Y588823D01*
G01X1241106Y588825D02*
X1241091Y588824D01*
G01X1258940Y605555D02*
X1258955D01*
G01X1258925Y605554D02*
X1258940Y605555D01*
G01X1258910Y605553D02*
X1258925Y605554D01*
G01X1254999Y605555D02*
X1255014D01*
G01X1254984Y605554D02*
X1254999Y605555D01*
G01X1254968Y605553D02*
X1254984Y605554D01*
G01X1247124Y605555D02*
X1247140D01*
G01X1247109Y605554D02*
X1247124Y605555D01*
G01X1247094Y605553D02*
X1247109Y605554D01*
G01X1260765Y587839D02*
X1260750D01*
G01X1260780D02*
X1260765D01*
G01X1260795Y587840D02*
X1260780Y587839D01*
G01X1256824D02*
X1256809D01*
G01X1256839D02*
X1256824D01*
G01X1256854Y587840D02*
X1256839Y587839D01*
G01X1252891D02*
X1252876D01*
G01X1252906D02*
X1252891D01*
G01X1252921Y587840D02*
X1252906Y587839D01*
G01X1248950D02*
X1248935D01*
G01X1248965D02*
X1248950D01*
G01X1248980Y587840D02*
X1248965Y587839D01*
G01X1245017D02*
X1245002D01*
G01X1245032D02*
X1245017D01*
G01X1245047Y587840D02*
X1245032Y587839D01*
G01X1241076D02*
X1241061D01*
G01X1241091D02*
X1241076D01*
G01X1241106Y587840D02*
X1241091Y587839D01*
G01X1258940Y606539D02*
X1258955D01*
G01X1258925D02*
X1258940D01*
G01X1258910Y606538D02*
X1258925Y606539D01*
G01X1254999D02*
X1255014D01*
G01X1254984D02*
X1254999D01*
G01X1254968Y606538D02*
X1254984Y606539D01*
G01X1251066D02*
X1251081D01*
G01X1251051D02*
X1251066D01*
G01X1251036Y606538D02*
X1251051Y606539D01*
G01X1243168Y587839D02*
X1243153Y587840D01*
G01X1243183Y587839D02*
X1243168D01*
G01X1243198D02*
X1243183D01*
G01X1247109D02*
X1247094Y587840D01*
G01X1247124Y587839D02*
X1247109D01*
G01X1247140D02*
X1247124D01*
G01X1251042D02*
X1251027Y587840D01*
G01X1251057Y587839D02*
X1251042D01*
G01X1251072D02*
X1251057D01*
G01X1254984D02*
X1254968Y587840D01*
G01X1254999Y587839D02*
X1254984D01*
G01X1255014D02*
X1254999D01*
G01X1258916D02*
X1258901Y587840D01*
G01X1258931Y587839D02*
X1258916D01*
G01X1258946D02*
X1258931D01*
G01X1241100Y606539D02*
X1241115Y606538D01*
G01X1241085Y606539D02*
X1241100D01*
G01X1241070D02*
X1241085D01*
G01X1245032D02*
X1245047Y606538D01*
G01X1245017Y606539D02*
X1245032D01*
G01X1245002D02*
X1245017D01*
G01X1248974D02*
X1248989Y606538D01*
G01X1248959Y606539D02*
X1248974D01*
G01X1248944D02*
X1248959D01*
G01X1252906D02*
X1252921Y606538D01*
G01X1252891Y606539D02*
X1252906D01*
G01X1252876D02*
X1252891D01*
G01X1256848D02*
X1256863Y606538D01*
G01X1256833Y606539D02*
X1256848D01*
G01X1256818D02*
X1256833D01*
G01X1260780D02*
X1260795Y606538D01*
G01X1260765Y606539D02*
X1260780D01*
G01X1260750D02*
X1260765D01*
G01X1243168Y588824D02*
X1243153Y588825D01*
G01X1243183Y588823D02*
X1243168Y588824D01*
G01X1243198Y588823D02*
X1243183D01*
G01X1247109Y588824D02*
X1247094Y588825D01*
G01X1247124Y588823D02*
X1247109Y588824D01*
G01X1247140Y588823D02*
X1247124D01*
G01X1251042Y588824D02*
X1251027Y588825D01*
G01X1251057Y588823D02*
X1251042Y588824D01*
G01X1251072Y588823D02*
X1251057D01*
G01X1254984Y588824D02*
X1254968Y588825D01*
G01X1254999Y588823D02*
X1254984Y588824D01*
G01X1255014Y588823D02*
X1254999D01*
G01X1258916Y588824D02*
X1258901Y588825D01*
G01X1258931Y588823D02*
X1258916Y588824D01*
G01X1258946Y588823D02*
X1258931D01*
G01X1241100Y605554D02*
X1241115Y605553D01*
G01X1241085Y605555D02*
X1241100Y605554D01*
G01X1241070Y605555D02*
X1241085D01*
G01X1245032Y605554D02*
X1245047Y605553D01*
G01X1245017Y605555D02*
X1245032Y605554D01*
G01X1245002Y605555D02*
X1245017D01*
G01X1248974Y605554D02*
X1248989Y605553D01*
G01X1248959Y605555D02*
X1248974Y605554D01*
G01X1248944Y605555D02*
X1248959D01*
G01X1252906Y605554D02*
X1252921Y605553D01*
G01X1252891Y605555D02*
X1252906Y605554D01*
G01X1252876Y605555D02*
X1252891D01*
G01X1260780Y605554D02*
X1260795Y605553D01*
G01X1260765Y605555D02*
X1260780Y605554D01*
G01X1260750Y605555D02*
X1260765D01*
G01X1256833D02*
X1256818D01*
G01X1256848Y605554D02*
X1256833Y605555D01*
G01X1256863Y605553D02*
X1256848Y605554D01*
G01X1247124Y606539D02*
X1247140D01*
G01X1247109D02*
X1247124D01*
G01X1247094Y606538D02*
X1247109Y606539D01*
G01X1243192D02*
X1243207D01*
G01X1243177D02*
X1243192D01*
G01X1243162Y606538D02*
X1243177Y606539D01*
G01X1243315Y610476D02*
X1240953D01*
G01X1247252D02*
X1244890D01*
G01X1251189D02*
X1248827D01*
G01X1255126D02*
X1252764D01*
G01X1259063D02*
X1256701D01*
G01X1263000D02*
X1260638D01*
G01X1246740Y609492D02*
X1245402D01*
G01X1254614D02*
X1253276D01*
G01X1262488D02*
X1261150D01*
G01X1260992Y609394D02*
X1262646D01*
G01X1253118D02*
X1254772D01*
G01X1245244D02*
X1246898D01*
G01X1243315Y609295D02*
X1240953D01*
G01X1247252D02*
X1244890D01*
G01X1251189D02*
X1248827D01*
G01X1255126D02*
X1252764D01*
G01X1259063D02*
X1256701D01*
G01X1263000D02*
X1260638D01*
G01X1246898Y608902D02*
X1245244D01*
G01X1254772D02*
X1253118D01*
G01X1262646D02*
X1260992D01*
G01X1243551Y608035D02*
X1240717D01*
G01X1247488D02*
X1244654D01*
G01X1251425D02*
X1248591D01*
G01X1255362D02*
X1252528D01*
G01X1259299D02*
X1256465D01*
G01X1263236D02*
X1260402D01*
G01X1246898Y607130D02*
X1245244D01*
G01X1254772D02*
X1253118D01*
G01X1262646D02*
X1260992D01*
G01Y606638D02*
X1262646D01*
G01X1253118D02*
X1254772D01*
G01X1245244D02*
X1246898D01*
G01X1243551Y606539D02*
X1240717D01*
G01X1247488D02*
X1244654D01*
G01X1251425D02*
X1248591D01*
G01X1255362D02*
X1252528D01*
G01X1259299D02*
X1256465D01*
G01X1263236D02*
X1260402D01*
G01Y606382D02*
X1260992D01*
G01X1258709D02*
X1259299D01*
G01X1256465D02*
X1257055D01*
G01X1254772D02*
X1255362D01*
G01X1252528D02*
X1253118D01*
G01X1250835D02*
X1251425D01*
G01X1248591D02*
X1249181D01*
G01X1246898D02*
X1247488D01*
G01X1244654D02*
X1245244D01*
G01X1242961D02*
X1243551D01*
G01X1240717D02*
X1241307D01*
G01X1260813Y606147D02*
X1262825D01*
G01X1256881D02*
X1258892D01*
G01X1252939D02*
X1254951D01*
G01X1249007D02*
X1251018D01*
G01X1245065D02*
X1247076D01*
G01X1241133D02*
X1243144D01*
G01X1242888Y605757D02*
X1241389D01*
G01X1246821D02*
X1245321D01*
G01X1250762D02*
X1249263D01*
G01X1254695D02*
X1253195D01*
G01X1258636D02*
X1257137D01*
G01X1262569D02*
X1261069D01*
G01X1261082Y605738D02*
X1262555D01*
G01X1257150D02*
X1258623D01*
G01X1253208D02*
X1254681D01*
G01X1249276D02*
X1250749D01*
G01X1245334D02*
X1246807D01*
G01X1241402D02*
X1242875D01*
G01X1241307Y605713D02*
X1240717D01*
G01X1243551D02*
X1242961D01*
G01X1245244D02*
X1244654D01*
G01X1247488D02*
X1246898D01*
G01X1249181D02*
X1248591D01*
G01X1251425D02*
X1250835D01*
G01X1253118D02*
X1252528D01*
G01X1255362D02*
X1254772D01*
G01X1257055D02*
X1256465D01*
G01X1259299D02*
X1258709D01*
G01X1260992D02*
X1260402D01*
G01Y605555D02*
X1263236D01*
G01X1252528D02*
X1255362D01*
G01X1248591D02*
X1251425D01*
G01X1244654D02*
X1247488D01*
G01X1240717D02*
X1243551D01*
G01X1259299D02*
X1256465D01*
G01X1242961Y605457D02*
X1241307D01*
G01X1250835D02*
X1249181D01*
G01X1258709D02*
X1257055D01*
G01X1242621Y605368D02*
X1241656D01*
G01X1246554D02*
X1245588D01*
G01X1250495D02*
X1249530D01*
G01X1254428D02*
X1253462D01*
G01X1258369D02*
X1257404D01*
G01X1262302D02*
X1261336D01*
G01X1260402Y605358D02*
X1260717D01*
G01X1256465D02*
X1256780D01*
G01X1252528D02*
X1252843D01*
G01X1248591D02*
X1248906D01*
G01X1244654D02*
X1244968D01*
G01X1240717D02*
X1241031D01*
G01X1243551D02*
X1243236D01*
G01X1247488D02*
X1247173D01*
G01X1251425D02*
X1251110D01*
G01X1255362D02*
X1255047D01*
G01X1259299D02*
X1258984D01*
G01X1243149Y605261D02*
X1241128D01*
G01X1247081D02*
X1245060D01*
G01X1251023D02*
X1249002D01*
G01X1254955D02*
X1252934D01*
G01X1258897D02*
X1256876D01*
G01X1262829D02*
X1260808D01*
G01X1257055Y604965D02*
X1258709D01*
G01X1249181D02*
X1250835D01*
G01X1241307D02*
X1242961D01*
G01X1242888Y604772D02*
X1241389D01*
G01X1246821D02*
X1245321D01*
G01X1250762D02*
X1249263D01*
G01X1254695D02*
X1253195D01*
G01X1258636D02*
X1257137D01*
G01X1262569D02*
X1261069D01*
G01X1242887Y604763D02*
X1241390D01*
G01X1246819D02*
X1245323D01*
G01X1250761D02*
X1249264D01*
G01X1254693D02*
X1253197D01*
G01X1258635D02*
X1257138D01*
G01X1262567D02*
X1261071D01*
G01X1261291Y604441D02*
X1262347D01*
G01X1257358D02*
X1258415D01*
G01X1253417D02*
X1254473D01*
G01X1249484D02*
X1250541D01*
G01X1245543D02*
X1246599D01*
G01X1241610D02*
X1242667D01*
G01X1243315Y604394D02*
X1240953D01*
G01X1247252D02*
X1244890D01*
G01X1251189D02*
X1248827D01*
G01X1255126D02*
X1252764D01*
G01X1259063D02*
X1256701D01*
G01X1263000D02*
X1260638D01*
G01X1260402Y603862D02*
X1260717D01*
G01X1258984D02*
X1259299D01*
G01X1256465D02*
X1256780D01*
G01X1255047D02*
X1255362D01*
G01X1252528D02*
X1252843D01*
G01X1251110D02*
X1251425D01*
G01X1248591D02*
X1248906D01*
G01X1247173D02*
X1247488D01*
G01X1244654D02*
X1244968D01*
G01X1243236D02*
X1243551D01*
G01X1240717D02*
X1241031D01*
G01X1261047Y603826D02*
X1262591D01*
G01X1257115D02*
X1258658D01*
G01X1253173D02*
X1254717D01*
G01X1249241D02*
X1250784D01*
G01X1245299D02*
X1246843D01*
G01X1241367D02*
X1242910D01*
G01X1261058Y603807D02*
X1262580D01*
G01X1257126D02*
X1258647D01*
G01X1253184D02*
X1254706D01*
G01X1249252D02*
X1250773D01*
G01X1245310D02*
X1246832D01*
G01X1241378D02*
X1242899D01*
G01X1257055Y603193D02*
X1258709D01*
G01X1249181D02*
X1250835D01*
G01X1241307D02*
X1242961D01*
G01Y602701D02*
X1241307D01*
G01X1250835D02*
X1249181D01*
G01X1258709D02*
X1257055D01*
G01X1242803Y602602D02*
X1241465D01*
G01X1250677D02*
X1249339D01*
G01X1258551D02*
X1257213D01*
G01Y601618D02*
X1258551D01*
G01X1249339D02*
X1250677D01*
G01X1241465D02*
X1242803D01*
G01X1242936Y600999D02*
X1241341D01*
G01X1246868D02*
X1245273D01*
G01X1250810D02*
X1249215D01*
G01X1254742D02*
X1253147D01*
G01X1258684D02*
X1257089D01*
G01X1262616D02*
X1261021D01*
G01X1243236Y600890D02*
X1241031D01*
G01X1247173D02*
X1244968D01*
G01X1251110D02*
X1248906D01*
G01X1255047D02*
X1252843D01*
G01X1258984D02*
X1256780D01*
G01X1262921D02*
X1260717D01*
G01X1243008Y600239D02*
X1241269D01*
G01X1246940D02*
X1245201D01*
G01X1250882D02*
X1249143D01*
G01X1254814D02*
X1253075D01*
G01X1258756D02*
X1257017D01*
G01X1262688D02*
X1260949D01*
G01X1261024Y600037D02*
X1262614D01*
G01X1257091D02*
X1258682D01*
G01X1253150D02*
X1254740D01*
G01X1249217D02*
X1250808D01*
G01X1245276D02*
X1246866D01*
G01X1241343D02*
X1242934D01*
G01X1260971Y600013D02*
X1262667D01*
G01X1257038D02*
X1258735D01*
G01X1253097D02*
X1254793D01*
G01X1249164D02*
X1250861D01*
G01X1245223D02*
X1246919D01*
G01X1241290D02*
X1242987D01*
G01X1242994Y599945D02*
X1241283D01*
G01X1246926D02*
X1245216D01*
G01X1250868D02*
X1249157D01*
G01X1254800D02*
X1253090D01*
G01X1258742D02*
X1257031D01*
G01X1262674D02*
X1260964D01*
G01X1260945Y599353D02*
X1262693D01*
G01X1257012D02*
X1258761D01*
G01X1253071D02*
X1254819D01*
G01X1249138D02*
X1250887D01*
G01X1245197D02*
X1246945D01*
G01X1241264D02*
X1243013D01*
G01X1242984Y599051D02*
X1241293D01*
G01X1246917D02*
X1245225D01*
G01X1250858D02*
X1249167D01*
G01X1254791D02*
X1253099D01*
G01X1258732D02*
X1257041D01*
G01X1262665D02*
X1260973D01*
G01X1242994Y598961D02*
X1241283D01*
G01X1246926D02*
X1245216D01*
G01X1250868D02*
X1249157D01*
G01X1254800D02*
X1253090D01*
G01X1258742D02*
X1257031D01*
G01X1262674D02*
X1260964D01*
G01X1260717Y598635D02*
X1262921D01*
G01X1256780D02*
X1258984D01*
G01X1252843D02*
X1255047D01*
G01X1248906D02*
X1251110D01*
G01X1244968D02*
X1247173D01*
G01X1241031D02*
X1243236D01*
G01X1260717Y598468D02*
X1262921D01*
G01X1256780D02*
X1258984D01*
G01X1252843D02*
X1255047D01*
G01X1248906D02*
X1251110D01*
G01X1244968D02*
X1247173D01*
G01X1241031D02*
X1243236D01*
G01Y595910D02*
X1241031D01*
G01X1247173D02*
X1244968D01*
G01X1251110D02*
X1248906D01*
G01X1255047D02*
X1252843D01*
G01X1258984D02*
X1256780D01*
G01X1262921D02*
X1260717D01*
G01X1243236Y595743D02*
X1241031D01*
G01X1247173D02*
X1244968D01*
G01X1251110D02*
X1248906D01*
G01X1255047D02*
X1252843D01*
G01X1258984D02*
X1256780D01*
G01X1262921D02*
X1260717D01*
G01X1260964Y595417D02*
X1262674D01*
G01X1257022D02*
X1258732D01*
G01X1253090D02*
X1254800D01*
G01X1249148D02*
X1250858D01*
G01X1245216D02*
X1246926D01*
G01X1241274D02*
X1242984D01*
G01X1260973Y595327D02*
X1262665D01*
G01X1257031D02*
X1258723D01*
G01X1253099D02*
X1254791D01*
G01X1249157D02*
X1250849D01*
G01X1245225D02*
X1246917D01*
G01X1241283D02*
X1242975D01*
G01X1243003Y595025D02*
X1241255D01*
G01X1246945D02*
X1245197D01*
G01X1250877D02*
X1249129D01*
G01X1254819D02*
X1253071D01*
G01X1258751D02*
X1257003D01*
G01X1262693D02*
X1260945D01*
G01X1260964Y594433D02*
X1262674D01*
G01X1257022D02*
X1258732D01*
G01X1253090D02*
X1254800D01*
G01X1249148D02*
X1250858D01*
G01X1245216D02*
X1246926D01*
G01X1241274D02*
X1242984D01*
G01X1242977Y594365D02*
X1241281D01*
G01X1246919D02*
X1245223D01*
G01X1250851D02*
X1249155D01*
G01X1254793D02*
X1253097D01*
G01X1258725D02*
X1257029D01*
G01X1262667D02*
X1260971D01*
G01X1242924Y594341D02*
X1241334D01*
G01X1246866D02*
X1245276D01*
G01X1250798D02*
X1249208D01*
G01X1254740D02*
X1253150D01*
G01X1258672D02*
X1257082D01*
G01X1262614D02*
X1261024D01*
G01X1260949Y594139D02*
X1262688D01*
G01X1257008D02*
X1258747D01*
G01X1253075D02*
X1254814D01*
G01X1249134D02*
X1250873D01*
G01X1245201D02*
X1246940D01*
G01X1241260D02*
X1242999D01*
G01X1260717Y593488D02*
X1262921D01*
G01X1256780D02*
X1258984D01*
G01X1252843D02*
X1255047D01*
G01X1248906D02*
X1251110D01*
G01X1244968D02*
X1247173D01*
G01X1241031D02*
X1243236D01*
G01X1261021Y593379D02*
X1262616D01*
G01X1257080D02*
X1258675D01*
G01X1253147D02*
X1254742D01*
G01X1249206D02*
X1250801D01*
G01X1245273D02*
X1246868D01*
G01X1241332D02*
X1242927D01*
G01X1242803Y592760D02*
X1241465D01*
G01X1250677D02*
X1249339D01*
G01X1258551D02*
X1257213D01*
G01X1242803Y591776D02*
X1241465D01*
G01X1250677D02*
X1249339D01*
G01X1258551D02*
X1257213D01*
G01X1257055Y591677D02*
X1258709D01*
G01X1249181D02*
X1250835D01*
G01X1241307D02*
X1242961D01*
G01Y591185D02*
X1241307D01*
G01X1250835D02*
X1249181D01*
G01X1258709D02*
X1257055D01*
G01X1242890Y590571D02*
X1241368D01*
G01X1246832D02*
X1245310D01*
G01X1250764D02*
X1249242D01*
G01X1254706D02*
X1253184D01*
G01X1258638D02*
X1257117D01*
G01X1262580D02*
X1261058D01*
G01X1242901Y590552D02*
X1241358D01*
G01X1246843D02*
X1245299D01*
G01X1250775D02*
X1249232D01*
G01X1254717D02*
X1253173D01*
G01X1258649D02*
X1257106D01*
G01X1262591D02*
X1261047D01*
G01X1241031Y590516D02*
X1240717D01*
G01X1243551D02*
X1243236D01*
G01X1244968D02*
X1244654D01*
G01X1247488D02*
X1247173D01*
G01X1248906D02*
X1248591D01*
G01X1251425D02*
X1251110D01*
G01X1252843D02*
X1252528D01*
G01X1256780D02*
X1256465D01*
G01X1255362D02*
X1255047D01*
G01X1259299D02*
X1258984D01*
G01X1260717D02*
X1260402D01*
G01X1243315Y589984D02*
X1240953D01*
G01X1247252D02*
X1244890D01*
G01X1251189D02*
X1248827D01*
G01X1255126D02*
X1252764D01*
G01X1259063D02*
X1256701D01*
G01X1263000D02*
X1260638D01*
G01X1242657Y589937D02*
X1241601D01*
G01X1246599D02*
X1245543D01*
G01X1250531D02*
X1249475D01*
G01X1254473D02*
X1253417D01*
G01X1258406D02*
X1257349D01*
G01X1262347D02*
X1261291D01*
G01X1261071Y589615D02*
X1262567D01*
G01X1257129D02*
X1258625D01*
G01X1253197D02*
X1254693D01*
G01X1249255D02*
X1250751D01*
G01X1245323D02*
X1246819D01*
G01X1241381D02*
X1242877D01*
G01X1261069Y589606D02*
X1262569D01*
G01X1257127D02*
X1258627D01*
G01X1253195D02*
X1254695D01*
G01X1249253D02*
X1250753D01*
G01X1245321D02*
X1246821D01*
G01X1241379D02*
X1242879D01*
G01X1242961Y589413D02*
X1241307D01*
G01X1250835D02*
X1249181D01*
G01X1258709D02*
X1257055D01*
G01X1260808Y589117D02*
X1262829D01*
G01X1256867D02*
X1258888D01*
G01X1252934D02*
X1254955D01*
G01X1248993D02*
X1251014D01*
G01X1245060D02*
X1247081D01*
G01X1241119D02*
X1243140D01*
G01X1258984Y589020D02*
X1259299D01*
G01X1255047D02*
X1255362D01*
G01X1251110D02*
X1251425D01*
G01X1247173D02*
X1247488D01*
G01X1243236D02*
X1243551D01*
G01X1241031D02*
X1240717D01*
G01X1244968D02*
X1244654D01*
G01X1248906D02*
X1248591D01*
G01X1252843D02*
X1252528D01*
G01X1256780D02*
X1256465D01*
G01X1260717D02*
X1260402D01*
G01X1261336Y589010D02*
X1262302D01*
G01X1257395D02*
X1258360D01*
G01X1253462D02*
X1254428D01*
G01X1249521D02*
X1250486D01*
G01X1245588D02*
X1246554D01*
G01X1241647D02*
X1242612D01*
G01X1257055Y588921D02*
X1258709D01*
G01X1249181D02*
X1250835D01*
G01X1241307D02*
X1242961D01*
G01X1260402Y588823D02*
X1263236D01*
G01X1256465D02*
X1259299D01*
G01X1252528D02*
X1255362D01*
G01X1248591D02*
X1251425D01*
G01X1244654D02*
X1247488D01*
G01X1240717D02*
X1243551D01*
G01X1260402Y588665D02*
X1260992D01*
G01X1258709D02*
X1259299D01*
G01X1256465D02*
X1257055D01*
G01X1254772D02*
X1255362D01*
G01X1252528D02*
X1253118D01*
G01X1250835D02*
X1251425D01*
G01X1248591D02*
X1249181D01*
G01X1246898D02*
X1247488D01*
G01X1244654D02*
X1245244D01*
G01X1242961D02*
X1243551D01*
G01X1240717D02*
X1241307D01*
G01X1242866Y588640D02*
X1241393D01*
G01X1246807D02*
X1245334D01*
G01X1250740D02*
X1249267D01*
G01X1254681D02*
X1253208D01*
G01X1258614D02*
X1257141D01*
G01X1262555D02*
X1261082D01*
G01X1261069Y588621D02*
X1262569D01*
G01X1257127D02*
X1258627D01*
G01X1253195D02*
X1254695D01*
G01X1249253D02*
X1250753D01*
G01X1245321D02*
X1246821D01*
G01X1241379D02*
X1242879D01*
G01X1243135Y588231D02*
X1241124D01*
G01X1247076D02*
X1245065D01*
G01X1251009D02*
X1248998D01*
G01X1254951D02*
X1252939D01*
G01X1258883D02*
X1256872D01*
G01X1262825D02*
X1260813D01*
G01X1241307Y587996D02*
X1240717D01*
G01X1243551D02*
X1242961D01*
G01X1245244D02*
X1244654D01*
G01X1247488D02*
X1246898D01*
G01X1249181D02*
X1248591D01*
G01X1251425D02*
X1250835D01*
G01X1253118D02*
X1252528D01*
G01X1255362D02*
X1254772D01*
G01X1257055D02*
X1256465D01*
G01X1259299D02*
X1258709D01*
G01X1260992D02*
X1260402D01*
G01X1243551Y587839D02*
X1240717D01*
G01X1247488D02*
X1244654D01*
G01X1251425D02*
X1248591D01*
G01X1255362D02*
X1252528D01*
G01X1259299D02*
X1256465D01*
G01X1263236D02*
X1260402D01*
G01X1246898Y587740D02*
X1245244D01*
G01X1254772D02*
X1253118D01*
G01X1262646D02*
X1260992D01*
G01Y587248D02*
X1262646D01*
G01X1253118D02*
X1254772D01*
G01X1245244D02*
X1246898D01*
G01X1260402Y586343D02*
X1263236D01*
G01X1256465D02*
X1259299D01*
G01X1252528D02*
X1255362D01*
G01X1248591D02*
X1251425D01*
G01X1244654D02*
X1247488D01*
G01X1240717D02*
X1243551D01*
G01X1260992Y585476D02*
X1262646D01*
G01X1253118D02*
X1254772D01*
G01X1245244D02*
X1246898D01*
G01X1243315Y585083D02*
X1240953D01*
G01X1247252D02*
X1244890D01*
G01X1251189D02*
X1248827D01*
G01X1255126D02*
X1252764D01*
G01X1259063D02*
X1256701D01*
G01X1263000D02*
X1260638D01*
G01X1246898Y584984D02*
X1245244D01*
G01X1254772D02*
X1253118D01*
G01X1262646D02*
X1260992D01*
G01X1246740Y584886D02*
X1245402D01*
G01X1254614D02*
X1253276D01*
G01X1262488D02*
X1261150D01*
G01X1260638Y583902D02*
X1263000D01*
G01X1256701D02*
X1259063D01*
G01X1252764D02*
X1255126D01*
G01X1248827D02*
X1251189D01*
G01X1244890D02*
X1247252D01*
G01X1240953D02*
X1243315D01*
G01X1261082Y605738D02*
X1261336Y605368D01*
G01X1261291Y604441D02*
X1261069Y604763D01*
G01X1257150Y605738D02*
X1257404Y605368D01*
G01X1257358Y604441D02*
X1257137Y604763D01*
G01X1253208Y605738D02*
X1253462Y605368D01*
G01X1253417Y604441D02*
X1253195Y604763D01*
G01X1249276Y605738D02*
X1249530Y605368D01*
G01X1249484Y604441D02*
X1249263Y604763D01*
G01X1258406Y589937D02*
X1258627Y589615D01*
G01X1258614Y588640D02*
X1258360Y589010D01*
G01X1245334Y605738D02*
X1245588Y605368D01*
G01X1245543Y604441D02*
X1245321Y604763D01*
G01X1254473Y589937D02*
X1254695Y589615D01*
G01X1254681Y588640D02*
X1254428Y589010D01*
G01X1241402Y605738D02*
X1241656Y605368D01*
G01X1241610Y604441D02*
X1241389Y604763D01*
G01X1250531Y589937D02*
X1250753Y589615D01*
G01X1250740Y588640D02*
X1250486Y589010D01*
G01X1246599Y589937D02*
X1246820Y589615D01*
G01X1246807Y588640D02*
X1246554Y589010D01*
G01X1242657Y589937D02*
X1242879Y589615D01*
G01X1242866Y588640D02*
X1242612Y589010D01*
G01X1261291Y604441D02*
X1261300Y604394D01*
G01X1257358Y604441D02*
X1257368Y604394D01*
G01X1258406Y589937D02*
X1258396Y589984D01*
G01X1253417Y604441D02*
X1253426Y604394D01*
G01X1254473Y589937D02*
X1254464Y589984D01*
G01X1249484Y604441D02*
X1249494Y604394D01*
G01X1250531Y589937D02*
X1250522Y589984D01*
G01X1245543Y604441D02*
X1245552Y604394D01*
G01X1246599Y589937D02*
X1246590Y589984D01*
G01X1241610Y604441D02*
X1241620Y604394D01*
G01X1242657Y589937D02*
X1242648Y589984D01*
G01X1261425Y609492D02*
Y610476D01*
G01Y584886D02*
Y583902D01*
G01X1261150Y584965D02*
Y583902D01*
G01Y610476D02*
Y609413D01*
G01X1261071Y589618D02*
Y588627D01*
G01Y605751D02*
Y604760D01*
G01X1260992Y605555D02*
Y610396D01*
G01Y583982D02*
Y588823D01*
G01X1260795Y587840D02*
Y588825D01*
G01Y605553D02*
Y606538D01*
G01X1260717Y606539D02*
Y587839D01*
G01X1260638Y589984D02*
Y583902D01*
G01Y610476D02*
Y604394D01*
G01X1260441Y588823D02*
Y587839D01*
G01Y606539D02*
Y605555D01*
G01X1260436Y606539D02*
Y605555D01*
G01X1260402Y590516D02*
Y586343D01*
G01Y608035D02*
Y603862D01*
G01X1261336Y589010D02*
X1261323Y589984D01*
G01X1258369Y605368D02*
X1258382Y604394D01*
G01X1260949Y600239D02*
X1260813Y606147D01*
G01X1260808Y605261D02*
X1260945Y599353D01*
G01X1258888Y589117D02*
X1258751Y595025D01*
G01X1258747Y594139D02*
X1258883Y588231D01*
G01X1257017Y600239D02*
X1256881Y606147D01*
G01X1256876Y605261D02*
X1257012Y599353D01*
G01X1261024Y594341D02*
X1260973Y595327D01*
G01X1260971Y594365D02*
X1261021Y593379D01*
G01X1258735Y600013D02*
X1258684Y600999D01*
G01X1258682Y600037D02*
X1258732Y599051D01*
G01X1257082Y594341D02*
X1257031Y595327D01*
G01X1257029Y594365D02*
X1257080Y593379D01*
G01X1254793Y600013D02*
X1254742Y600999D01*
G01X1254740Y600037D02*
X1254791Y599051D01*
G01X1253150Y594341D02*
X1253099Y595327D01*
G01X1253097Y594365D02*
X1253147Y593379D01*
G01X1261300Y589984D02*
X1261291Y589937D01*
G01X1260973Y599051D02*
X1261024Y600037D01*
G01X1261021Y600999D02*
X1260971Y600013D01*
G01X1258675Y593379D02*
X1258725Y594365D01*
G01X1258723Y595327D02*
X1258672Y594341D01*
G01X1257041Y599051D02*
X1257091Y600037D01*
G01X1257089Y600999D02*
X1257038Y600013D01*
G01X1254742Y593379D02*
X1254793Y594365D01*
G01X1254791Y595327D02*
X1254740Y594341D01*
G01X1253099Y599051D02*
X1253150Y600037D01*
G01X1253147Y600999D02*
X1253097Y600013D01*
G01X1250801Y593379D02*
X1250851Y594365D01*
G01X1250849Y595327D02*
X1250798Y594341D01*
G01X1249167Y599051D02*
X1249217Y600037D01*
G01X1249215Y600999D02*
X1249164Y600013D01*
G01X1246868Y593379D02*
X1246919Y594365D01*
G01X1246917Y595327D02*
X1246866Y594341D01*
G01X1245225Y599051D02*
X1245276Y600037D01*
G01X1245273Y600999D02*
X1245223Y600013D01*
G01X1242927Y593379D02*
X1242977Y594365D01*
G01X1242975Y595327D02*
X1242924Y594341D01*
G01X1260813Y588231D02*
X1260949Y594139D01*
G01X1260945Y595025D02*
X1260808Y589117D01*
G01X1258761Y599353D02*
X1258897Y605261D01*
G01X1258892Y606147D02*
X1258756Y600239D01*
G01X1256872Y588231D02*
X1257008Y594139D01*
G01X1257003Y595025D02*
X1256867Y589117D01*
G01X1254819Y599353D02*
X1254955Y605261D01*
G01X1254951Y606147D02*
X1254814Y600239D01*
G01X1252939Y588231D02*
X1253075Y594139D01*
G01X1253071Y595025D02*
X1252934Y589117D01*
G01X1250887Y599353D02*
X1251023Y605261D01*
G01X1251018Y606147D02*
X1250882Y600239D01*
G01X1248998Y588231D02*
X1249134Y594139D01*
G01X1249129Y595025D02*
X1248993Y589117D01*
G01X1246945Y599353D02*
X1247081Y605261D01*
G01X1247076Y606147D02*
X1246940Y600239D01*
G01X1245065Y588231D02*
X1245201Y594139D01*
G01X1245197Y595025D02*
X1245060Y589117D01*
G01X1243013Y599353D02*
X1243149Y605261D01*
G01X1243144Y606147D02*
X1243008Y600239D01*
G01X1241124Y588231D02*
X1241260Y594139D01*
G01X1241255Y595025D02*
X1241119Y589117D01*
G01X1261323Y604394D02*
X1261336Y605368D01*
G01X1258373Y589984D02*
X1258360Y589010D01*
G01X1257391Y604394D02*
X1257404Y605368D01*
G01X1254441Y589984D02*
X1254428Y589010D01*
G01X1253449Y604394D02*
X1253462Y605368D01*
G01X1250499Y589984D02*
X1250486Y589010D01*
G01X1249517Y604394D02*
X1249530Y605368D01*
G01X1246567Y589984D02*
X1246554Y589010D01*
G01X1245575Y604394D02*
X1245588Y605368D01*
G01X1242625Y589984D02*
X1242612Y589010D01*
G01X1241643Y604394D02*
X1241656Y605368D01*
G01X1259299Y603862D02*
Y608035D01*
G01Y586343D02*
Y590516D01*
G01X1259265Y606539D02*
Y605555D01*
G01X1259260Y588823D02*
Y587839D01*
G01X1259255Y588823D02*
Y587839D01*
G01X1259063Y589984D02*
Y583902D01*
G01Y610476D02*
Y604394D01*
G01X1258984Y587839D02*
Y606539D01*
G01X1258910Y606538D02*
Y605553D01*
G01X1258901Y588825D02*
Y587840D01*
G01X1258709Y601698D02*
Y606539D01*
G01Y587839D02*
Y592680D01*
G01X1258635Y604760D02*
Y605751D01*
G01X1258625Y588627D02*
Y589618D01*
G01X1258551Y592760D02*
Y591696D01*
G01Y602681D02*
Y601618D01*
G01X1258276Y592760D02*
Y591776D01*
G01Y602602D02*
Y601618D01*
G01X1257488Y592760D02*
Y591776D01*
G01Y602602D02*
Y601618D01*
G01X1257213Y592760D02*
Y591696D01*
G01Y602682D02*
Y601618D01*
G01X1257139Y605751D02*
Y604760D01*
G01X1257129Y589618D02*
Y588627D01*
G01X1257055Y601698D02*
Y606539D01*
G01Y587839D02*
Y592680D01*
G01X1256863Y605553D02*
Y606538D01*
G01X1256854Y587840D02*
Y588825D01*
G01X1256780Y606539D02*
Y587839D01*
G01X1256701Y589984D02*
Y583902D01*
G01Y610476D02*
Y604394D01*
G01X1256509Y606539D02*
Y605555D01*
G01X1256504Y606539D02*
Y605555D01*
G01X1256499Y588823D02*
Y587839D01*
G01X1256465Y590516D02*
Y586343D01*
G01Y608035D02*
Y603862D01*
G01X1255362D02*
Y608035D01*
G01Y586343D02*
Y590516D01*
G01X1255328Y588823D02*
Y587839D01*
G01X1255323Y588823D02*
Y587839D01*
G01Y606539D02*
Y605555D01*
G01X1255126Y589984D02*
Y583902D01*
G01Y610476D02*
Y604394D01*
G01X1255047Y587839D02*
Y606539D01*
G01X1254968Y588825D02*
Y587840D01*
G01Y606538D02*
Y605553D01*
G01X1254772Y605555D02*
Y610396D01*
G01Y583982D02*
Y588823D01*
G01X1254693Y604760D02*
Y605751D01*
G01Y588627D02*
Y589618D01*
G01X1254614Y584965D02*
Y583902D01*
G01Y610476D02*
Y609413D01*
G01X1254339Y584886D02*
Y583902D01*
G01Y610476D02*
Y609492D01*
G01X1253551D02*
Y610476D01*
G01Y584886D02*
Y583902D01*
G01X1253276Y584965D02*
Y583902D01*
G01Y610476D02*
Y609413D01*
G01X1253197Y589618D02*
Y588627D01*
G01Y605751D02*
Y604760D01*
G01X1253118Y605555D02*
Y610396D01*
G01Y583982D02*
Y588823D01*
G01X1252921Y605553D02*
Y606538D01*
G01Y587840D02*
Y588825D01*
G01X1252843Y606539D02*
Y587839D01*
G01X1252764Y589984D02*
Y583902D01*
G01Y610476D02*
Y604394D01*
G01X1252567Y588823D02*
Y587839D01*
G01Y606539D02*
Y605555D01*
G01X1252562Y606539D02*
Y605555D01*
G01X1252528Y590516D02*
Y586343D01*
G01Y608035D02*
Y603862D01*
G01X1251425D02*
Y608035D01*
G01Y586343D02*
Y590516D01*
G01X1251390Y606539D02*
Y605555D01*
G01X1251386Y588823D02*
Y587839D01*
G01X1251381Y588823D02*
Y587839D01*
G01X1251189Y589984D02*
Y583902D01*
G01Y610476D02*
Y604394D01*
G01X1251110Y587839D02*
Y606539D01*
G01X1251036Y606538D02*
Y605553D01*
G01X1251027Y588825D02*
Y587840D01*
G01X1250835Y601698D02*
Y606539D01*
G01Y587839D02*
Y592680D01*
G01X1250761Y604760D02*
Y605751D01*
G01X1250751Y588627D02*
Y589618D01*
G01X1250677Y592760D02*
Y591696D01*
G01Y602681D02*
Y601618D01*
G01X1250402D02*
Y602602D01*
G01Y592760D02*
Y591776D01*
G01X1249614Y601618D02*
Y602602D01*
G01Y591776D02*
Y592760D01*
G01X1249339D02*
Y591696D01*
G01Y602682D02*
Y601618D01*
G01X1249265Y605751D02*
Y604760D01*
G01X1249255Y589618D02*
Y588627D01*
G01X1249181Y601698D02*
Y606539D01*
G01Y587839D02*
Y592680D01*
G01X1248989Y605553D02*
Y606538D01*
G01X1248980Y587840D02*
Y588825D01*
G01X1248906Y606539D02*
Y587839D01*
G01X1248827Y589984D02*
Y583902D01*
G01Y610476D02*
Y604394D01*
G01X1248635Y606539D02*
Y605555D01*
G01X1248630Y606539D02*
Y605555D01*
G01X1248625Y588823D02*
Y587839D01*
G01X1248591Y590516D02*
Y586343D01*
G01Y608035D02*
Y603862D01*
G01X1247488D02*
Y608035D01*
G01Y586343D02*
Y590516D01*
G01X1247453Y588823D02*
Y587839D01*
G01X1247449Y588823D02*
Y587839D01*
G01Y606539D02*
Y605555D01*
G01X1247252Y589984D02*
Y583902D01*
G01Y610476D02*
Y604394D01*
G01X1247173Y587839D02*
Y606539D01*
G01X1247094Y588825D02*
Y587840D01*
G01Y606538D02*
Y605553D01*
G01X1246898Y605555D02*
Y610396D01*
G01Y583982D02*
Y588823D01*
G01X1246819Y604760D02*
Y605751D01*
G01Y588627D02*
Y589618D01*
G01X1246740Y584965D02*
Y583902D01*
G01Y610476D02*
Y609413D01*
G01X1246465Y584886D02*
Y583902D01*
G01Y610476D02*
Y609492D01*
G01X1245677D02*
Y610476D01*
G01Y584886D02*
Y583902D01*
G01X1245402Y584965D02*
Y583902D01*
G01Y610476D02*
Y609413D01*
G01X1245323Y589618D02*
Y588627D01*
G01Y605751D02*
Y604760D01*
G01X1245244Y605555D02*
Y610396D01*
G01Y583982D02*
Y588823D01*
G01X1245047Y605553D02*
Y606538D01*
G01Y587840D02*
Y588825D01*
G01X1244968Y606539D02*
Y587839D01*
G01X1244890Y589984D02*
Y583902D01*
G01Y610476D02*
Y604394D01*
G01X1244693Y588823D02*
Y587839D01*
G01Y606539D02*
Y605555D01*
G01X1244688Y606539D02*
Y605555D01*
G01X1244654Y590516D02*
Y586343D01*
G01Y608035D02*
Y603862D01*
G01X1243551D02*
Y608035D01*
G01Y586343D02*
Y590516D01*
G01X1243516Y606539D02*
Y605555D01*
G01X1243512Y588823D02*
Y587839D01*
G01X1243507Y588823D02*
Y587839D01*
G01X1243315Y589984D02*
Y583902D01*
G01Y610476D02*
Y604394D01*
G01X1243236Y587839D02*
Y606539D01*
G01X1243162Y606538D02*
Y605553D01*
G01X1243153Y588825D02*
Y587840D01*
G01X1242961Y601698D02*
Y606539D01*
G01Y587839D02*
Y592680D01*
G01X1242887Y604760D02*
Y605751D01*
G01X1242877Y588627D02*
Y589618D01*
G01X1242803Y592760D02*
Y591696D01*
G01Y602681D02*
Y601618D01*
G01X1242528D02*
Y602602D01*
G01Y592760D02*
Y591776D01*
G01X1241740Y601618D02*
Y602602D01*
G01Y591776D02*
Y592760D01*
G01X1241465D02*
Y591696D01*
G01Y602682D02*
Y601618D01*
G01X1241390Y605751D02*
Y604760D01*
G01X1241381Y589618D02*
Y588627D01*
G01X1241307Y601698D02*
Y606539D01*
G01Y587839D02*
Y592680D01*
G01X1241115Y605553D02*
Y606538D01*
G01X1241106Y587840D02*
Y588825D01*
G01X1241031Y606539D02*
Y587839D01*
G01X1240953Y589984D02*
Y583902D01*
G01Y610476D02*
Y604394D01*
G01X1240761Y606539D02*
Y605555D01*
G01X1240756Y606539D02*
Y605555D01*
G01X1240751Y588823D02*
Y587839D01*
G01X1240717Y590516D02*
Y586343D01*
G01Y608035D02*
Y603862D01*
G01X1257395Y589010D02*
X1257381Y589984D01*
G01X1254428Y605368D02*
X1254441Y604394D01*
G01X1253462Y589010D02*
X1253449Y589984D01*
G01X1250495Y605368D02*
X1250508Y604394D01*
G01X1249521Y589010D02*
X1249507Y589984D01*
G01X1246554Y605368D02*
X1246567Y604394D01*
G01X1245588Y589010D02*
X1245575Y589984D01*
G01X1242621Y605368D02*
X1242634Y604394D01*
G01X1241647Y589010D02*
X1241633Y589984D01*
G01X1254955Y589117D02*
X1254819Y595025D01*
G01X1254814Y594139D02*
X1254951Y588231D01*
G01X1253075Y600239D02*
X1252939Y606147D01*
G01X1252934Y605261D02*
X1253071Y599353D01*
G01X1251014Y589117D02*
X1250877Y595025D01*
G01X1250873Y594139D02*
X1251009Y588231D01*
G01X1249143Y600239D02*
X1249007Y606147D01*
G01X1249002Y605261D02*
X1249138Y599353D01*
G01X1247081Y589117D02*
X1246945Y595025D01*
G01X1246940Y594139D02*
X1247076Y588231D01*
G01X1245201Y600239D02*
X1245065Y606147D01*
G01X1245060Y605261D02*
X1245197Y599353D01*
G01X1243140Y589117D02*
X1243003Y595025D01*
G01X1242999Y594139D02*
X1243135Y588231D01*
G01X1241269Y600239D02*
X1241133Y606147D01*
G01X1241128Y605261D02*
X1241264Y599353D01*
G01X1250861Y600013D02*
X1250810Y600999D01*
G01X1250808Y600037D02*
X1250858Y599051D01*
G01X1249208Y594341D02*
X1249157Y595327D01*
G01X1249155Y594365D02*
X1249206Y593379D01*
G01X1246919Y600013D02*
X1246868Y600999D01*
G01X1246866Y600037D02*
X1246917Y599051D01*
G01X1245276Y594341D02*
X1245225Y595327D01*
G01X1245223Y594365D02*
X1245273Y593379D01*
G01X1242987Y600013D02*
X1242936Y600999D01*
G01X1242934Y600037D02*
X1242984Y599051D01*
G01X1241334Y594341D02*
X1241283Y595327D01*
G01X1241281Y594365D02*
X1241332Y593379D01*
G01X1257359Y589984D02*
X1257349Y589937D01*
G01X1258405Y604394D02*
X1258415Y604441D01*
G01X1253426Y589984D02*
X1253417Y589937D01*
G01X1254464Y604394D02*
X1254473Y604441D01*
G01X1249484Y589984D02*
X1249475Y589937D01*
G01X1250531Y604394D02*
X1250541Y604441D01*
G01X1245552Y589984D02*
X1245543Y589937D01*
G01X1246590Y604394D02*
X1246599Y604441D01*
G01X1241610Y589984D02*
X1241601Y589937D01*
G01X1242657Y604394D02*
X1242667Y604441D01*
G01X1241293Y599051D02*
X1241343Y600037D01*
G01X1241341Y600999D02*
X1241290Y600013D01*
G01X1261082Y588640D02*
X1261336Y589010D01*
G01X1261069Y589615D02*
X1261291Y589937D01*
G01X1257141Y588640D02*
X1257395Y589010D01*
G01X1257128Y589615D02*
X1257349Y589937D01*
G01X1253208Y588640D02*
X1253462Y589010D01*
G01X1253195Y589615D02*
X1253417Y589937D01*
G01X1249267Y588640D02*
X1249521Y589010D01*
G01X1249254Y589615D02*
X1249475Y589937D01*
G01X1258636Y604763D02*
X1258415Y604441D01*
G01X1258623Y605738D02*
X1258369Y605368D01*
G01X1245334Y588640D02*
X1245588Y589010D01*
G01X1245321Y589615D02*
X1245543Y589937D01*
G01X1254695Y604763D02*
X1254473Y604441D01*
G01X1254681Y605738D02*
X1254428Y605368D01*
G01X1241393Y588640D02*
X1241647Y589010D01*
G01X1241380Y589615D02*
X1241601Y589937D01*
G01X1250762Y604763D02*
X1250541Y604441D01*
G01X1250749Y605738D02*
X1250495Y605368D01*
G01X1246820Y604763D02*
X1246599Y604441D01*
G01X1246807Y605738D02*
X1246554Y605368D01*
G01X1242888Y604763D02*
X1242667Y604441D01*
G01X1242875Y605738D02*
X1242621Y605368D01*
G01X1262567Y605754D02*
Y605751D01*
G01X1262568Y605756D02*
X1262567Y605754D01*
G01X1262569Y605757D02*
X1262568Y605756D01*
G01X1270442Y605754D02*
X1270441Y605751D01*
G01X1270442Y605756D02*
Y605754D01*
G01X1270443Y605757D02*
X1270442Y605756D01*
G01X1262568Y604768D02*
X1262567Y604763D01*
G01X1262568Y604771D02*
Y604768D01*
G01X1262569Y604772D02*
X1262568Y604771D01*
G01X1270442Y604768D02*
X1270441Y604763D01*
G01X1270442Y604771D02*
Y604768D01*
G01X1270443Y604772D02*
X1270442Y604771D01*
G01X1278316Y605754D02*
X1278315Y605751D01*
G01X1278316Y605756D02*
Y605754D01*
G01X1278317Y605757D02*
X1278316Y605756D01*
G01X1268944Y588624D02*
X1268945Y588627D01*
G01X1268944Y588622D02*
Y588624D01*
G01X1268943Y588621D02*
X1268944Y588622D01*
G01X1286190Y605754D02*
X1286189Y605751D01*
G01X1286190Y605756D02*
Y605754D01*
G01X1286191Y605757D02*
X1286190Y605756D01*
G01X1276818Y588624D02*
X1276819Y588627D01*
G01X1276818Y588622D02*
Y588624D01*
G01X1276817Y588621D02*
X1276818Y588622D01*
G01X1294064Y605754D02*
X1294063Y605751D01*
G01X1294064Y605756D02*
Y605754D01*
G01X1294065Y605757D02*
X1294064Y605756D01*
G01X1284692Y588624D02*
X1284693Y588627D01*
G01X1284692Y588622D02*
Y588624D01*
G01X1284691Y588621D02*
X1284692Y588622D01*
G01X1301938Y605754D02*
X1301937Y605751D01*
G01X1301938Y605756D02*
Y605754D01*
G01X1301939Y605757D02*
X1301938Y605756D01*
G01X1268944Y589610D02*
X1268945Y589615D01*
G01X1268944Y589607D02*
Y589610D01*
G01X1268943Y589606D02*
X1268944Y589607D01*
G01X1278316Y604768D02*
X1278315Y604763D01*
G01X1278316Y604771D02*
Y604768D01*
G01X1278317Y604772D02*
X1278316Y604771D01*
G01X1276818Y589610D02*
X1276819Y589615D01*
G01X1276818Y589607D02*
Y589610D01*
G01X1276817Y589606D02*
X1276818Y589607D01*
G01X1286190Y604768D02*
X1286189Y604763D01*
G01X1286190Y604771D02*
Y604768D01*
G01X1286191Y604772D02*
X1286190Y604771D01*
G01X1284692Y589610D02*
X1284693Y589615D01*
G01X1284692Y589607D02*
Y589610D01*
G01X1284691Y589606D02*
X1284692Y589607D01*
G01X1294064Y604768D02*
X1294063Y604763D01*
G01X1294064Y604771D02*
Y604768D01*
G01X1294065Y604772D02*
X1294064Y604771D01*
G01X1292566Y588624D02*
X1292567Y588627D01*
G01X1292566Y588622D02*
Y588624D01*
G01X1292565Y588621D02*
X1292566Y588622D01*
G01X1300440Y588624D02*
X1300441Y588627D01*
G01X1300440Y588622D02*
Y588624D01*
G01X1300439Y588621D02*
X1300440Y588622D01*
G01X1262589Y589804D02*
X1262591Y590552D01*
G01X1262584Y589184D02*
X1262589Y589804D01*
G01X1262577Y588770D02*
X1262584Y589184D01*
G01X1262569Y588621D02*
X1262577Y588770D01*
G01X1262579Y590200D02*
X1262580Y590571D01*
G01X1262576Y589887D02*
X1262579Y590200D01*
G01X1262573Y589679D02*
X1262576Y589887D01*
G01X1262569Y589606D02*
X1262573Y589679D01*
G01X1262834Y605413D02*
X1262829Y605261D01*
G01X1262838Y605511D02*
X1262834Y605413D01*
G01X1262843Y605553D02*
X1262838Y605511D01*
G01X1264737Y588965D02*
X1264741Y589117D01*
G01X1264732Y588867D02*
X1264737Y588965D01*
G01X1264728Y588825D02*
X1264732Y588867D01*
G01X1266775Y605413D02*
X1266771Y605261D01*
G01X1266780Y605511D02*
X1266775Y605413D01*
G01X1266784Y605553D02*
X1266780Y605511D01*
G01X1268678Y588965D02*
X1268682Y589117D01*
G01X1268674Y588867D02*
X1268678Y588965D01*
G01X1268669Y588825D02*
X1268674Y588867D01*
G01X1270708Y605413D02*
X1270703Y605261D01*
G01X1270712Y605511D02*
X1270708Y605413D01*
G01X1270717Y605553D02*
X1270712Y605511D01*
G01X1272611Y588965D02*
X1272615Y589117D01*
G01X1272606Y588867D02*
X1272611Y588965D01*
G01X1272602Y588825D02*
X1272606Y588867D01*
G01X1274649Y605413D02*
X1274645Y605261D01*
G01X1274654Y605511D02*
X1274649Y605413D01*
G01X1274658Y605553D02*
X1274654Y605511D01*
G01X1262830Y606353D02*
X1262825Y606147D01*
G01X1262836Y606485D02*
X1262830Y606353D01*
G01X1262843Y606538D02*
X1262836Y606485D01*
G01X1266772Y606353D02*
X1266766Y606147D01*
G01X1266778Y606485D02*
X1266772Y606353D01*
G01X1266784Y606538D02*
X1266778Y606485D01*
G01X1264740Y588025D02*
X1264746Y588231D01*
G01X1264734Y587893D02*
X1264740Y588025D01*
G01X1264728Y587840D02*
X1264734Y587893D01*
G01X1270704Y606353D02*
X1270699Y606147D01*
G01X1270710Y606485D02*
X1270704Y606353D01*
G01X1270717Y606538D02*
X1270710Y606485D01*
G01X1268682Y588025D02*
X1268687Y588231D01*
G01X1268675Y587893D02*
X1268682Y588025D01*
G01X1268669Y587840D02*
X1268675Y587893D01*
G01X1274646Y606353D02*
X1274640Y606147D01*
G01X1274652Y606485D02*
X1274646Y606353D01*
G01X1274658Y606538D02*
X1274652Y606485D01*
G01X1272614Y588025D02*
X1272620Y588231D01*
G01X1272608Y587893D02*
X1272614Y588025D01*
G01X1272602Y587840D02*
X1272608Y587893D01*
G01X1265001Y604209D02*
X1265000Y603807D01*
G01X1265004Y604537D02*
X1265001Y604209D01*
G01X1265008Y604733D02*
X1265004Y604537D01*
G01X1265012Y604763D02*
X1265008Y604733D01*
G01X1266511Y590169D02*
X1266512Y590571D01*
G01X1266508Y589841D02*
X1266511Y590169D01*
G01X1266504Y589645D02*
X1266508Y589841D01*
G01X1266499Y589615D02*
X1266504Y589645D01*
G01X1272875Y604209D02*
X1272874Y603807D01*
G01X1272878Y604537D02*
X1272875Y604209D01*
G01X1272882Y604733D02*
X1272878Y604537D01*
G01X1272886Y604763D02*
X1272882Y604733D01*
G01X1274385Y590169D02*
X1274386Y590571D01*
G01X1274382Y589841D02*
X1274385Y590169D01*
G01X1274378Y589645D02*
X1274382Y589841D01*
G01X1274373Y589615D02*
X1274378Y589645D01*
G01X1280749Y604209D02*
X1280748Y603807D01*
G01X1280752Y604537D02*
X1280749Y604209D01*
G01X1280756Y604733D02*
X1280752Y604537D01*
G01X1280760Y604763D02*
X1280756Y604733D01*
G01X1292566Y589610D02*
X1292567Y589615D01*
G01X1292566Y589607D02*
Y589610D01*
G01X1292565Y589606D02*
X1292566Y589607D01*
G01X1262568D02*
X1262569Y589606D01*
G01X1262568Y589610D02*
Y589607D01*
G01X1262567Y589615D02*
X1262568Y589610D01*
G01X1268944Y604771D02*
X1268943Y604772D01*
G01X1268944Y604768D02*
Y604771D01*
G01X1268945Y604763D02*
X1268944Y604768D01*
G01X1270442Y589607D02*
X1270443Y589606D01*
G01X1270442Y589610D02*
Y589607D01*
G01X1270441Y589615D02*
X1270442Y589610D01*
G01X1262836Y587893D02*
X1262843Y587840D01*
G01X1262830Y588025D02*
X1262836Y587893D01*
G01X1262825Y588231D02*
X1262830Y588025D01*
G01X1264743Y606485D02*
X1264737Y606538D01*
G01X1264749Y606353D02*
X1264743Y606485D01*
G01X1264755Y606147D02*
X1264749Y606353D01*
G01X1266769Y587893D02*
X1266775Y587840D01*
G01X1266763Y588025D02*
X1266769Y587893D01*
G01X1266757Y588231D02*
X1266763Y588025D01*
G01X1268675Y606485D02*
X1268669Y606538D01*
G01X1268682Y606353D02*
X1268675Y606485D01*
G01X1268687Y606147D02*
X1268682Y606353D01*
G01X1270710Y587893D02*
X1270717Y587840D01*
G01X1270704Y588025D02*
X1270710Y587893D01*
G01X1270699Y588231D02*
X1270704Y588025D01*
G01X1272617Y606485D02*
X1272611Y606538D01*
G01X1272623Y606353D02*
X1272617Y606485D01*
G01X1272629Y606147D02*
X1272623Y606353D01*
G01X1274643Y587893D02*
X1274649Y587840D01*
G01X1274637Y588025D02*
X1274643Y587893D01*
G01X1274631Y588231D02*
X1274637Y588025D01*
G01X1276549Y606485D02*
X1276543Y606538D01*
G01X1276556Y606353D02*
X1276549Y606485D01*
G01X1276561Y606147D02*
X1276556Y606353D01*
G01X1278584Y587893D02*
X1278591Y587840D01*
G01X1278578Y588025D02*
X1278584Y587893D01*
G01X1278573Y588231D02*
X1278578Y588025D01*
G01X1262838Y588867D02*
X1262843Y588825D01*
G01X1262834Y588965D02*
X1262838Y588867D01*
G01X1262829Y589117D02*
X1262834Y588965D01*
G01X1264741Y605511D02*
X1264737Y605553D01*
G01X1264746Y605413D02*
X1264741Y605511D01*
G01X1264750Y605261D02*
X1264746Y605413D01*
G01X1266770Y588867D02*
X1266775Y588825D01*
G01X1266766Y588965D02*
X1266770Y588867D01*
G01X1266762Y589117D02*
X1266766Y588965D01*
G01X1268674Y605511D02*
X1268669Y605553D01*
G01X1268678Y605413D02*
X1268674Y605511D01*
G01X1268682Y605261D02*
X1268678Y605413D01*
G01X1270712Y588867D02*
X1270717Y588825D01*
G01X1270708Y588965D02*
X1270712Y588867D01*
G01X1270703Y589117D02*
X1270708Y588965D01*
G01X1272616Y605511D02*
X1272611Y605553D01*
G01X1272620Y605413D02*
X1272616Y605511D01*
G01X1272624Y605261D02*
X1272620Y605413D01*
G01X1274644Y588867D02*
X1274649Y588825D01*
G01X1274640Y588965D02*
X1274644Y588867D01*
G01X1274636Y589117D02*
X1274640Y588965D01*
G01X1276548Y605511D02*
X1276543Y605553D01*
G01X1276552Y605413D02*
X1276548Y605511D01*
G01X1276557Y605261D02*
X1276552Y605413D01*
G01X1278586Y588867D02*
X1278591Y588825D01*
G01X1278582Y588965D02*
X1278586Y588867D01*
G01X1278577Y589117D02*
X1278582Y588965D01*
G01X1264998Y589645D02*
X1265003Y589615D01*
G01X1264994Y589841D02*
X1264998Y589645D01*
G01X1264992Y590169D02*
X1264994Y589841D01*
G01X1264991Y590571D02*
X1264992Y590169D01*
G01X1266513Y604733D02*
X1266509Y604763D01*
G01X1266517Y604537D02*
X1266513Y604733D01*
G01X1266520Y604209D02*
X1266517Y604537D01*
G01X1266521Y603807D02*
X1266520Y604209D01*
G01X1272872Y589645D02*
X1272877Y589615D01*
G01X1272868Y589841D02*
X1272872Y589645D01*
G01X1272866Y590169D02*
X1272868Y589841D01*
G01X1272865Y590571D02*
X1272866Y590169D01*
G01X1274387Y604733D02*
X1274383Y604763D01*
G01X1274391Y604537D02*
X1274387Y604733D01*
G01X1274394Y604209D02*
X1274391Y604537D01*
G01X1274395Y603807D02*
X1274394Y604209D01*
G01X1280746Y589645D02*
X1280751Y589615D01*
G01X1280742Y589841D02*
X1280746Y589645D01*
G01X1280740Y590169D02*
X1280742Y589841D01*
G01X1280739Y590571D02*
X1280740Y590169D01*
G01X1282261Y604733D02*
X1282257Y604763D01*
G01X1282265Y604537D02*
X1282261Y604733D01*
G01X1282268Y604209D02*
X1282265Y604537D01*
G01X1282269Y603807D02*
X1282268Y604209D01*
G01X1262573Y604699D02*
X1262569Y604772D01*
G01X1262576Y604491D02*
X1262573Y604699D01*
G01X1262579Y604178D02*
X1262576Y604491D01*
G01X1262580Y603807D02*
X1262579Y604178D01*
G01X1262577Y605608D02*
X1262569Y605757D01*
G01X1262584Y605193D02*
X1262577Y605608D01*
G01X1262589Y604573D02*
X1262584Y605193D01*
G01X1262591Y603826D02*
X1262589Y604573D01*
G01X1268935Y588770D02*
X1268943Y588621D01*
G01X1268928Y589184D02*
X1268935Y588770D01*
G01X1268923Y589804D02*
X1268928Y589184D01*
G01X1268921Y590552D02*
X1268923Y589804D01*
G01X1268939Y589679D02*
X1268943Y589606D01*
G01X1268935Y589887D02*
X1268939Y589679D01*
G01X1268933Y590200D02*
X1268935Y589887D01*
G01X1268932Y590571D02*
X1268933Y590200D01*
G01X1270447Y604699D02*
X1270443Y604772D01*
G01X1270450Y604491D02*
X1270447Y604699D01*
G01X1270453Y604178D02*
X1270450Y604491D01*
G01X1270454Y603807D02*
X1270453Y604178D01*
G01X1270451Y605608D02*
X1270443Y605757D01*
G01X1270458Y605193D02*
X1270451Y605608D01*
G01X1270463Y604573D02*
X1270458Y605193D01*
G01X1270465Y603826D02*
X1270463Y604573D01*
G01X1276809Y588770D02*
X1276817Y588621D01*
G01X1276802Y589184D02*
X1276809Y588770D01*
G01X1276797Y589804D02*
X1276802Y589184D01*
G01X1276795Y590552D02*
X1276797Y589804D01*
G01X1276813Y589679D02*
X1276817Y589606D01*
G01X1276810Y589887D02*
X1276813Y589679D01*
G01X1276807Y590200D02*
X1276810Y589887D01*
G01X1276806Y590571D02*
X1276807Y590200D01*
G01X1278321Y604699D02*
X1278317Y604772D01*
G01X1278324Y604491D02*
X1278321Y604699D01*
G01X1278327Y604178D02*
X1278324Y604491D01*
G01X1278328Y603807D02*
X1278327Y604178D01*
G01X1278325Y605608D02*
X1278317Y605757D01*
G01X1278332Y605193D02*
X1278325Y605608D01*
G01X1278337Y604573D02*
X1278332Y605193D01*
G01X1278339Y603826D02*
X1278337Y604573D01*
G01X1268923D02*
X1268921Y603826D01*
G01X1268928Y605193D02*
X1268923Y604573D01*
G01X1268935Y605608D02*
X1268928Y605193D01*
G01X1268943Y605757D02*
X1268935Y605608D01*
G01X1270463Y589804D02*
X1270465Y590552D01*
G01X1270458Y589184D02*
X1270463Y589804D01*
G01X1270451Y588770D02*
X1270458Y589184D01*
G01X1270443Y588621D02*
X1270451Y588770D01*
G01X1276797Y604573D02*
X1276795Y603826D01*
G01X1276802Y605193D02*
X1276797Y604573D01*
G01X1276809Y605608D02*
X1276802Y605193D01*
G01X1276817Y605757D02*
X1276809Y605608D01*
G01X1278337Y589804D02*
X1278339Y590552D01*
G01X1278332Y589184D02*
X1278337Y589804D01*
G01X1278325Y588770D02*
X1278332Y589184D01*
G01X1278317Y588621D02*
X1278325Y588770D01*
G01X1284671Y604573D02*
X1284669Y603826D01*
G01X1284676Y605193D02*
X1284671Y604573D01*
G01X1284683Y605608D02*
X1284676Y605193D01*
G01X1284691Y605757D02*
X1284683Y605608D01*
G01X1286211Y589804D02*
X1286213Y590552D01*
G01X1286206Y589184D02*
X1286211Y589804D01*
G01X1286199Y588770D02*
X1286206Y589184D01*
G01X1286191Y588621D02*
X1286199Y588770D01*
G01X1268933Y604178D02*
X1268932Y603807D01*
G01X1268935Y604491D02*
X1268933Y604178D01*
G01X1268939Y604699D02*
X1268935Y604491D01*
G01X1268943Y604772D02*
X1268939Y604699D01*
G01X1270453Y590200D02*
X1270454Y590571D01*
G01X1270450Y589887D02*
X1270453Y590200D01*
G01X1270447Y589679D02*
X1270450Y589887D01*
G01X1270443Y589606D02*
X1270447Y589679D01*
G01X1276807Y604178D02*
X1276806Y603807D01*
G01X1276810Y604491D02*
X1276807Y604178D01*
G01X1276813Y604699D02*
X1276810Y604491D01*
G01X1276817Y604772D02*
X1276813Y604699D01*
G01X1278327Y590200D02*
X1278328Y590571D01*
G01X1278324Y589887D02*
X1278327Y590200D01*
G01X1278321Y589679D02*
X1278324Y589887D01*
G01X1278317Y589606D02*
X1278321Y589679D01*
G01X1284681Y604178D02*
X1284680Y603807D01*
G01X1284684Y604491D02*
X1284681Y604178D01*
G01X1284687Y604699D02*
X1284684Y604491D01*
G01X1284691Y604772D02*
X1284687Y604699D01*
G01X1286201Y590200D02*
X1286202Y590571D01*
G01X1286198Y589887D02*
X1286201Y590200D01*
G01X1286195Y589679D02*
X1286198Y589887D01*
G01X1286191Y589606D02*
X1286195Y589679D01*
G01X1276552Y588965D02*
X1276557Y589117D01*
G01X1276548Y588867D02*
X1276552Y588965D01*
G01X1276543Y588825D02*
X1276548Y588867D01*
G01X1278582Y605413D02*
X1278577Y605261D01*
G01X1278586Y605511D02*
X1278582Y605413D01*
G01X1278591Y605553D02*
X1278586Y605511D01*
G01X1280485Y588965D02*
X1280489Y589117D01*
G01X1280480Y588867D02*
X1280485Y588965D01*
G01X1280476Y588825D02*
X1280480Y588867D01*
G01X1282523Y605413D02*
X1282519Y605261D01*
G01X1282528Y605511D02*
X1282523Y605413D01*
G01X1282532Y605553D02*
X1282528Y605511D01*
G01X1284426Y588965D02*
X1284431Y589117D01*
G01X1284422Y588867D02*
X1284426Y588965D01*
G01X1284417Y588825D02*
X1284422Y588867D01*
G01X1286456Y605413D02*
X1286451Y605261D01*
G01X1286460Y605511D02*
X1286456Y605413D01*
G01X1286465Y605553D02*
X1286460Y605511D01*
G01X1288359Y588965D02*
X1288363Y589117D01*
G01X1288354Y588867D02*
X1288359Y588965D01*
G01X1288350Y588825D02*
X1288354Y588867D01*
G01X1290397Y605413D02*
X1290393Y605261D01*
G01X1290402Y605511D02*
X1290397Y605413D01*
G01X1290406Y605553D02*
X1290402Y605511D01*
G01X1292300Y588965D02*
X1292305Y589117D01*
G01X1292296Y588867D02*
X1292300Y588965D01*
G01X1292291Y588825D02*
X1292296Y588867D01*
G01X1294330Y605413D02*
X1294325Y605261D01*
G01X1294334Y605511D02*
X1294330Y605413D01*
G01X1294339Y605553D02*
X1294334Y605511D01*
G01X1296233Y588965D02*
X1296237Y589117D01*
G01X1296228Y588867D02*
X1296233Y588965D01*
G01X1296224Y588825D02*
X1296228Y588867D01*
G01X1298271Y605413D02*
X1298267Y605261D01*
G01X1298276Y605511D02*
X1298271Y605413D01*
G01X1298280Y605553D02*
X1298276Y605511D01*
G01X1278578Y606353D02*
X1278573Y606147D01*
G01X1278584Y606485D02*
X1278578Y606353D01*
G01X1278591Y606538D02*
X1278584Y606485D01*
G01X1276556Y588025D02*
X1276561Y588231D01*
G01X1276549Y587893D02*
X1276556Y588025D01*
G01X1276543Y587840D02*
X1276549Y587893D01*
G01X1282520Y606353D02*
X1282514Y606147D01*
G01X1282526Y606485D02*
X1282520Y606353D01*
G01X1282532Y606538D02*
X1282526Y606485D01*
G01X1280488Y588025D02*
X1280494Y588231D01*
G01X1280482Y587893D02*
X1280488Y588025D01*
G01X1280476Y587840D02*
X1280482Y587893D01*
G01X1286452Y606353D02*
X1286447Y606147D01*
G01X1286458Y606485D02*
X1286452Y606353D01*
G01X1286465Y606538D02*
X1286458Y606485D01*
G01X1284430Y588025D02*
X1284435Y588231D01*
G01X1284424Y587893D02*
X1284430Y588025D01*
G01X1284417Y587840D02*
X1284424Y587893D01*
G01X1290394Y606353D02*
X1290388Y606147D01*
G01X1290400Y606485D02*
X1290394Y606353D01*
G01X1290406Y606538D02*
X1290400Y606485D01*
G01X1288362Y588025D02*
X1288368Y588231D01*
G01X1288356Y587893D02*
X1288362Y588025D01*
G01X1288350Y587840D02*
X1288356Y587893D01*
G01X1294326Y606353D02*
X1294321Y606147D01*
G01X1294332Y606485D02*
X1294326Y606353D01*
G01X1294339Y606538D02*
X1294332Y606485D01*
G01X1292304Y588025D02*
X1292309Y588231D01*
G01X1292298Y587893D02*
X1292304Y588025D01*
G01X1292291Y587840D02*
X1292298Y587893D01*
G01X1298268Y606353D02*
X1298262Y606147D01*
G01X1298274Y606485D02*
X1298268Y606353D01*
G01X1298280Y606538D02*
X1298274Y606485D01*
G01X1296236Y588025D02*
X1296242Y588231D01*
G01X1296230Y587893D02*
X1296236Y588025D01*
G01X1296224Y587840D02*
X1296230Y587893D01*
G01X1282259Y590169D02*
X1282260Y590571D01*
G01X1282256Y589841D02*
X1282259Y590169D01*
G01X1282252Y589645D02*
X1282256Y589841D01*
G01X1282247Y589615D02*
X1282252Y589645D01*
G01X1288623Y604209D02*
X1288622Y603807D01*
G01X1288626Y604537D02*
X1288623Y604209D01*
G01X1288630Y604733D02*
X1288626Y604537D01*
G01X1288634Y604763D02*
X1288630Y604733D01*
G01X1290133Y590169D02*
X1290134Y590571D01*
G01X1290130Y589841D02*
X1290133Y590169D01*
G01X1290126Y589645D02*
X1290130Y589841D01*
G01X1290122Y589615D02*
X1290126Y589645D01*
G01X1296497Y604209D02*
X1296496Y603807D01*
G01X1296500Y604537D02*
X1296497Y604209D01*
G01X1296504Y604733D02*
X1296500Y604537D01*
G01X1296508Y604763D02*
X1296504Y604733D01*
G01X1298007Y590169D02*
X1298008Y590571D01*
G01X1298004Y589841D02*
X1298007Y590169D01*
G01X1298000Y589645D02*
X1298004Y589841D01*
G01X1297996Y589615D02*
X1298000Y589645D01*
G01X1304371Y604209D02*
X1304370Y603807D01*
G01X1304374Y604537D02*
X1304371Y604209D01*
G01X1304378Y604733D02*
X1304374Y604537D01*
G01X1304382Y604763D02*
X1304378Y604733D01*
G01X1276818Y604771D02*
X1276817Y604772D01*
G01X1276818Y604768D02*
Y604771D01*
G01X1276819Y604763D02*
X1276818Y604768D01*
G01X1278316Y589607D02*
X1278317Y589606D01*
G01X1278316Y589610D02*
Y589607D01*
G01X1278315Y589615D02*
X1278316Y589610D01*
G01X1284692Y604771D02*
X1284691Y604772D01*
G01X1284692Y604768D02*
Y604771D01*
G01X1284693Y604763D02*
X1284692Y604768D01*
G01X1286190Y589607D02*
X1286191Y589606D01*
G01X1286190Y589610D02*
Y589607D01*
G01X1286189Y589615D02*
X1286190Y589610D01*
G01X1292566Y604771D02*
X1292565Y604772D01*
G01X1292566Y604768D02*
Y604771D01*
G01X1292567Y604763D02*
X1292566Y604768D01*
G01X1294064Y589607D02*
X1294065Y589606D01*
G01X1294064Y589610D02*
Y589607D01*
G01X1294063Y589615D02*
X1294064Y589610D01*
G01X1300429Y590197D02*
X1300428Y590571D01*
G01X1300432Y589887D02*
X1300429Y590197D01*
G01X1300435Y589680D02*
X1300432Y589887D01*
G01X1300439Y589606D02*
X1300435Y589680D01*
G01X1280491Y606485D02*
X1280485Y606538D01*
G01X1280497Y606353D02*
X1280491Y606485D01*
G01X1280503Y606147D02*
X1280497Y606353D01*
G01X1282517Y587893D02*
X1282523Y587840D01*
G01X1282511Y588025D02*
X1282517Y587893D01*
G01X1282505Y588231D02*
X1282511Y588025D01*
G01X1284424Y606485D02*
X1284417Y606538D01*
G01X1284430Y606353D02*
X1284424Y606485D01*
G01X1284435Y606147D02*
X1284430Y606353D01*
G01X1286458Y587893D02*
X1286465Y587840D01*
G01X1286452Y588025D02*
X1286458Y587893D01*
G01X1286447Y588231D02*
X1286452Y588025D01*
G01X1288365Y606485D02*
X1288359Y606538D01*
G01X1288371Y606353D02*
X1288365Y606485D01*
G01X1288377Y606147D02*
X1288371Y606353D01*
G01X1290391Y587893D02*
X1290397Y587840D01*
G01X1290385Y588025D02*
X1290391Y587893D01*
G01X1290379Y588231D02*
X1290385Y588025D01*
G01X1292298Y606485D02*
X1292291Y606538D01*
G01X1292304Y606353D02*
X1292298Y606485D01*
G01X1292309Y606147D02*
X1292304Y606353D01*
G01X1294332Y587893D02*
X1294339Y587840D01*
G01X1294326Y588025D02*
X1294332Y587893D01*
G01X1294321Y588231D02*
X1294326Y588025D01*
G01X1296239Y606485D02*
X1296233Y606538D01*
G01X1296245Y606353D02*
X1296239Y606485D01*
G01X1296251Y606147D02*
X1296245Y606353D01*
G01X1298265Y587893D02*
X1298271Y587840D01*
G01X1298259Y588025D02*
X1298265Y587893D01*
G01X1298253Y588231D02*
X1298259Y588025D01*
G01X1300172Y606485D02*
X1300165Y606538D01*
G01X1300178Y606353D02*
X1300172Y606485D01*
G01X1300183Y606147D02*
X1300178Y606353D01*
G01X1302206Y587893D02*
X1302213Y587840D01*
G01X1302200Y588025D02*
X1302206Y587893D01*
G01X1302195Y588231D02*
X1302200Y588025D01*
G01X1304113Y606485D02*
X1304107Y606538D01*
G01X1304119Y606353D02*
X1304113Y606485D01*
G01X1304125Y606147D02*
X1304119Y606353D01*
G01X1280490Y605511D02*
X1280485Y605553D01*
G01X1280494Y605413D02*
X1280490Y605511D01*
G01X1280498Y605261D02*
X1280494Y605413D01*
G01X1282518Y588867D02*
X1282523Y588825D01*
G01X1282514Y588965D02*
X1282518Y588867D01*
G01X1282510Y589117D02*
X1282514Y588965D01*
G01X1284422Y605511D02*
X1284417Y605553D01*
G01X1284426Y605413D02*
X1284422Y605511D01*
G01X1284431Y605261D02*
X1284426Y605413D01*
G01X1286460Y588867D02*
X1286465Y588825D01*
G01X1286456Y588965D02*
X1286460Y588867D01*
G01X1286451Y589117D02*
X1286456Y588965D01*
G01X1288364Y605511D02*
X1288359Y605553D01*
G01X1288368Y605413D02*
X1288364Y605511D01*
G01X1288372Y605261D02*
X1288368Y605413D01*
G01X1290392Y588867D02*
X1290397Y588825D01*
G01X1290388Y588965D02*
X1290392Y588867D01*
G01X1290384Y589117D02*
X1290388Y588965D01*
G01X1292296Y605511D02*
X1292291Y605553D01*
G01X1292300Y605413D02*
X1292296Y605511D01*
G01X1292305Y605261D02*
X1292300Y605413D01*
G01X1294334Y588867D02*
X1294339Y588825D01*
G01X1294330Y588965D02*
X1294334Y588867D01*
G01X1294325Y589117D02*
X1294330Y588965D01*
G01X1296238Y605511D02*
X1296233Y605553D01*
G01X1296242Y605413D02*
X1296238Y605511D01*
G01X1296246Y605261D02*
X1296242Y605413D01*
G01X1298266Y588867D02*
X1298271Y588825D01*
G01X1298262Y588965D02*
X1298266Y588867D01*
G01X1298258Y589117D02*
X1298262Y588965D01*
G01X1300170Y605511D02*
X1300165Y605553D01*
G01X1300174Y605413D02*
X1300170Y605511D01*
G01X1300179Y605261D02*
X1300174Y605413D01*
G01X1302208Y588867D02*
X1302213Y588825D01*
G01X1302204Y588965D02*
X1302208Y588867D01*
G01X1302199Y589117D02*
X1302204Y588965D01*
G01X1304112Y605511D02*
X1304107Y605553D01*
G01X1304116Y605413D02*
X1304112Y605511D01*
G01X1304120Y605261D02*
X1304116Y605413D01*
G01X1288620Y589645D02*
X1288625Y589615D01*
G01X1288616Y589841D02*
X1288620Y589645D01*
G01X1288614Y590169D02*
X1288616Y589841D01*
G01X1288613Y590571D02*
X1288614Y590169D01*
G01X1290135Y604733D02*
X1290131Y604763D01*
G01X1290139Y604537D02*
X1290135Y604733D01*
G01X1290142Y604209D02*
X1290139Y604537D01*
G01X1290143Y603807D02*
X1290142Y604209D01*
G01X1296494Y589645D02*
X1296499Y589615D01*
G01X1296490Y589841D02*
X1296494Y589645D01*
G01X1296488Y590169D02*
X1296490Y589841D01*
G01X1296487Y590571D02*
X1296488Y590169D01*
G01X1298009Y604733D02*
X1298005Y604763D01*
G01X1298013Y604537D02*
X1298009Y604733D01*
G01X1298016Y604209D02*
X1298013Y604537D01*
G01X1298017Y603807D02*
X1298016Y604209D01*
G01X1304368Y589645D02*
X1304373Y589615D01*
G01X1304364Y589841D02*
X1304368Y589645D01*
G01X1304362Y590169D02*
X1304364Y589841D01*
G01X1304361Y590571D02*
X1304362Y590169D01*
G01X1305883Y604733D02*
X1305879Y604763D01*
G01X1305888Y604537D02*
X1305883Y604733D01*
G01X1305890Y604209D02*
X1305888Y604537D01*
G01X1305891Y603807D02*
X1305890Y604209D01*
G01X1284683Y588770D02*
X1284691Y588621D01*
G01X1284676Y589184D02*
X1284683Y588770D01*
G01X1284671Y589804D02*
X1284676Y589184D01*
G01X1284669Y590552D02*
X1284671Y589804D01*
G01X1284687Y589679D02*
X1284691Y589606D01*
G01X1284684Y589887D02*
X1284687Y589679D01*
G01X1284681Y590200D02*
X1284684Y589887D01*
G01X1284680Y590571D02*
X1284681Y590200D01*
G01X1286195Y604699D02*
X1286191Y604772D01*
G01X1286198Y604491D02*
X1286195Y604699D01*
G01X1286201Y604178D02*
X1286198Y604491D01*
G01X1286202Y603807D02*
X1286201Y604178D01*
G01X1286199Y605608D02*
X1286191Y605757D01*
G01X1286206Y605193D02*
X1286199Y605608D01*
G01X1286211Y604573D02*
X1286206Y605193D01*
G01X1286213Y603826D02*
X1286211Y604573D01*
G01X1292557Y588770D02*
X1292565Y588621D01*
G01X1292550Y589184D02*
X1292557Y588770D01*
G01X1292545Y589804D02*
X1292550Y589184D01*
G01X1292543Y590552D02*
X1292545Y589804D01*
G01X1292561Y589679D02*
X1292565Y589606D01*
G01X1292558Y589887D02*
X1292561Y589679D01*
G01X1292555Y590200D02*
X1292558Y589887D01*
G01X1292554Y590571D02*
X1292555Y590200D01*
G01X1294069Y604699D02*
X1294065Y604772D01*
G01X1294072Y604491D02*
X1294069Y604699D01*
G01X1294075Y604178D02*
X1294072Y604491D01*
G01X1294076Y603807D02*
X1294075Y604178D01*
G01X1294073Y605608D02*
X1294065Y605757D01*
G01X1294080Y605193D02*
X1294073Y605608D01*
G01X1294085Y604573D02*
X1294080Y605193D01*
G01X1294087Y603826D02*
X1294085Y604573D01*
G01X1300431Y588770D02*
X1300439Y588621D01*
G01X1300424Y589184D02*
X1300431Y588770D01*
G01X1300419Y589804D02*
X1300424Y589184D01*
G01X1300417Y590552D02*
X1300419Y589804D01*
G01X1301947Y605608D02*
X1301939Y605757D01*
G01X1301954Y605193D02*
X1301947Y605608D01*
G01X1301959Y604573D02*
X1301954Y605193D01*
G01X1301961Y603826D02*
X1301959Y604573D01*
G01X1300435Y604698D02*
X1300439Y604772D01*
G01X1300432Y604491D02*
X1300435Y604698D01*
G01X1300429Y604181D02*
X1300432Y604491D01*
G01X1300428Y603807D02*
X1300429Y604181D01*
G01X1301943Y589680D02*
X1301939Y589606D01*
G01X1301946Y589887D02*
X1301943Y589680D01*
G01X1301949Y590197D02*
X1301946Y589887D01*
G01X1301950Y590571D02*
X1301949Y590197D01*
G01X1292545Y604573D02*
X1292543Y603826D01*
G01X1292550Y605193D02*
X1292545Y604573D01*
G01X1292557Y605608D02*
X1292550Y605193D01*
G01X1292565Y605757D02*
X1292557Y605608D01*
G01X1294085Y589804D02*
X1294087Y590552D01*
G01X1294080Y589184D02*
X1294085Y589804D01*
G01X1294073Y588770D02*
X1294080Y589184D01*
G01X1294065Y588621D02*
X1294073Y588770D01*
G01X1300419Y604573D02*
X1300417Y603826D01*
G01X1300424Y605193D02*
X1300419Y604573D01*
G01X1300431Y605608D02*
X1300424Y605193D01*
G01X1300439Y605757D02*
X1300431Y605608D01*
G01X1301959Y589804D02*
X1301961Y590552D01*
G01X1301954Y589184D02*
X1301959Y589804D01*
G01X1301947Y588770D02*
X1301954Y589184D01*
G01X1301939Y588621D02*
X1301947Y588770D01*
G01X1292555Y604178D02*
X1292554Y603807D01*
G01X1292558Y604491D02*
X1292555Y604178D01*
G01X1292561Y604699D02*
X1292558Y604491D01*
G01X1292565Y604772D02*
X1292561Y604699D01*
G01X1294075Y590200D02*
X1294076Y590571D01*
G01X1294072Y589887D02*
X1294075Y590200D01*
G01X1294069Y589679D02*
X1294072Y589887D01*
G01X1294065Y589606D02*
X1294069Y589679D01*
G01X1300440Y589607D02*
X1300439Y589606D01*
G01X1300440Y589610D02*
Y589607D01*
G01X1300441Y589617D02*
X1300440Y589610D01*
G01X1301938Y604771D02*
X1301939Y604772D01*
G01X1301938Y604768D02*
Y604771D01*
G01X1301937Y604761D02*
X1301938Y604768D01*
G01X1300174Y588965D02*
X1300179Y589117D01*
G01X1300170Y588867D02*
X1300174Y588965D01*
G01X1300165Y588825D02*
X1300170Y588867D01*
G01X1302204Y605413D02*
X1302199Y605261D01*
G01X1302208Y605511D02*
X1302204Y605413D01*
G01X1302213Y605553D02*
X1302208Y605511D01*
G01X1304107Y588965D02*
X1304111Y589117D01*
G01X1304102Y588867D02*
X1304107Y588965D01*
G01X1304098Y588825D02*
X1304102Y588867D01*
G01X1306145Y605413D02*
X1306141Y605261D01*
G01X1306150Y605511D02*
X1306145Y605413D01*
G01X1306154Y605553D02*
X1306150Y605511D01*
G01X1302200Y606353D02*
X1302195Y606147D01*
G01X1302206Y606485D02*
X1302200Y606353D01*
G01X1302213Y606538D02*
X1302206Y606485D01*
G01X1300178Y588025D02*
X1300183Y588231D01*
G01X1300172Y587893D02*
X1300178Y588025D01*
G01X1300165Y587840D02*
X1300172Y587893D01*
G01X1306142Y606353D02*
X1306136Y606147D01*
G01X1306148Y606485D02*
X1306142Y606353D01*
G01X1306154Y606538D02*
X1306148Y606485D01*
G01X1304110Y588025D02*
X1304116Y588231D01*
G01X1304104Y587893D02*
X1304110Y588025D01*
G01X1304098Y587840D02*
X1304104Y587893D01*
G01X1305881Y590169D02*
X1305882Y590571D01*
G01X1305878Y589841D02*
X1305881Y590169D01*
G01X1305874Y589645D02*
X1305878Y589841D01*
G01X1305870Y589615D02*
X1305874Y589645D01*
G01X1262568Y588622D02*
X1262569Y588621D01*
G01X1262567Y588624D02*
X1262568Y588622D01*
G01X1262567Y588627D02*
Y588624D01*
G01X1270442Y588622D02*
X1270443Y588621D01*
G01X1270442Y588624D02*
Y588622D01*
G01X1270441Y588627D02*
X1270442Y588624D01*
G01X1268944Y605756D02*
X1268943Y605757D01*
G01X1268944Y605754D02*
Y605756D01*
G01X1268945Y605751D02*
X1268944Y605754D01*
G01X1278316Y588622D02*
X1278317Y588621D01*
G01X1278316Y588624D02*
Y588622D01*
G01X1278315Y588627D02*
X1278316Y588624D01*
G01X1276818Y605756D02*
X1276817Y605757D01*
G01X1276818Y605754D02*
Y605756D01*
G01X1276819Y605751D02*
X1276818Y605754D01*
G01X1286190Y588622D02*
X1286191Y588621D01*
G01X1286190Y588624D02*
Y588622D01*
G01X1286189Y588627D02*
X1286190Y588624D01*
G01X1301949Y604181D02*
X1301950Y603807D01*
G01X1301946Y604491D02*
X1301949Y604181D01*
G01X1301943Y604698D02*
X1301946Y604491D01*
G01X1301939Y604772D02*
X1301943Y604698D01*
G01X1306139Y587893D02*
X1306145Y587840D01*
G01X1306133Y588025D02*
X1306139Y587893D01*
G01X1306127Y588231D02*
X1306133Y588025D01*
G01X1306140Y588867D02*
X1306145Y588825D01*
G01X1306136Y588965D02*
X1306140Y588867D01*
G01X1306132Y589117D02*
X1306136Y588965D01*
G01X1284692Y605756D02*
X1284691Y605757D01*
G01X1284692Y605754D02*
Y605756D01*
G01X1284693Y605751D02*
X1284692Y605754D01*
G01X1294064Y588622D02*
X1294065Y588621D01*
G01X1294064Y588624D02*
Y588622D01*
G01X1294063Y588627D02*
X1294064Y588624D01*
G01X1292566Y605756D02*
X1292565Y605757D01*
G01X1292566Y605754D02*
Y605756D01*
G01X1292567Y605751D02*
X1292566Y605754D01*
G01X1301938Y588622D02*
X1301939Y588621D01*
G01X1301938Y588624D02*
Y588622D01*
G01X1301937Y588627D02*
X1301938Y588624D01*
G01X1300440Y605756D02*
X1300439Y605757D01*
G01X1300440Y605754D02*
Y605756D01*
G01X1300441Y605751D02*
X1300440Y605754D01*
G01X1301938Y589610D02*
X1301937Y589617D01*
G01X1301938Y589607D02*
Y589610D01*
G01X1301939Y589606D02*
X1301938Y589607D01*
G01X1300440Y604768D02*
X1300441Y604761D01*
G01X1300440Y604771D02*
Y604768D01*
G01X1300439Y604772D02*
X1300440Y604771D01*
G01X1300135Y588823D02*
X1300120D01*
G01X1300150Y588824D02*
X1300135Y588823D01*
G01X1300165Y588825D02*
X1300150Y588824D01*
G01X1292261Y588823D02*
X1292246D01*
G01X1292276Y588824D02*
X1292261Y588823D01*
G01X1292291Y588825D02*
X1292276Y588824D01*
G01X1288320Y588823D02*
X1288305D01*
G01X1288335Y588824D02*
X1288320Y588823D01*
G01X1288350Y588825D02*
X1288335Y588824D01*
G01X1284387Y588823D02*
X1284372D01*
G01X1284402Y588824D02*
X1284387Y588823D01*
G01X1284417Y588825D02*
X1284402Y588824D01*
G01X1280446Y588823D02*
X1280431D01*
G01X1280461Y588824D02*
X1280446Y588823D01*
G01X1280476Y588825D02*
X1280461Y588824D01*
G01X1276513Y588823D02*
X1276498D01*
G01X1276528Y588824D02*
X1276513Y588823D01*
G01X1276543Y588825D02*
X1276528Y588824D01*
G01X1272572Y588823D02*
X1272557D01*
G01X1272587Y588824D02*
X1272572Y588823D01*
G01X1272602Y588825D02*
X1272587Y588824D01*
G01X1268639Y588823D02*
X1268624D01*
G01X1268654Y588824D02*
X1268639Y588823D01*
G01X1268669Y588825D02*
X1268654Y588824D01*
G01X1264698Y588823D02*
X1264683D01*
G01X1264713Y588824D02*
X1264698Y588823D01*
G01X1264728Y588825D02*
X1264713Y588824D01*
G01X1306184Y605555D02*
X1306199D01*
G01X1306169Y605554D02*
X1306184Y605555D01*
G01X1306154Y605553D02*
X1306169Y605554D01*
G01X1302243Y605555D02*
X1302258D01*
G01X1302228Y605554D02*
X1302243Y605555D01*
G01X1302213Y605553D02*
X1302228Y605554D01*
G01X1298310Y605555D02*
X1298325D01*
G01X1298295Y605554D02*
X1298310Y605555D01*
G01X1298280Y605553D02*
X1298295Y605554D01*
G01X1294369Y605555D02*
X1294384D01*
G01X1294354Y605554D02*
X1294369Y605555D01*
G01X1294339Y605553D02*
X1294354Y605554D01*
G01X1290436Y605555D02*
X1290451D01*
G01X1290421Y605554D02*
X1290436Y605555D01*
G01X1290406Y605553D02*
X1290421Y605554D01*
G01X1286495Y605555D02*
X1286510D01*
G01X1286480Y605554D02*
X1286495Y605555D01*
G01X1286465Y605553D02*
X1286480Y605554D01*
G01X1278621Y605555D02*
X1278636D01*
G01X1278606Y605554D02*
X1278621Y605555D01*
G01X1278591Y605553D02*
X1278606Y605554D01*
G01X1270747Y605555D02*
X1270762D01*
G01X1270732Y605554D02*
X1270747Y605555D01*
G01X1270717Y605553D02*
X1270732Y605554D01*
G01X1266814Y605555D02*
X1266829D01*
G01X1266799Y605554D02*
X1266814Y605555D01*
G01X1266784Y605553D02*
X1266799Y605554D01*
G01X1262873Y605555D02*
X1262888D01*
G01X1262858Y605554D02*
X1262873Y605555D01*
G01X1262843Y605553D02*
X1262858Y605554D01*
G01X1304068Y587839D02*
X1304053D01*
G01X1304083D02*
X1304068D01*
G01X1304098Y587840D02*
X1304083Y587839D01*
G01X1296194D02*
X1296179D01*
G01X1296209D02*
X1296194D01*
G01X1296224Y587840D02*
X1296209Y587839D01*
G01X1292261D02*
X1292246D01*
G01X1292276D02*
X1292261D01*
G01X1292291Y587840D02*
X1292276Y587839D01*
G01X1288320D02*
X1288305D01*
G01X1288335D02*
X1288320D01*
G01X1288350Y587840D02*
X1288335Y587839D01*
G01X1284387D02*
X1284372D01*
G01X1284402D02*
X1284387D01*
G01X1284417Y587840D02*
X1284402Y587839D01*
G01X1280446D02*
X1280431D01*
G01X1280461D02*
X1280446D01*
G01X1280476Y587840D02*
X1280461Y587839D01*
G01X1276513D02*
X1276498D01*
G01X1276528D02*
X1276513D01*
G01X1276543Y587840D02*
X1276528Y587839D01*
G01X1272572D02*
X1272557D01*
G01X1272587D02*
X1272572D01*
G01X1272602Y587840D02*
X1272587Y587839D01*
G01X1268639D02*
X1268624D01*
G01X1268654D02*
X1268639D01*
G01X1268669Y587840D02*
X1268654Y587839D01*
G01X1264698D02*
X1264683D01*
G01X1264713D02*
X1264698D01*
G01X1264728Y587840D02*
X1264713Y587839D01*
G01X1298310Y606539D02*
X1298325D01*
G01X1298295D02*
X1298310D01*
G01X1298280Y606538D02*
X1298295Y606539D01*
G01X1294369D02*
X1294384D01*
G01X1294354D02*
X1294369D01*
G01X1294339Y606538D02*
X1294354Y606539D01*
G01X1290436D02*
X1290451D01*
G01X1290421D02*
X1290436D01*
G01X1290406Y606538D02*
X1290421Y606539D01*
G01X1286495D02*
X1286510D01*
G01X1286480D02*
X1286495D01*
G01X1286465Y606538D02*
X1286480Y606539D01*
G01X1282562D02*
X1282577D01*
G01X1282547D02*
X1282562D01*
G01X1282532Y606538D02*
X1282547Y606539D01*
G01X1278621D02*
X1278636D01*
G01X1278606D02*
X1278621D01*
G01X1278591Y606538D02*
X1278606Y606539D01*
G01X1274688D02*
X1274703D01*
G01X1274673D02*
X1274688D01*
G01X1274658Y606538D02*
X1274673Y606539D01*
G01X1270747D02*
X1270762D01*
G01X1270732D02*
X1270747D01*
G01X1270717Y606538D02*
X1270732Y606539D01*
G01X1266814D02*
X1266829D01*
G01X1266799D02*
X1266814D01*
G01X1266784Y606538D02*
X1266799Y606539D01*
G01X1262873D02*
X1262888D01*
G01X1262858D02*
X1262873D01*
G01X1262843Y606538D02*
X1262858Y606539D01*
G01Y587839D02*
X1262843Y587840D01*
G01X1262873Y587839D02*
X1262858D01*
G01X1262888D02*
X1262873D01*
G01X1266790D02*
X1266775Y587840D01*
G01X1266805Y587839D02*
X1266790D01*
G01X1266820D02*
X1266805D01*
G01X1270732D02*
X1270717Y587840D01*
G01X1270747Y587839D02*
X1270732D01*
G01X1270762D02*
X1270747D01*
G01X1274664D02*
X1274649Y587840D01*
G01X1274679Y587839D02*
X1274664D01*
G01X1274694D02*
X1274679D01*
G01X1278606D02*
X1278591Y587840D01*
G01X1278621Y587839D02*
X1278606D01*
G01X1278636D02*
X1278621D01*
G01X1282538D02*
X1282523Y587840D01*
G01X1282553Y587839D02*
X1282538D01*
G01X1282568D02*
X1282553D01*
G01X1286480D02*
X1286465Y587840D01*
G01X1286495Y587839D02*
X1286480D01*
G01X1286510D02*
X1286495D01*
G01X1290412D02*
X1290397Y587840D01*
G01X1290427Y587839D02*
X1290412D01*
G01X1290442D02*
X1290427D01*
G01X1294354D02*
X1294339Y587840D01*
G01X1294369Y587839D02*
X1294354D01*
G01X1294384D02*
X1294369D01*
G01X1298286D02*
X1298271Y587840D01*
G01X1298301Y587839D02*
X1298286D01*
G01X1298316D02*
X1298301D01*
G01X1302228D02*
X1302213Y587840D01*
G01X1302243Y587839D02*
X1302228D01*
G01X1302258D02*
X1302243D01*
G01X1306160D02*
X1306145Y587840D01*
G01X1306175Y587839D02*
X1306160D01*
G01X1306190D02*
X1306175D01*
G01X1264722Y606539D02*
X1264737Y606538D01*
G01X1264707Y606539D02*
X1264722D01*
G01X1264692D02*
X1264707D01*
G01X1268654D02*
X1268669Y606538D01*
G01X1268639Y606539D02*
X1268654D01*
G01X1268624D02*
X1268639D01*
G01X1272596D02*
X1272611Y606538D01*
G01X1272581Y606539D02*
X1272596D01*
G01X1272566D02*
X1272581D01*
G01X1276528D02*
X1276543Y606538D01*
G01X1276513Y606539D02*
X1276528D01*
G01X1276498D02*
X1276513D01*
G01X1280470D02*
X1280485Y606538D01*
G01X1280455Y606539D02*
X1280470D01*
G01X1280440D02*
X1280455D01*
G01X1284402D02*
X1284417Y606538D01*
G01X1284387Y606539D02*
X1284402D01*
G01X1284372D02*
X1284387D01*
G01X1288344D02*
X1288359Y606538D01*
G01X1288329Y606539D02*
X1288344D01*
G01X1288314D02*
X1288329D01*
G01X1292276D02*
X1292291Y606538D01*
G01X1292261Y606539D02*
X1292276D01*
G01X1292246D02*
X1292261D01*
G01X1296218D02*
X1296233Y606538D01*
G01X1296203Y606539D02*
X1296218D01*
G01X1296188D02*
X1296203D01*
G01X1300150D02*
X1300165Y606538D01*
G01X1300135Y606539D02*
X1300150D01*
G01X1300120D02*
X1300135D01*
G01X1304092D02*
X1304107Y606538D01*
G01X1304077Y606539D02*
X1304092D01*
G01X1304062D02*
X1304077D01*
G01X1262858Y588824D02*
X1262843Y588825D01*
G01X1262873Y588823D02*
X1262858Y588824D01*
G01X1262888Y588823D02*
X1262873D01*
G01X1266790Y588824D02*
X1266775Y588825D01*
G01X1266805Y588823D02*
X1266790Y588824D01*
G01X1266820Y588823D02*
X1266805D01*
G01X1270732Y588824D02*
X1270717Y588825D01*
G01X1270747Y588823D02*
X1270732Y588824D01*
G01X1270762Y588823D02*
X1270747D01*
G01X1274664Y588824D02*
X1274649Y588825D01*
G01X1274679Y588823D02*
X1274664Y588824D01*
G01X1274694Y588823D02*
X1274679D01*
G01X1278606Y588824D02*
X1278591Y588825D01*
G01X1278621Y588823D02*
X1278606Y588824D01*
G01X1278636Y588823D02*
X1278621D01*
G01X1282538Y588824D02*
X1282523Y588825D01*
G01X1282553Y588823D02*
X1282538Y588824D01*
G01X1282568Y588823D02*
X1282553D01*
G01X1286480Y588824D02*
X1286465Y588825D01*
G01X1286495Y588823D02*
X1286480Y588824D01*
G01X1286510Y588823D02*
X1286495D01*
G01X1290412Y588824D02*
X1290397Y588825D01*
G01X1290427Y588823D02*
X1290412Y588824D01*
G01X1290442Y588823D02*
X1290427D01*
G01X1294354Y588824D02*
X1294339Y588825D01*
G01X1294369Y588823D02*
X1294354Y588824D01*
G01X1294384Y588823D02*
X1294369D01*
G01X1302228Y588824D02*
X1302213Y588825D01*
G01X1302243Y588823D02*
X1302228Y588824D01*
G01X1302258Y588823D02*
X1302243D01*
G01X1268654Y605554D02*
X1268669Y605553D01*
G01X1268639Y605555D02*
X1268654Y605554D01*
G01X1268624Y605555D02*
X1268639D01*
G01X1272596Y605554D02*
X1272611Y605553D01*
G01X1272581Y605555D02*
X1272596Y605554D01*
G01X1272566Y605555D02*
X1272581D01*
G01X1276528Y605554D02*
X1276543Y605553D01*
G01X1276513Y605555D02*
X1276528Y605554D01*
G01X1276498Y605555D02*
X1276513D01*
G01X1280470Y605554D02*
X1280485Y605553D01*
G01X1280455Y605555D02*
X1280470Y605554D01*
G01X1280440Y605555D02*
X1280455D01*
G01X1284402Y605554D02*
X1284417Y605553D01*
G01X1284387Y605555D02*
X1284402Y605554D01*
G01X1284372Y605555D02*
X1284387D01*
G01X1292276Y605554D02*
X1292291Y605553D01*
G01X1292261Y605555D02*
X1292276Y605554D01*
G01X1292246Y605555D02*
X1292261D01*
G01X1296218Y605554D02*
X1296233Y605553D01*
G01X1296203Y605555D02*
X1296218Y605554D01*
G01X1296188Y605555D02*
X1296203D01*
G01X1300150Y605554D02*
X1300165Y605553D01*
G01X1300135Y605555D02*
X1300150Y605554D01*
G01X1300120Y605555D02*
X1300135D01*
G01X1304092Y605554D02*
X1304107Y605553D01*
G01X1304077Y605555D02*
X1304092Y605554D01*
G01X1304062Y605555D02*
X1304077D01*
G01X1298301Y588823D02*
X1298316D01*
G01X1298286Y588824D02*
X1298301Y588823D01*
G01X1298271Y588825D02*
X1298286Y588824D01*
G01X1306175Y588823D02*
X1306190D01*
G01X1306160Y588824D02*
X1306175Y588823D01*
G01X1306145Y588825D02*
X1306160Y588824D01*
G01X1264707Y605555D02*
X1264692D01*
G01X1264722Y605554D02*
X1264707Y605555D01*
G01X1264737Y605553D02*
X1264722Y605554D01*
G01X1288329Y605555D02*
X1288314D01*
G01X1288344Y605554D02*
X1288329Y605555D01*
G01X1288359Y605553D02*
X1288344Y605554D01*
G01X1266937Y610476D02*
X1264575D01*
G01X1270874D02*
X1268512D01*
G01X1274811D02*
X1272449D01*
G01X1278748D02*
X1276386D01*
G01X1282685D02*
X1280323D01*
G01X1286622D02*
X1284260D01*
G01X1290559D02*
X1288197D01*
G01X1294496D02*
X1292134D01*
G01X1298433D02*
X1296071D01*
G01X1302370D02*
X1300008D01*
G01X1306307D02*
X1303945D01*
G01X1270362Y609492D02*
X1269024D01*
G01X1278236D02*
X1276898D01*
G01X1286110D02*
X1284772D01*
G01X1293984D02*
X1292646D01*
G01X1301858D02*
X1300520D01*
G01X1300362Y609394D02*
X1302016D01*
G01X1292488D02*
X1294142D01*
G01X1284614D02*
X1286268D01*
G01X1276740D02*
X1278394D01*
G01X1268866D02*
X1270520D01*
G01X1266937Y609295D02*
X1264575D01*
G01X1270874D02*
X1268512D01*
G01X1274811D02*
X1272449D01*
G01X1278748D02*
X1276386D01*
G01X1282685D02*
X1280323D01*
G01X1286622D02*
X1284260D01*
G01X1290559D02*
X1288197D01*
G01X1294496D02*
X1292134D01*
G01X1298433D02*
X1296071D01*
G01X1302370D02*
X1300008D01*
G01X1306307D02*
X1303945D01*
G01X1270520Y608902D02*
X1268866D01*
G01X1278394D02*
X1276740D01*
G01X1286268D02*
X1284614D01*
G01X1294142D02*
X1292488D01*
G01X1302016D02*
X1300362D01*
G01X1267173Y608035D02*
X1264339D01*
G01X1271110D02*
X1268276D01*
G01X1275047D02*
X1272213D01*
G01X1278984D02*
X1276150D01*
G01X1282921D02*
X1280087D01*
G01X1286858D02*
X1284024D01*
G01X1290795D02*
X1287961D01*
G01X1294732D02*
X1291898D01*
G01X1298669D02*
X1295835D01*
G01X1302606D02*
X1299772D01*
G01X1306543D02*
X1303709D01*
G01X1310480D02*
X1307646D01*
G01X1270520Y607130D02*
X1268866D01*
G01X1278394D02*
X1276740D01*
G01X1286268D02*
X1284614D01*
G01X1294142D02*
X1292488D01*
G01X1302016D02*
X1300362D01*
G01Y606638D02*
X1302016D01*
G01X1292488D02*
X1294142D01*
G01X1284614D02*
X1286268D01*
G01X1276740D02*
X1278394D01*
G01X1268866D02*
X1270520D01*
G01X1267173Y606539D02*
X1264339D01*
G01X1271110D02*
X1268276D01*
G01X1275047D02*
X1272213D01*
G01X1278984D02*
X1276150D01*
G01X1282921D02*
X1280087D01*
G01X1286858D02*
X1284024D01*
G01X1290795D02*
X1287961D01*
G01X1294732D02*
X1291898D01*
G01X1298669D02*
X1295835D01*
G01X1302606D02*
X1299772D01*
G01X1306543D02*
X1303709D01*
G01X1310480D02*
X1307646D01*
G01Y606382D02*
X1308236D01*
G01X1305953D02*
X1306543D01*
G01X1303709D02*
X1304299D01*
G01X1302016D02*
X1302606D01*
G01X1299772D02*
X1300362D01*
G01X1298079D02*
X1298669D01*
G01X1295835D02*
X1296425D01*
G01X1294142D02*
X1294732D01*
G01X1291898D02*
X1292488D01*
G01X1290205D02*
X1290795D01*
G01X1287961D02*
X1288551D01*
G01X1286268D02*
X1286858D01*
G01X1284024D02*
X1284614D01*
G01X1282331D02*
X1282921D01*
G01X1280087D02*
X1280677D01*
G01X1278394D02*
X1278984D01*
G01X1276150D02*
X1276740D01*
G01X1274457D02*
X1275047D01*
G01X1272213D02*
X1272803D01*
G01X1270520D02*
X1271110D01*
G01X1268276D02*
X1268866D01*
G01X1266583D02*
X1267173D01*
G01X1264339D02*
X1264929D01*
G01X1262646D02*
X1263236D01*
G01X1304125Y606147D02*
X1306136D01*
G01X1300183D02*
X1302195D01*
G01X1296251D02*
X1298262D01*
G01X1292309D02*
X1294321D01*
G01X1288377D02*
X1290388D01*
G01X1284435D02*
X1286447D01*
G01X1280503D02*
X1282514D01*
G01X1276561D02*
X1278573D01*
G01X1272629D02*
X1274640D01*
G01X1268687D02*
X1270699D01*
G01X1264755D02*
X1266766D01*
G01X1266510Y605757D02*
X1265011D01*
G01X1270443D02*
X1268943D01*
G01X1274384D02*
X1272885D01*
G01X1278317D02*
X1276817D01*
G01X1282258D02*
X1280759D01*
G01X1286191D02*
X1284691D01*
G01X1290132D02*
X1288633D01*
G01X1294065D02*
X1292565D01*
G01X1298006D02*
X1296507D01*
G01X1301939D02*
X1300439D01*
G01X1305880D02*
X1304381D01*
G01X1304394Y605738D02*
X1305867D01*
G01X1300452D02*
X1301925D01*
G01X1296520D02*
X1297993D01*
G01X1292578D02*
X1294051D01*
G01X1288646D02*
X1290119D01*
G01X1284704D02*
X1286177D01*
G01X1280772D02*
X1282245D01*
G01X1276830D02*
X1278303D01*
G01X1272898D02*
X1274371D01*
G01X1268956D02*
X1270429D01*
G01X1265024D02*
X1266497D01*
G01X1263236Y605713D02*
X1262646D01*
G01X1264929D02*
X1264339D01*
G01X1267173D02*
X1266583D01*
G01X1268866D02*
X1268276D01*
G01X1271110D02*
X1270520D01*
G01X1272803D02*
X1272213D01*
G01X1275047D02*
X1274457D01*
G01X1276740D02*
X1276150D01*
G01X1278984D02*
X1278394D01*
G01X1280677D02*
X1280087D01*
G01X1282921D02*
X1282331D01*
G01X1284614D02*
X1284024D01*
G01X1286858D02*
X1286268D01*
G01X1288551D02*
X1287961D01*
G01X1290795D02*
X1290205D01*
G01X1292488D02*
X1291898D01*
G01X1294732D02*
X1294142D01*
G01X1296425D02*
X1295835D01*
G01X1298669D02*
X1298079D01*
G01X1300362D02*
X1299772D01*
G01X1302606D02*
X1302016D01*
G01X1304299D02*
X1303709D01*
G01X1306543D02*
X1305953D01*
G01X1308236D02*
X1307646D01*
G01Y605555D02*
X1310480D01*
G01X1303709D02*
X1306543D01*
G01X1299772D02*
X1302606D01*
G01X1291898D02*
X1294732D01*
G01X1287961D02*
X1290795D01*
G01X1284024D02*
X1286858D01*
G01X1280087D02*
X1282921D01*
G01X1276150D02*
X1278984D01*
G01X1272213D02*
X1275047D01*
G01X1268276D02*
X1271110D01*
G01X1267173D02*
X1264339D01*
G01X1298669D02*
X1295835D01*
G01X1266583Y605457D02*
X1264929D01*
G01X1274457D02*
X1272803D01*
G01X1282331D02*
X1280677D01*
G01X1290205D02*
X1288551D01*
G01X1298079D02*
X1296425D01*
G01X1305953D02*
X1304299D01*
G01X1266243Y605368D02*
X1265278D01*
G01X1270176D02*
X1269210D01*
G01X1274117D02*
X1273152D01*
G01X1278050D02*
X1277084D01*
G01X1281991D02*
X1281026D01*
G01X1285924D02*
X1284958D01*
G01X1289865D02*
X1288900D01*
G01X1293798D02*
X1292832D01*
G01X1297739D02*
X1296774D01*
G01X1301672D02*
X1300706D01*
G01X1305613D02*
X1304648D01*
G01X1303709Y605358D02*
X1304024D01*
G01X1295835D02*
X1296150D01*
G01X1291898D02*
X1292213D01*
G01X1287961D02*
X1288276D01*
G01X1284024D02*
X1284339D01*
G01X1280087D02*
X1280402D01*
G01X1276150D02*
X1276465D01*
G01X1272213D02*
X1272528D01*
G01X1268276D02*
X1268591D01*
G01X1264339D02*
X1264654D01*
G01X1263236D02*
X1262921D01*
G01X1267173D02*
X1266858D01*
G01X1271110D02*
X1270795D01*
G01X1275047D02*
X1274732D01*
G01X1278984D02*
X1278669D01*
G01X1282921D02*
X1282606D01*
G01X1286858D02*
X1286543D01*
G01X1290795D02*
X1290480D01*
G01X1294732D02*
X1294417D01*
G01X1298669D02*
X1298354D01*
G01X1300087D02*
X1299772D01*
G01X1302606D02*
X1302291D01*
G01X1306543D02*
X1306228D01*
G01X1307961D02*
X1307646D01*
G01X1266771Y605261D02*
X1264750D01*
G01X1270703D02*
X1268682D01*
G01X1274645D02*
X1272624D01*
G01X1278577D02*
X1276557D01*
G01X1282519D02*
X1280498D01*
G01X1286451D02*
X1284431D01*
G01X1290393D02*
X1288372D01*
G01X1294325D02*
X1292305D01*
G01X1298267D02*
X1296246D01*
G01X1302199D02*
X1300179D01*
G01X1306141D02*
X1304120D01*
G01X1304299Y604965D02*
X1305953D01*
G01X1296425D02*
X1298079D01*
G01X1288551D02*
X1290205D01*
G01X1280677D02*
X1282331D01*
G01X1272803D02*
X1274457D01*
G01X1264929D02*
X1266583D01*
G01X1266510Y604772D02*
X1265011D01*
G01X1270443D02*
X1268943D01*
G01X1274384D02*
X1272885D01*
G01X1278317D02*
X1276817D01*
G01X1282258D02*
X1280759D01*
G01X1286191D02*
X1284691D01*
G01X1290132D02*
X1288633D01*
G01X1294065D02*
X1292565D01*
G01X1298006D02*
X1296507D01*
G01X1301939D02*
X1300439D01*
G01X1305880D02*
X1304381D01*
G01X1266509Y604763D02*
X1265012D01*
G01X1270441D02*
X1268945D01*
G01X1274383D02*
X1272886D01*
G01X1278315D02*
X1276819D01*
G01X1282257D02*
X1280760D01*
G01X1286189D02*
X1284693D01*
G01X1290131D02*
X1288634D01*
G01X1294063D02*
X1292567D01*
G01X1298005D02*
X1296508D01*
G01X1301937D02*
X1300441D01*
G01X1305879D02*
X1304382D01*
G01X1304602Y604441D02*
X1305659D01*
G01X1300661D02*
X1301717D01*
G01X1296728D02*
X1297785D01*
G01X1292787D02*
X1293843D01*
G01X1288854D02*
X1289911D01*
G01X1284913D02*
X1285969D01*
G01X1280980D02*
X1282037D01*
G01X1277039D02*
X1278095D01*
G01X1273106D02*
X1274163D01*
G01X1269165D02*
X1270221D01*
G01X1265232D02*
X1266289D01*
G01X1303945Y604394D02*
X1306307D01*
G01X1300008D02*
X1302370D01*
G01X1266937D02*
X1264575D01*
G01X1270874D02*
X1268512D01*
G01X1274811D02*
X1272449D01*
G01X1278748D02*
X1276386D01*
G01X1282685D02*
X1280323D01*
G01X1286622D02*
X1284260D01*
G01X1290559D02*
X1288197D01*
G01X1294496D02*
X1292134D01*
G01X1298433D02*
X1296071D01*
G01X1307646Y603862D02*
X1307961D01*
G01X1306228D02*
X1306543D01*
G01X1303709D02*
X1304024D01*
G01X1302291D02*
X1302606D01*
G01X1299772D02*
X1300087D01*
G01X1298354D02*
X1298669D01*
G01X1295835D02*
X1296150D01*
G01X1294417D02*
X1294732D01*
G01X1291898D02*
X1292213D01*
G01X1290480D02*
X1290795D01*
G01X1287961D02*
X1288276D01*
G01X1286543D02*
X1286858D01*
G01X1284024D02*
X1284339D01*
G01X1282606D02*
X1282921D01*
G01X1280087D02*
X1280402D01*
G01X1278669D02*
X1278984D01*
G01X1276150D02*
X1276465D01*
G01X1274732D02*
X1275047D01*
G01X1272213D02*
X1272528D01*
G01X1270795D02*
X1271110D01*
G01X1268276D02*
X1268591D01*
G01X1266858D02*
X1267173D01*
G01X1264339D02*
X1264654D01*
G01X1262921D02*
X1263236D01*
G01X1304359Y603826D02*
X1305902D01*
G01X1300417D02*
X1301961D01*
G01X1296485D02*
X1298028D01*
G01X1292543D02*
X1294087D01*
G01X1288611D02*
X1290154D01*
G01X1284669D02*
X1286213D01*
G01X1280737D02*
X1282280D01*
G01X1276795D02*
X1278339D01*
G01X1272863D02*
X1274406D01*
G01X1268921D02*
X1270465D01*
G01X1264989D02*
X1266532D01*
G01X1304370Y603807D02*
X1305891D01*
G01X1300428D02*
X1301950D01*
G01X1296496D02*
X1298017D01*
G01X1292554D02*
X1294076D01*
G01X1288622D02*
X1290143D01*
G01X1284680D02*
X1286202D01*
G01X1280748D02*
X1282269D01*
G01X1276806D02*
X1278328D01*
G01X1272874D02*
X1274395D01*
G01X1268932D02*
X1270454D01*
G01X1265000D02*
X1266521D01*
G01X1304299Y603193D02*
X1305953D01*
G01X1296425D02*
X1298079D01*
G01X1288551D02*
X1290205D01*
G01X1280677D02*
X1282331D01*
G01X1272803D02*
X1274457D01*
G01X1264929D02*
X1266583D01*
G01Y602701D02*
X1264929D01*
G01X1274457D02*
X1272803D01*
G01X1282331D02*
X1280677D01*
G01X1290205D02*
X1288551D01*
G01X1298079D02*
X1296425D01*
G01X1305953D02*
X1304299D01*
G01X1266425Y602602D02*
X1265087D01*
G01X1274299D02*
X1272961D01*
G01X1282173D02*
X1280835D01*
G01X1290047D02*
X1288709D01*
G01X1297921D02*
X1296583D01*
G01X1305795D02*
X1304457D01*
G01Y601618D02*
X1305795D01*
G01X1296583D02*
X1297921D01*
G01X1288709D02*
X1290047D01*
G01X1280835D02*
X1282173D01*
G01X1272961D02*
X1274299D01*
G01X1265087D02*
X1266425D01*
G01X1266558Y600999D02*
X1264963D01*
G01X1270490D02*
X1268895D01*
G01X1274432D02*
X1272837D01*
G01X1278365D02*
X1276769D01*
G01X1282306D02*
X1280711D01*
G01X1286239D02*
X1284643D01*
G01X1290180D02*
X1288585D01*
G01X1294113D02*
X1292517D01*
G01X1298054D02*
X1296459D01*
G01X1301987D02*
X1300391D01*
G01X1305928D02*
X1304333D01*
G01X1266858Y600890D02*
X1264654D01*
G01X1270795D02*
X1268591D01*
G01X1274732D02*
X1272528D01*
G01X1278669D02*
X1276465D01*
G01X1282606D02*
X1280402D01*
G01X1286543D02*
X1284339D01*
G01X1290480D02*
X1288276D01*
G01X1294417D02*
X1292213D01*
G01X1298354D02*
X1296150D01*
G01X1302291D02*
X1300087D01*
G01X1306228D02*
X1304024D01*
G01X1266630Y600239D02*
X1264891D01*
G01X1270562D02*
X1268824D01*
G01X1274504D02*
X1272765D01*
G01X1278436D02*
X1276698D01*
G01X1282378D02*
X1280639D01*
G01X1286310D02*
X1284572D01*
G01X1290252D02*
X1288513D01*
G01X1294184D02*
X1292446D01*
G01X1298126D02*
X1296387D01*
G01X1302058D02*
X1300320D01*
G01X1306000D02*
X1304261D01*
G01X1304335Y600037D02*
X1305926D01*
G01X1300394D02*
X1301984D01*
G01X1296461D02*
X1298052D01*
G01X1292520D02*
X1294110D01*
G01X1288587D02*
X1290178D01*
G01X1284646D02*
X1286236D01*
G01X1280713D02*
X1282304D01*
G01X1276772D02*
X1278362D01*
G01X1272839D02*
X1274430D01*
G01X1268898D02*
X1270488D01*
G01X1264965D02*
X1266556D01*
G01X1304283Y600013D02*
X1305979D01*
G01X1300341D02*
X1302037D01*
G01X1296409D02*
X1298105D01*
G01X1292467D02*
X1294163D01*
G01X1288535D02*
X1290231D01*
G01X1284593D02*
X1286289D01*
G01X1280661D02*
X1282357D01*
G01X1276719D02*
X1278415D01*
G01X1272787D02*
X1274483D01*
G01X1268845D02*
X1270541D01*
G01X1264912D02*
X1266609D01*
G01X1266616Y599945D02*
X1264905D01*
G01X1270548D02*
X1268838D01*
G01X1274490D02*
X1272780D01*
G01X1278422D02*
X1276712D01*
G01X1282364D02*
X1280654D01*
G01X1286296D02*
X1284586D01*
G01X1290238D02*
X1288528D01*
G01X1294170D02*
X1292460D01*
G01X1298112D02*
X1296402D01*
G01X1302044D02*
X1300334D01*
G01X1305986D02*
X1304276D01*
G01X1304256Y599353D02*
X1306005D01*
G01X1300315D02*
X1302063D01*
G01X1296382D02*
X1298131D01*
G01X1292441D02*
X1294189D01*
G01X1288508D02*
X1290257D01*
G01X1284567D02*
X1286315D01*
G01X1280634D02*
X1282383D01*
G01X1276693D02*
X1278441D01*
G01X1272760D02*
X1274509D01*
G01X1268819D02*
X1270567D01*
G01X1264886D02*
X1266635D01*
G01X1266606Y599051D02*
X1264915D01*
G01X1270539D02*
X1268847D01*
G01X1274480D02*
X1272789D01*
G01X1278413D02*
X1276721D01*
G01X1282354D02*
X1280663D01*
G01X1286287D02*
X1284595D01*
G01X1290228D02*
X1288537D01*
G01X1294161D02*
X1292469D01*
G01X1298102D02*
X1296411D01*
G01X1302035D02*
X1300343D01*
G01X1305976D02*
X1304285D01*
G01X1266616Y598961D02*
X1264905D01*
G01X1270548D02*
X1268838D01*
G01X1274490D02*
X1272780D01*
G01X1278422D02*
X1276712D01*
G01X1282364D02*
X1280654D01*
G01X1286296D02*
X1284586D01*
G01X1290238D02*
X1288528D01*
G01X1294170D02*
X1292460D01*
G01X1298112D02*
X1296402D01*
G01X1302044D02*
X1300334D01*
G01X1305986D02*
X1304276D01*
G01X1304024Y598635D02*
X1306228D01*
G01X1300087D02*
X1302291D01*
G01X1296150D02*
X1298354D01*
G01X1292213D02*
X1294417D01*
G01X1288276D02*
X1290480D01*
G01X1284339D02*
X1286543D01*
G01X1280402D02*
X1282606D01*
G01X1276465D02*
X1278669D01*
G01X1272528D02*
X1274732D01*
G01X1268591D02*
X1270795D01*
G01X1264654D02*
X1266858D01*
G01X1304024Y598468D02*
X1306228D01*
G01X1300087D02*
X1302291D01*
G01X1296150D02*
X1298354D01*
G01X1292213D02*
X1294417D01*
G01X1288276D02*
X1290480D01*
G01X1284339D02*
X1286543D01*
G01X1280402D02*
X1282606D01*
G01X1276465D02*
X1278669D01*
G01X1272528D02*
X1274732D01*
G01X1268591D02*
X1270795D01*
G01X1264654D02*
X1266858D01*
G01Y595910D02*
X1264654D01*
G01X1270795D02*
X1268591D01*
G01X1274732D02*
X1272528D01*
G01X1278669D02*
X1276465D01*
G01X1282606D02*
X1280402D01*
G01X1286543D02*
X1284339D01*
G01X1290480D02*
X1288276D01*
G01X1294417D02*
X1292213D01*
G01X1298354D02*
X1296150D01*
G01X1302291D02*
X1300087D01*
G01X1306228D02*
X1304024D01*
G01X1266858Y595743D02*
X1264654D01*
G01X1270795D02*
X1268591D01*
G01X1274732D02*
X1272528D01*
G01X1278669D02*
X1276465D01*
G01X1282606D02*
X1280402D01*
G01X1286543D02*
X1284339D01*
G01X1290480D02*
X1288276D01*
G01X1294417D02*
X1292213D01*
G01X1298354D02*
X1296150D01*
G01X1302291D02*
X1300087D01*
G01X1306228D02*
X1304024D01*
G01X1304266Y595417D02*
X1305976D01*
G01X1300334D02*
X1302044D01*
G01X1296392D02*
X1298102D01*
G01X1292460D02*
X1294170D01*
G01X1288518D02*
X1290228D01*
G01X1284586D02*
X1286296D01*
G01X1280644D02*
X1282354D01*
G01X1276712D02*
X1278422D01*
G01X1272770D02*
X1274480D01*
G01X1268838D02*
X1270548D01*
G01X1264896D02*
X1266606D01*
G01X1304276Y595327D02*
X1305967D01*
G01X1300343D02*
X1302035D01*
G01X1296402D02*
X1298093D01*
G01X1292469D02*
X1294161D01*
G01X1288528D02*
X1290219D01*
G01X1284595D02*
X1286287D01*
G01X1280654D02*
X1282345D01*
G01X1276721D02*
X1278413D01*
G01X1272780D02*
X1274471D01*
G01X1268847D02*
X1270539D01*
G01X1264905D02*
X1266597D01*
G01X1266625Y595025D02*
X1264877D01*
G01X1270567D02*
X1268819D01*
G01X1274499D02*
X1272751D01*
G01X1278441D02*
X1276693D01*
G01X1282373D02*
X1280625D01*
G01X1286315D02*
X1284567D01*
G01X1290247D02*
X1288499D01*
G01X1294189D02*
X1292441D01*
G01X1298121D02*
X1296373D01*
G01X1302063D02*
X1300315D01*
G01X1305995D02*
X1304247D01*
G01X1304266Y594433D02*
X1305976D01*
G01X1300334D02*
X1302044D01*
G01X1296392D02*
X1298102D01*
G01X1292460D02*
X1294170D01*
G01X1288518D02*
X1290228D01*
G01X1284586D02*
X1286296D01*
G01X1280644D02*
X1282354D01*
G01X1276712D02*
X1278422D01*
G01X1272770D02*
X1274480D01*
G01X1268838D02*
X1270548D01*
G01X1264896D02*
X1266606D01*
G01X1266599Y594365D02*
X1264903D01*
G01X1270541D02*
X1268845D01*
G01X1274473D02*
X1272777D01*
G01X1278415D02*
X1276719D01*
G01X1282347D02*
X1280651D01*
G01X1286289D02*
X1284593D01*
G01X1290221D02*
X1288525D01*
G01X1294163D02*
X1292467D01*
G01X1298095D02*
X1296399D01*
G01X1302037D02*
X1300341D01*
G01X1305969D02*
X1304273D01*
G01X1266546Y594341D02*
X1264956D01*
G01X1270488D02*
X1268898D01*
G01X1274420D02*
X1272830D01*
G01X1278362D02*
X1276772D01*
G01X1282295D02*
X1280704D01*
G01X1286236D02*
X1284646D01*
G01X1290169D02*
X1288578D01*
G01X1294110D02*
X1292520D01*
G01X1298043D02*
X1296452D01*
G01X1301984D02*
X1300394D01*
G01X1305917D02*
X1304326D01*
G01X1304252Y594139D02*
X1305991D01*
G01X1300320D02*
X1302058D01*
G01X1296378D02*
X1298117D01*
G01X1292446D02*
X1294184D01*
G01X1288504D02*
X1290243D01*
G01X1284572D02*
X1286310D01*
G01X1280630D02*
X1282369D01*
G01X1276698D02*
X1278436D01*
G01X1272756D02*
X1274495D01*
G01X1268824D02*
X1270562D01*
G01X1264882D02*
X1266621D01*
G01X1304024Y593488D02*
X1306228D01*
G01X1300087D02*
X1302291D01*
G01X1296150D02*
X1298354D01*
G01X1292213D02*
X1294417D01*
G01X1288276D02*
X1290480D01*
G01X1284339D02*
X1286543D01*
G01X1280402D02*
X1282606D01*
G01X1276465D02*
X1278669D01*
G01X1272528D02*
X1274732D01*
G01X1268591D02*
X1270795D01*
G01X1264654D02*
X1266858D01*
G01X1304324Y593379D02*
X1305919D01*
G01X1300391D02*
X1301987D01*
G01X1296450D02*
X1298045D01*
G01X1292517D02*
X1294113D01*
G01X1288576D02*
X1290171D01*
G01X1284643D02*
X1286239D01*
G01X1280702D02*
X1282297D01*
G01X1276769D02*
X1278365D01*
G01X1272828D02*
X1274423D01*
G01X1268895D02*
X1270490D01*
G01X1264954D02*
X1266549D01*
G01X1266425Y592760D02*
X1265087D01*
G01X1274299D02*
X1272961D01*
G01X1282173D02*
X1280835D01*
G01X1290047D02*
X1288709D01*
G01X1297921D02*
X1296583D01*
G01X1305795D02*
X1304457D01*
G01X1266425Y591776D02*
X1265087D01*
G01X1274299D02*
X1272961D01*
G01X1282173D02*
X1280835D01*
G01X1290047D02*
X1288709D01*
G01X1297921D02*
X1296583D01*
G01X1305795D02*
X1304457D01*
G01X1304299Y591677D02*
X1305953D01*
G01X1296425D02*
X1298079D01*
G01X1288551D02*
X1290205D01*
G01X1280677D02*
X1282331D01*
G01X1272803D02*
X1274457D01*
G01X1264929D02*
X1266583D01*
G01Y591185D02*
X1264929D01*
G01X1274457D02*
X1272803D01*
G01X1282331D02*
X1280677D01*
G01X1290205D02*
X1288551D01*
G01X1298079D02*
X1296425D01*
G01X1305953D02*
X1304299D01*
G01X1266512Y590571D02*
X1264991D01*
G01X1270454D02*
X1268932D01*
G01X1274386D02*
X1272865D01*
G01X1278328D02*
X1276806D01*
G01X1282260D02*
X1280739D01*
G01X1286202D02*
X1284680D01*
G01X1290134D02*
X1288613D01*
G01X1294076D02*
X1292554D01*
G01X1298008D02*
X1296487D01*
G01X1301950D02*
X1300428D01*
G01X1305882D02*
X1304361D01*
G01X1266523Y590552D02*
X1264980D01*
G01X1270465D02*
X1268921D01*
G01X1274397D02*
X1272854D01*
G01X1278339D02*
X1276795D01*
G01X1282271D02*
X1280728D01*
G01X1286213D02*
X1284669D01*
G01X1290145D02*
X1288602D01*
G01X1294087D02*
X1292543D01*
G01X1298019D02*
X1296476D01*
G01X1301961D02*
X1300417D01*
G01X1305893D02*
X1304350D01*
G01X1263236Y590516D02*
X1262921D01*
G01X1264654D02*
X1264339D01*
G01X1267173D02*
X1266858D01*
G01X1268591D02*
X1268276D01*
G01X1271110D02*
X1270795D01*
G01X1272528D02*
X1272213D01*
G01X1275047D02*
X1274732D01*
G01X1276465D02*
X1276150D01*
G01X1278984D02*
X1278669D01*
G01X1280402D02*
X1280087D01*
G01X1282921D02*
X1282606D01*
G01X1284339D02*
X1284024D01*
G01X1288276D02*
X1287961D01*
G01X1286858D02*
X1286543D01*
G01X1290795D02*
X1290480D01*
G01X1292213D02*
X1291898D01*
G01X1294732D02*
X1294417D01*
G01X1296150D02*
X1295835D01*
G01X1298669D02*
X1298354D01*
G01X1300087D02*
X1299772D01*
G01X1302606D02*
X1302291D01*
G01X1304024D02*
X1303709D01*
G01X1306543D02*
X1306228D01*
G01X1307961D02*
X1307646D01*
G01X1266937Y589984D02*
X1264575D01*
G01X1270874D02*
X1268512D01*
G01X1274811D02*
X1272449D01*
G01X1278748D02*
X1276386D01*
G01X1282685D02*
X1280323D01*
G01X1286622D02*
X1284260D01*
G01X1290559D02*
X1288197D01*
G01X1294496D02*
X1292134D01*
G01X1298433D02*
X1296071D01*
G01X1302370D02*
X1300008D01*
G01X1306307D02*
X1303945D01*
G01X1266280Y589937D02*
X1265223D01*
G01X1270221D02*
X1269165D01*
G01X1274154D02*
X1273097D01*
G01X1278095D02*
X1277039D01*
G01X1282028D02*
X1280971D01*
G01X1285969D02*
X1284913D01*
G01X1289902D02*
X1288845D01*
G01X1293843D02*
X1292787D01*
G01X1297776D02*
X1296719D01*
G01X1301717D02*
X1300661D01*
G01X1305650D02*
X1304593D01*
G01X1304373Y589615D02*
X1305870D01*
G01X1300441D02*
X1301937D01*
G01X1296499D02*
X1297996D01*
G01X1292567D02*
X1294063D01*
G01X1288625D02*
X1290122D01*
G01X1284693D02*
X1286189D01*
G01X1280751D02*
X1282247D01*
G01X1276819D02*
X1278315D01*
G01X1272877D02*
X1274373D01*
G01X1268945D02*
X1270441D01*
G01X1265003D02*
X1266499D01*
G01X1304372Y589606D02*
X1305871D01*
G01X1300439D02*
X1301939D01*
G01X1296498D02*
X1297997D01*
G01X1292565D02*
X1294065D01*
G01X1288624D02*
X1290123D01*
G01X1284691D02*
X1286191D01*
G01X1280750D02*
X1282249D01*
G01X1276817D02*
X1278317D01*
G01X1272876D02*
X1274375D01*
G01X1268943D02*
X1270443D01*
G01X1265002D02*
X1266501D01*
G01X1266583Y589413D02*
X1264929D01*
G01X1274457D02*
X1272803D01*
G01X1282331D02*
X1280677D01*
G01X1290205D02*
X1288551D01*
G01X1298079D02*
X1296425D01*
G01X1305953D02*
X1304299D01*
G01X1304111Y589117D02*
X1306132D01*
G01X1300179D02*
X1302199D01*
G01X1296237D02*
X1298258D01*
G01X1292305D02*
X1294325D01*
G01X1288363D02*
X1290384D01*
G01X1284431D02*
X1286451D01*
G01X1280489D02*
X1282510D01*
G01X1276557D02*
X1278577D01*
G01X1272615D02*
X1274636D01*
G01X1268682D02*
X1270703D01*
G01X1264741D02*
X1266762D01*
G01X1306228Y589020D02*
X1306543D01*
G01X1298354D02*
X1298669D01*
G01X1294417D02*
X1294732D01*
G01X1290480D02*
X1290795D01*
G01X1286543D02*
X1286858D01*
G01X1282606D02*
X1282921D01*
G01X1278669D02*
X1278984D01*
G01X1274732D02*
X1275047D01*
G01X1270795D02*
X1271110D01*
G01X1266858D02*
X1267173D01*
G01X1262921D02*
X1263236D01*
G01X1264654D02*
X1264339D01*
G01X1268591D02*
X1268276D01*
G01X1272528D02*
X1272213D01*
G01X1276465D02*
X1276150D01*
G01X1280402D02*
X1280087D01*
G01X1284339D02*
X1284024D01*
G01X1288276D02*
X1287961D01*
G01X1292213D02*
X1291898D01*
G01X1296150D02*
X1295835D01*
G01X1300087D02*
X1299772D01*
G01X1302606D02*
X1302291D01*
G01X1304024D02*
X1303709D01*
G01X1307961D02*
X1307646D01*
G01X1304639Y589010D02*
X1305604D01*
G01X1300706D02*
X1301672D01*
G01X1296765D02*
X1297730D01*
G01X1292832D02*
X1293798D01*
G01X1288891D02*
X1289856D01*
G01X1284958D02*
X1285924D01*
G01X1281017D02*
X1281982D01*
G01X1277084D02*
X1278050D01*
G01X1273143D02*
X1274108D01*
G01X1269210D02*
X1270176D01*
G01X1265269D02*
X1266234D01*
G01X1304299Y588921D02*
X1305953D01*
G01X1296425D02*
X1298079D01*
G01X1288551D02*
X1290205D01*
G01X1280677D02*
X1282331D01*
G01X1272803D02*
X1274457D01*
G01X1264929D02*
X1266583D01*
G01X1307646Y588823D02*
X1310480D01*
G01X1303709D02*
X1306543D01*
G01X1299772D02*
X1302606D01*
G01X1295835D02*
X1298669D01*
G01X1291898D02*
X1294732D01*
G01X1287961D02*
X1290795D01*
G01X1284024D02*
X1286858D01*
G01X1280087D02*
X1282921D01*
G01X1276150D02*
X1278984D01*
G01X1272213D02*
X1275047D01*
G01X1268276D02*
X1271110D01*
G01X1264339D02*
X1267173D01*
G01X1307646Y588665D02*
X1308236D01*
G01X1305953D02*
X1306543D01*
G01X1303709D02*
X1304299D01*
G01X1302016D02*
X1302606D01*
G01X1299772D02*
X1300362D01*
G01X1298079D02*
X1298669D01*
G01X1295835D02*
X1296425D01*
G01X1294142D02*
X1294732D01*
G01X1291898D02*
X1292488D01*
G01X1290205D02*
X1290795D01*
G01X1287961D02*
X1288551D01*
G01X1286268D02*
X1286858D01*
G01X1284024D02*
X1284614D01*
G01X1282331D02*
X1282921D01*
G01X1280087D02*
X1280677D01*
G01X1278394D02*
X1278984D01*
G01X1276150D02*
X1276740D01*
G01X1274457D02*
X1275047D01*
G01X1272213D02*
X1272803D01*
G01X1270520D02*
X1271110D01*
G01X1268276D02*
X1268866D01*
G01X1266583D02*
X1267173D01*
G01X1264339D02*
X1264929D01*
G01X1262646D02*
X1263236D01*
G01X1266488Y588640D02*
X1265015D01*
G01X1270429D02*
X1268956D01*
G01X1274362D02*
X1272889D01*
G01X1278303D02*
X1276830D01*
G01X1282236D02*
X1280763D01*
G01X1286177D02*
X1284704D01*
G01X1290110D02*
X1288637D01*
G01X1294051D02*
X1292578D01*
G01X1297984D02*
X1296511D01*
G01X1301925D02*
X1300452D01*
G01X1305858D02*
X1304385D01*
G01X1304372Y588621D02*
X1305871D01*
G01X1300439D02*
X1301939D01*
G01X1296498D02*
X1297997D01*
G01X1292565D02*
X1294065D01*
G01X1288624D02*
X1290123D01*
G01X1284691D02*
X1286191D01*
G01X1280750D02*
X1282249D01*
G01X1276817D02*
X1278317D01*
G01X1272876D02*
X1274375D01*
G01X1268943D02*
X1270443D01*
G01X1265002D02*
X1266501D01*
G01X1266757Y588231D02*
X1264746D01*
G01X1270699D02*
X1268687D01*
G01X1274631D02*
X1272620D01*
G01X1278573D02*
X1276561D01*
G01X1282505D02*
X1280494D01*
G01X1286447D02*
X1284435D01*
G01X1290379D02*
X1288368D01*
G01X1294321D02*
X1292309D01*
G01X1298253D02*
X1296242D01*
G01X1302195D02*
X1300183D01*
G01X1306127D02*
X1304116D01*
G01X1263236Y587996D02*
X1262646D01*
G01X1264929D02*
X1264339D01*
G01X1267173D02*
X1266583D01*
G01X1268866D02*
X1268276D01*
G01X1271110D02*
X1270520D01*
G01X1272803D02*
X1272213D01*
G01X1275047D02*
X1274457D01*
G01X1276740D02*
X1276150D01*
G01X1278984D02*
X1278394D01*
G01X1280677D02*
X1280087D01*
G01X1282921D02*
X1282331D01*
G01X1284614D02*
X1284024D01*
G01X1286858D02*
X1286268D01*
G01X1288551D02*
X1287961D01*
G01X1290795D02*
X1290205D01*
G01X1292488D02*
X1291898D01*
G01X1294732D02*
X1294142D01*
G01X1296425D02*
X1295835D01*
G01X1298669D02*
X1298079D01*
G01X1300362D02*
X1299772D01*
G01X1302606D02*
X1302016D01*
G01X1304299D02*
X1303709D01*
G01X1306543D02*
X1305953D01*
G01X1308236D02*
X1307646D01*
G01X1267173Y587839D02*
X1264339D01*
G01X1271110D02*
X1268276D01*
G01X1275047D02*
X1272213D01*
G01X1278984D02*
X1276150D01*
G01X1282921D02*
X1280087D01*
G01X1286858D02*
X1284024D01*
G01X1290795D02*
X1287961D01*
G01X1294732D02*
X1291898D01*
G01X1298669D02*
X1295835D01*
G01X1302606D02*
X1299772D01*
G01X1306543D02*
X1303709D01*
G01X1310480D02*
X1307646D01*
G01X1270520Y587740D02*
X1268866D01*
G01X1278394D02*
X1276740D01*
G01X1286268D02*
X1284614D01*
G01X1294142D02*
X1292488D01*
G01X1302016D02*
X1300362D01*
G01Y587248D02*
X1302016D01*
G01X1292488D02*
X1294142D01*
G01X1284614D02*
X1286268D01*
G01X1276740D02*
X1278394D01*
G01X1268866D02*
X1270520D01*
G01X1307646Y586343D02*
X1310480D01*
G01X1303709D02*
X1306543D01*
G01X1299772D02*
X1302606D01*
G01X1295835D02*
X1298669D01*
G01X1291898D02*
X1294732D01*
G01X1287961D02*
X1290795D01*
G01X1284024D02*
X1286858D01*
G01X1280087D02*
X1282921D01*
G01X1276150D02*
X1278984D01*
G01X1272213D02*
X1275047D01*
G01X1268276D02*
X1271110D01*
G01X1264339D02*
X1267173D01*
G01X1300362Y585476D02*
X1302016D01*
G01X1292488D02*
X1294142D01*
G01X1284614D02*
X1286268D01*
G01X1276740D02*
X1278394D01*
G01X1268866D02*
X1270520D01*
G01X1303945Y585083D02*
X1306307D01*
G01X1300008D02*
X1302370D01*
G01X1296071D02*
X1298433D01*
G01X1266937D02*
X1264575D01*
G01X1270874D02*
X1268512D01*
G01X1274811D02*
X1272449D01*
G01X1278748D02*
X1276386D01*
G01X1282685D02*
X1280323D01*
G01X1286622D02*
X1284260D01*
G01X1290559D02*
X1288197D01*
G01X1294496D02*
X1292134D01*
G01X1270520Y584984D02*
X1268866D01*
G01X1278394D02*
X1276740D01*
G01X1286268D02*
X1284614D01*
G01X1294142D02*
X1292488D01*
G01X1302016D02*
X1300362D01*
G01X1270362Y584886D02*
X1269024D01*
G01X1278236D02*
X1276898D01*
G01X1286110D02*
X1284772D01*
G01X1293984D02*
X1292646D01*
G01X1301858D02*
X1300520D01*
G01X1303945Y583902D02*
X1306307D01*
G01X1300008D02*
X1302370D01*
G01X1296071D02*
X1298433D01*
G01X1292134D02*
X1294496D01*
G01X1288197D02*
X1290559D01*
G01X1284260D02*
X1286622D01*
G01X1280323D02*
X1282685D01*
G01X1276386D02*
X1278748D01*
G01X1272449D02*
X1274811D01*
G01X1268512D02*
X1270874D01*
G01X1264575D02*
X1266937D01*
G01X1304648Y605368D02*
X1304394Y605738D01*
G01X1304602Y604441D02*
X1304381Y604763D01*
G01X1300706Y605368D02*
X1300452Y605738D01*
G01X1300441Y604760D02*
X1300661Y604441D01*
G01X1296774Y605368D02*
X1296520Y605738D01*
G01X1296728Y604441D02*
X1296507Y604763D01*
G01X1305650Y589937D02*
X1305871Y589615D01*
G01X1305604Y589010D02*
X1305858Y588640D01*
G01X1292578Y605738D02*
X1292832Y605368D01*
G01X1292787Y604441D02*
X1292565Y604763D01*
G01X1301937Y589618D02*
X1301717Y589937D01*
G01X1301672Y589010D02*
X1301925Y588640D01*
G01X1288646Y605738D02*
X1288900Y605368D01*
G01X1288854Y604441D02*
X1288633Y604763D01*
G01X1297776Y589937D02*
X1297997Y589615D01*
G01X1297730Y589010D02*
X1297984Y588640D01*
G01X1284704Y605738D02*
X1284958Y605368D01*
G01X1284913Y604441D02*
X1284691Y604763D01*
G01X1293843Y589937D02*
X1294065Y589615D01*
G01X1294051Y588640D02*
X1293798Y589010D01*
G01X1280772Y605738D02*
X1281026Y605368D01*
G01X1280980Y604441D02*
X1280759Y604763D01*
G01X1289902Y589937D02*
X1290123Y589615D01*
G01X1290110Y588640D02*
X1289856Y589010D01*
G01X1276830Y605738D02*
X1277084Y605368D01*
G01X1277039Y604441D02*
X1276817Y604763D01*
G01X1285969Y589937D02*
X1286191Y589615D01*
G01X1286177Y588640D02*
X1285924Y589010D01*
G01X1272898Y605738D02*
X1273152Y605368D01*
G01X1273106Y604441D02*
X1272885Y604763D01*
G01X1282028Y589937D02*
X1282249Y589615D01*
G01X1282236Y588640D02*
X1281982Y589010D01*
G01X1268956Y605738D02*
X1269210Y605368D01*
G01X1269165Y604441D02*
X1268943Y604763D01*
G01X1304602Y604441D02*
X1304612Y604394D01*
G01X1278095Y589937D02*
X1278317Y589615D01*
G01X1278303Y588640D02*
X1278050Y589010D01*
G01X1265024Y605738D02*
X1265278Y605368D01*
G01X1265232Y604441D02*
X1265011Y604763D01*
G01X1274154Y589937D02*
X1274375Y589615D01*
G01X1274362Y588640D02*
X1274108Y589010D01*
G01X1270221Y589937D02*
X1270443Y589615D01*
G01X1270429Y588640D02*
X1270176Y589010D01*
G01X1266280Y589937D02*
X1266501Y589615D01*
G01X1266488Y588640D02*
X1266234Y589010D01*
G01X1262347Y589937D02*
X1262569Y589615D01*
G01X1262555Y588640D02*
X1262302Y589010D01*
G01X1305650Y589937D02*
X1305640Y589984D01*
G01X1300670Y604394D02*
X1300661Y604441D01*
G01X1301708Y589984D02*
X1301717Y589937D01*
G01X1296728Y604441D02*
X1296738Y604394D01*
G01X1297776Y589937D02*
X1297766Y589984D01*
G01X1292787Y604441D02*
X1292796Y604394D01*
G01X1293843Y589937D02*
X1293834Y589984D01*
G01X1288854Y604441D02*
X1288864Y604394D01*
G01X1289902Y589937D02*
X1289892Y589984D01*
G01X1284913Y604441D02*
X1284922Y604394D01*
G01X1285969Y589937D02*
X1285960Y589984D01*
G01X1280980Y604441D02*
X1280990Y604394D01*
G01X1306132Y589117D02*
X1305995Y595025D01*
G01X1305991Y594139D02*
X1306127Y588231D01*
G01X1305979Y600013D02*
X1305928Y600999D01*
G01X1305926Y600037D02*
X1305976Y599051D01*
G01X1304326Y594341D02*
X1304276Y595327D01*
G01X1304273Y594365D02*
X1304324Y593379D01*
G01X1302037Y600013D02*
X1301987Y600999D01*
G01X1301984Y600037D02*
X1302035Y599051D01*
G01X1282028Y589937D02*
X1282018Y589984D01*
G01X1277039Y604441D02*
X1277048Y604394D01*
G01X1278095Y589937D02*
X1278086Y589984D01*
G01X1273106Y604441D02*
X1273116Y604394D01*
G01X1274154Y589937D02*
X1274144Y589984D01*
G01X1269165Y604441D02*
X1269174Y604394D01*
G01X1270221Y589937D02*
X1270212Y589984D01*
G01X1265232Y604441D02*
X1265242Y604394D01*
G01X1266280Y589937D02*
X1266270Y589984D01*
G01X1262347Y589937D02*
X1262338Y589984D01*
G01X1305919Y593379D02*
X1305969Y594365D01*
G01X1305967Y595327D02*
X1305917Y594341D01*
G01X1304285Y599051D02*
X1304335Y600037D01*
G01X1304333Y600999D02*
X1304283Y600013D01*
G01X1301987Y593379D02*
X1302037Y594365D01*
G01X1302035Y595327D02*
X1301984Y594341D01*
G01X1300343Y599051D02*
X1300394Y600037D01*
G01X1300391Y600999D02*
X1300341Y600013D01*
G01X1298045Y593379D02*
X1298095Y594365D01*
G01X1298093Y595327D02*
X1298043Y594341D01*
G01X1296411Y599051D02*
X1296461Y600037D01*
G01X1296459Y600999D02*
X1296409Y600013D01*
G01X1294113Y593379D02*
X1294163Y594365D01*
G01X1294161Y595327D02*
X1294110Y594341D01*
G01X1292469Y599051D02*
X1292520Y600037D01*
G01X1292517Y600999D02*
X1292467Y600013D01*
G01X1306005Y599353D02*
X1306141Y605261D01*
G01X1306136Y606147D02*
X1306000Y600239D01*
G01X1304116Y588231D02*
X1304252Y594139D01*
G01X1304247Y595025D02*
X1304111Y589117D01*
G01X1302063Y599353D02*
X1302199Y605261D01*
G01X1302195Y606147D02*
X1302058Y600239D01*
G01X1300183Y588231D02*
X1300320Y594139D01*
G01X1300315Y595025D02*
X1300179Y589117D01*
G01X1298131Y599353D02*
X1298267Y605261D01*
G01X1298262Y606147D02*
X1298126Y600239D01*
G01X1296242Y588231D02*
X1296378Y594139D01*
G01X1296373Y595025D02*
X1296237Y589117D01*
G01X1294189Y599353D02*
X1294325Y605261D01*
G01X1294321Y606147D02*
X1294184Y600239D01*
G01X1292309Y588231D02*
X1292446Y594139D01*
G01X1292441Y595025D02*
X1292305Y589117D01*
G01X1290257Y599353D02*
X1290393Y605261D01*
G01X1290388Y606147D02*
X1290252Y600239D01*
G01X1288368Y588231D02*
X1288504Y594139D01*
G01X1288499Y595025D02*
X1288363Y589117D01*
G01X1305617Y589984D02*
X1305604Y589010D01*
G01X1304635Y604394D02*
X1304648Y605368D01*
G01X1301685Y589984D02*
X1301672Y589010D01*
G01X1300693Y604394D02*
X1300706Y605368D01*
G01X1297743Y589984D02*
X1297730Y589010D01*
G01X1296761Y604394D02*
X1296774Y605368D01*
G01X1293811Y589984D02*
X1293798Y589010D01*
G01X1292819Y604394D02*
X1292832Y605368D01*
G01X1289869Y589984D02*
X1289856Y589010D01*
G01X1288887Y604394D02*
X1288900Y605368D01*
G01X1285937Y589984D02*
X1285924Y589010D01*
G01X1307685Y588823D02*
Y587839D01*
G01Y606539D02*
Y605555D01*
G01X1307680Y606539D02*
Y605555D01*
G01X1307646Y590516D02*
Y586343D01*
G01Y608035D02*
Y603862D01*
G01X1306543D02*
Y608035D01*
G01Y586343D02*
Y590516D01*
G01X1306509Y606539D02*
Y605555D01*
G01X1306504Y588823D02*
Y587839D01*
G01X1306499Y588823D02*
Y587839D01*
G01X1306307Y589984D02*
Y583902D01*
G01Y610476D02*
Y604394D01*
G01X1306228Y587839D02*
Y606539D01*
G01X1306154Y606538D02*
Y605553D01*
G01X1306145Y588825D02*
Y587840D01*
G01X1305953Y601698D02*
Y606539D01*
G01Y587839D02*
Y592680D01*
G01X1305879Y604760D02*
Y605751D01*
G01X1305869Y588627D02*
Y589618D01*
G01X1305795Y592760D02*
Y591696D01*
G01Y602681D02*
Y601618D01*
G01X1305520D02*
Y602602D01*
G01Y592760D02*
Y591776D01*
G01X1304732Y601618D02*
Y602602D01*
G01Y592760D02*
Y591776D01*
G01X1304457Y592760D02*
Y591696D01*
G01Y602682D02*
Y601618D01*
G01X1304383Y605751D02*
Y604760D01*
G01X1304373Y589618D02*
Y588627D01*
G01X1304299Y601698D02*
Y606539D01*
G01Y587839D02*
Y592680D01*
G01X1304107Y605553D02*
Y606538D01*
G01X1304098Y587840D02*
Y588825D01*
G01X1304024Y606539D02*
Y587839D01*
G01X1303945Y589984D02*
Y583902D01*
G01Y610476D02*
Y604394D01*
G01X1303753Y606539D02*
Y605555D01*
G01X1303748Y606539D02*
Y605555D01*
G01X1303743Y588823D02*
Y587839D01*
G01X1303709Y590516D02*
Y586343D01*
G01Y608035D02*
Y603862D01*
G01X1302606D02*
Y608035D01*
G01Y586343D02*
Y590516D01*
G01X1302572Y588823D02*
Y587839D01*
G01X1302567Y588823D02*
Y587839D01*
G01Y606539D02*
Y605555D01*
G01X1302370Y589984D02*
Y583902D01*
G01Y610476D02*
Y604394D01*
G01X1302291Y587839D02*
Y606539D01*
G01X1302213Y588825D02*
Y587840D01*
G01Y606538D02*
Y605553D01*
G01X1302016Y605555D02*
Y610396D01*
G01Y583982D02*
Y588823D01*
G01X1301937Y604760D02*
Y605751D01*
G01Y588627D02*
Y589618D01*
G01X1301858Y584965D02*
Y583902D01*
G01Y610476D02*
Y609413D01*
G01X1301583Y583902D02*
Y584886D01*
G01Y610476D02*
Y609492D01*
G01X1300795Y584886D02*
Y583902D01*
G01Y610476D02*
Y609492D01*
G01X1300520Y584965D02*
Y583902D01*
G01Y610476D02*
Y609413D01*
G01X1300441Y589618D02*
Y588627D01*
G01Y605751D02*
Y604760D01*
G01X1300362Y605555D02*
Y610396D01*
G01Y583982D02*
Y588823D01*
G01X1300165Y587840D02*
Y588825D01*
G01Y605553D02*
Y606538D01*
G01X1300087Y606539D02*
Y587839D01*
G01X1300008Y589984D02*
Y583902D01*
G01Y610476D02*
Y604394D01*
G01X1299811Y588823D02*
Y587839D01*
G01Y606539D02*
Y605555D01*
G01X1299806Y606539D02*
Y605555D01*
G01X1299772Y590516D02*
Y586343D01*
G01Y608035D02*
Y603862D01*
G01X1298669D02*
Y608035D01*
G01Y586343D02*
Y590516D01*
G01X1298635Y606539D02*
Y605555D01*
G01X1298630Y588823D02*
Y587839D01*
G01X1298625Y588823D02*
Y587839D01*
G01X1298433Y589984D02*
Y583902D01*
G01Y610476D02*
Y604394D01*
G01X1298354Y587839D02*
Y606539D01*
G01X1298280Y606538D02*
Y605553D01*
G01X1298271Y588825D02*
Y587840D01*
G01X1298079Y601698D02*
Y606539D01*
G01Y587839D02*
Y592680D01*
G01X1298005Y604760D02*
Y605751D01*
G01X1297995Y588627D02*
Y589618D01*
G01X1297921Y592760D02*
Y591696D01*
G01Y602681D02*
Y601618D01*
G01X1297646D02*
Y602602D01*
G01Y592760D02*
Y591776D01*
G01X1296858Y601618D02*
Y602602D01*
G01Y592760D02*
Y591776D01*
G01X1296583Y592760D02*
Y591696D01*
G01Y602682D02*
Y601618D01*
G01X1296509Y605751D02*
Y604760D01*
G01X1296499Y589618D02*
Y588627D01*
G01X1296425Y601698D02*
Y606539D01*
G01Y587839D02*
Y592680D01*
G01X1296233Y605553D02*
Y606538D01*
G01X1296224Y587840D02*
Y588825D01*
G01X1296150Y606539D02*
Y587839D01*
G01X1296071Y589984D02*
Y583902D01*
G01Y610476D02*
Y604394D01*
G01X1295879Y606539D02*
Y605555D01*
G01X1295874Y606539D02*
Y605555D01*
G01X1295869Y588823D02*
Y587839D01*
G01X1295835Y590516D02*
Y586343D01*
G01Y608035D02*
Y603862D01*
G01X1294732D02*
Y608035D01*
G01Y586343D02*
Y590516D01*
G01X1294698Y588823D02*
Y587839D01*
G01X1294693Y588823D02*
Y587839D01*
G01Y606539D02*
Y605555D01*
G01X1294496Y589984D02*
Y583902D01*
G01Y610476D02*
Y604394D01*
G01X1294417Y587839D02*
Y606539D01*
G01X1294339Y588825D02*
Y587840D01*
G01Y606538D02*
Y605553D01*
G01X1294142Y605555D02*
Y610396D01*
G01Y583982D02*
Y588823D01*
G01X1294063Y604760D02*
Y605751D01*
G01Y588627D02*
Y589618D01*
G01X1293984Y584965D02*
Y583902D01*
G01Y610476D02*
Y609413D01*
G01X1293709Y584886D02*
Y583902D01*
G01Y610476D02*
Y609492D01*
G01X1292921D02*
Y610476D01*
G01Y584886D02*
Y583902D01*
G01X1292646Y584965D02*
Y583902D01*
G01Y610476D02*
Y609413D01*
G01X1292567Y589618D02*
Y588627D01*
G01Y605751D02*
Y604760D01*
G01X1292488Y605555D02*
Y610396D01*
G01Y583982D02*
Y588823D01*
G01X1292291Y587840D02*
Y588825D01*
G01Y605553D02*
Y606538D01*
G01X1292213Y606539D02*
Y587839D01*
G01X1292134Y589984D02*
Y583902D01*
G01Y610476D02*
Y604394D01*
G01X1291937Y588823D02*
Y587839D01*
G01Y606539D02*
Y605555D01*
G01X1291932Y606539D02*
Y605555D01*
G01X1291898Y590516D02*
Y586343D01*
G01Y608035D02*
Y603862D01*
G01X1290795D02*
Y608035D01*
G01Y586343D02*
Y590516D01*
G01X1290761Y606539D02*
Y605555D01*
G01X1290756Y588823D02*
Y587839D01*
G01X1290751Y588823D02*
Y587839D01*
G01X1290559Y589984D02*
Y583902D01*
G01Y610476D02*
Y604394D01*
G01X1290480Y587839D02*
Y606539D01*
G01X1290406Y606538D02*
Y605553D01*
G01X1290397Y588825D02*
Y587840D01*
G01X1290205Y601698D02*
Y606539D01*
G01Y587839D02*
Y592680D01*
G01X1290131Y604760D02*
Y605751D01*
G01X1290121Y588627D02*
Y589618D01*
G01X1290047Y592760D02*
Y591696D01*
G01Y602681D02*
Y601618D01*
G01X1289772Y592760D02*
Y591776D01*
G01Y602602D02*
Y601618D01*
G01X1288984Y592760D02*
Y591776D01*
G01Y602602D02*
Y601618D01*
G01X1288709Y592760D02*
Y591696D01*
G01Y602682D02*
Y601618D01*
G01X1288635Y605751D02*
Y604760D01*
G01X1288625Y589618D02*
Y588627D01*
G01X1288551Y601698D02*
Y606539D01*
G01Y587839D02*
Y592680D01*
G01X1288359Y605553D02*
Y606538D01*
G01X1288350Y587840D02*
Y588825D01*
G01X1288276Y606539D02*
Y587839D01*
G01X1288197Y589984D02*
Y583902D01*
G01Y610476D02*
Y604394D01*
G01X1288005Y606539D02*
Y605555D01*
G01X1288000Y606539D02*
Y605555D01*
G01X1287995Y588823D02*
Y587839D01*
G01X1287961Y590516D02*
Y586343D01*
G01Y608035D02*
Y603862D01*
G01X1286858D02*
Y608035D01*
G01Y586343D02*
Y590516D01*
G01X1286824Y588823D02*
Y587839D01*
G01X1286819Y588823D02*
Y587839D01*
G01Y606539D02*
Y605555D01*
G01X1286622Y589984D02*
Y583902D01*
G01Y610476D02*
Y604394D01*
G01X1286543Y587839D02*
Y606539D01*
G01X1286465Y588825D02*
Y587840D01*
G01Y606538D02*
Y605553D01*
G01X1286268Y605555D02*
Y610396D01*
G01Y583982D02*
Y588823D01*
G01X1286189Y604760D02*
Y605751D01*
G01Y588627D02*
Y589618D01*
G01X1286110Y584965D02*
Y583902D01*
G01Y610476D02*
Y609413D01*
G01X1285835Y584886D02*
Y583902D01*
G01Y610476D02*
Y609492D01*
G01X1285047D02*
Y610476D01*
G01Y584886D02*
Y583902D01*
G01X1284772Y584965D02*
Y583902D01*
G01Y610476D02*
Y609413D01*
G01X1284693Y589618D02*
Y588627D01*
G01Y605751D02*
Y604760D01*
G01X1284614Y605555D02*
Y610396D01*
G01Y583982D02*
Y588823D01*
G01X1284417Y605553D02*
Y606538D01*
G01Y587840D02*
Y588825D01*
G01X1284339Y606539D02*
Y587839D01*
G01X1284260Y589984D02*
Y583902D01*
G01Y610476D02*
Y604394D01*
G01X1305613Y605368D02*
X1305626Y604394D01*
G01X1304639Y589010D02*
X1304626Y589984D01*
G01X1301672Y605368D02*
X1301685Y604394D01*
G01X1300706Y589010D02*
X1300693Y589984D01*
G01X1297739Y605368D02*
X1297752Y604394D01*
G01X1296765Y589010D02*
X1296751Y589984D01*
G01X1293798Y605368D02*
X1293811Y604394D01*
G01X1292832Y589010D02*
X1292819Y589984D01*
G01X1289865Y605368D02*
X1289878Y604394D01*
G01X1288891Y589010D02*
X1288877Y589984D01*
G01X1285924Y605368D02*
X1285937Y604394D01*
G01X1284958Y589010D02*
X1284945Y589984D01*
G01X1304261Y600239D02*
X1304125Y606147D01*
G01X1304120Y605261D02*
X1304256Y599353D01*
G01X1302199Y589117D02*
X1302063Y595025D01*
G01X1302058Y594139D02*
X1302195Y588231D01*
G01X1300320Y600239D02*
X1300183Y606147D01*
G01X1300179Y605261D02*
X1300315Y599353D01*
G01X1298258Y589117D02*
X1298121Y595025D01*
G01X1298117Y594139D02*
X1298253Y588231D01*
G01X1296387Y600239D02*
X1296251Y606147D01*
G01X1296246Y605261D02*
X1296382Y599353D01*
G01X1294325Y589117D02*
X1294189Y595025D01*
G01X1294184Y594139D02*
X1294321Y588231D01*
G01X1292446Y600239D02*
X1292309Y606147D01*
G01X1292305Y605261D02*
X1292441Y599353D01*
G01X1290384Y589117D02*
X1290247Y595025D01*
G01X1290243Y594139D02*
X1290379Y588231D01*
G01X1288513Y600239D02*
X1288377Y606147D01*
G01X1288372Y605261D02*
X1288508Y599353D01*
G01X1286451Y589117D02*
X1286315Y595025D01*
G01X1286310Y594139D02*
X1286447Y588231D01*
G01X1284572Y600239D02*
X1284435Y606147D01*
G01X1284431Y605261D02*
X1284567Y599353D01*
G01X1282510Y589117D02*
X1282373Y595025D01*
G01X1282369Y594139D02*
X1282505Y588231D01*
G01X1300394Y594341D02*
X1300343Y595327D01*
G01X1300341Y594365D02*
X1300391Y593379D01*
G01X1298105Y600013D02*
X1298054Y600999D01*
G01X1298052Y600037D02*
X1298102Y599051D01*
G01X1296452Y594341D02*
X1296402Y595327D01*
G01X1296399Y594365D02*
X1296450Y593379D01*
G01X1294163Y600013D02*
X1294113Y600999D01*
G01X1294110Y600037D02*
X1294161Y599051D01*
G01X1292520Y594341D02*
X1292469Y595327D01*
G01X1292467Y594365D02*
X1292517Y593379D01*
G01X1290231Y600013D02*
X1290180Y600999D01*
G01X1290178Y600037D02*
X1290228Y599051D01*
G01X1288578Y594341D02*
X1288528Y595327D01*
G01X1288525Y594365D02*
X1288576Y593379D01*
G01X1286289Y600013D02*
X1286239Y600999D01*
G01X1286236Y600037D02*
X1286287Y599051D01*
G01X1284646Y594341D02*
X1284595Y595327D01*
G01X1284593Y594365D02*
X1284643Y593379D01*
G01X1282357Y600013D02*
X1282306Y600999D01*
G01X1282304Y600037D02*
X1282354Y599051D01*
G01X1280704Y594341D02*
X1280654Y595327D01*
G01X1280651Y594365D02*
X1280702Y593379D01*
G01X1278415Y600013D02*
X1278365Y600999D01*
G01X1278362Y600037D02*
X1278413Y599051D01*
G01X1304603Y589984D02*
X1304593Y589937D01*
G01X1305649Y604394D02*
X1305659Y604441D01*
G01X1300661Y589937D02*
X1300670Y589984D01*
G01X1301717Y604441D02*
X1301708Y604394D01*
G01X1296729Y589984D02*
X1296719Y589937D01*
G01X1297775Y604394D02*
X1297785Y604441D01*
G01X1292796Y589984D02*
X1292787Y589937D01*
G01X1293834Y604394D02*
X1293843Y604441D01*
G01X1288855Y589984D02*
X1288845Y589937D01*
G01X1289901Y604394D02*
X1289911Y604441D01*
G01X1290171Y593379D02*
X1290221Y594365D01*
G01X1290219Y595327D02*
X1290169Y594341D01*
G01X1288537Y599051D02*
X1288587Y600037D01*
G01X1288585Y600999D02*
X1288535Y600013D01*
G01X1286239Y593379D02*
X1286289Y594365D01*
G01X1286287Y595327D02*
X1286236Y594341D01*
G01X1284595Y599051D02*
X1284646Y600037D01*
G01X1284643Y600999D02*
X1284593Y600013D01*
G01X1282297Y593379D02*
X1282347Y594365D01*
G01X1282345Y595327D02*
X1282295Y594341D01*
G01X1280663Y599051D02*
X1280713Y600037D01*
G01X1280711Y600999D02*
X1280661Y600013D01*
G01X1278365Y593379D02*
X1278415Y594365D01*
G01X1278413Y595327D02*
X1278362Y594341D01*
G01X1276721Y599051D02*
X1276772Y600037D01*
G01X1276769Y600999D02*
X1276719Y600013D01*
G01X1274423Y593379D02*
X1274473Y594365D01*
G01X1274471Y595327D02*
X1274420Y594341D01*
G01X1272789Y599051D02*
X1272839Y600037D01*
G01X1272837Y600999D02*
X1272787Y600013D01*
G01X1270490Y593379D02*
X1270541Y594365D01*
G01X1270539Y595327D02*
X1270488Y594341D01*
G01X1268847Y599051D02*
X1268898Y600037D01*
G01X1268895Y600999D02*
X1268845Y600013D01*
G01X1266549Y593379D02*
X1266599Y594365D01*
G01X1286315Y599353D02*
X1286451Y605261D01*
G01X1286447Y606147D02*
X1286310Y600239D01*
G01X1284435Y588231D02*
X1284572Y594139D01*
G01X1284567Y595025D02*
X1284431Y589117D01*
G01X1282383Y599353D02*
X1282519Y605261D01*
G01X1282514Y606147D02*
X1282378Y600239D01*
G01X1280494Y588231D02*
X1280630Y594139D01*
G01X1280625Y595025D02*
X1280489Y589117D01*
G01X1278441Y599353D02*
X1278577Y605261D01*
G01X1278573Y606147D02*
X1278436Y600239D01*
G01X1276561Y588231D02*
X1276698Y594139D01*
G01X1276693Y595025D02*
X1276557Y589117D01*
G01X1274509Y599353D02*
X1274645Y605261D01*
G01X1274640Y606147D02*
X1274504Y600239D01*
G01X1272620Y588231D02*
X1272756Y594139D01*
G01X1272751Y595025D02*
X1272615Y589117D01*
G01X1270567Y599353D02*
X1270703Y605261D01*
G01X1270699Y606147D02*
X1270562Y600239D01*
G01X1268687Y588231D02*
X1268824Y594139D01*
G01X1268819Y595025D02*
X1268682Y589117D01*
G01X1266635Y599353D02*
X1266771Y605261D01*
G01X1266766Y606147D02*
X1266630Y600239D01*
G01X1264746Y588231D02*
X1264882Y594139D01*
G01X1264877Y595025D02*
X1264741Y589117D01*
G01X1284945Y604394D02*
X1284958Y605368D01*
G01X1281995Y589984D02*
X1281982Y589010D01*
G01X1281013Y604394D02*
X1281026Y605368D01*
G01X1278063Y589984D02*
X1278050Y589010D01*
G01X1277071Y604394D02*
X1277084Y605368D01*
G01X1274121Y589984D02*
X1274108Y589010D01*
G01X1273139Y604394D02*
X1273152Y605368D01*
G01X1270189Y589984D02*
X1270176Y589010D01*
G01X1269197Y604394D02*
X1269210Y605368D01*
G01X1266247Y589984D02*
X1266234Y589010D01*
G01X1265265Y604394D02*
X1265278Y605368D01*
G01X1262315Y589984D02*
X1262302Y589010D01*
G01X1284063Y588823D02*
Y587839D01*
G01Y606539D02*
Y605555D01*
G01X1284058Y606539D02*
Y605555D01*
G01X1284024Y590516D02*
Y586343D01*
G01Y608035D02*
Y603862D01*
G01X1282921D02*
Y608035D01*
G01Y586343D02*
Y590516D01*
G01X1282887Y606539D02*
Y605555D01*
G01X1282882Y588823D02*
Y587839D01*
G01X1282877Y588823D02*
Y587839D01*
G01X1282685Y589984D02*
Y583902D01*
G01Y610476D02*
Y604394D01*
G01X1282606Y587839D02*
Y606539D01*
G01X1282532Y606538D02*
Y605553D01*
G01X1282523Y588825D02*
Y587840D01*
G01X1282331Y601698D02*
Y606539D01*
G01Y587839D02*
Y592680D01*
G01X1282257Y604760D02*
Y605751D01*
G01X1282247Y588627D02*
Y589618D01*
G01X1282173Y592760D02*
Y591696D01*
G01Y602681D02*
Y601618D01*
G01X1281898D02*
Y602602D01*
G01Y592760D02*
Y591776D01*
G01X1281110Y601618D02*
Y602602D01*
G01Y591776D02*
Y592760D01*
G01X1280835D02*
Y591696D01*
G01Y602682D02*
Y601618D01*
G01X1280761Y605751D02*
Y604760D01*
G01X1280751Y589618D02*
Y588627D01*
G01X1280677Y601698D02*
Y606539D01*
G01Y587839D02*
Y592680D01*
G01X1280485Y605553D02*
Y606538D01*
G01X1280476Y587840D02*
Y588825D01*
G01X1280402Y606539D02*
Y587839D01*
G01X1280323Y589984D02*
Y583902D01*
G01Y610476D02*
Y604394D01*
G01X1280131Y606539D02*
Y605555D01*
G01X1280126Y606539D02*
Y605555D01*
G01X1280121Y588823D02*
Y587839D01*
G01X1280087Y590516D02*
Y586343D01*
G01Y608035D02*
Y603862D01*
G01X1278984D02*
Y608035D01*
G01Y586343D02*
Y590516D01*
G01X1278950Y588823D02*
Y587839D01*
G01X1278945Y588823D02*
Y587839D01*
G01Y606539D02*
Y605555D01*
G01X1278748Y589984D02*
Y583902D01*
G01Y610476D02*
Y604394D01*
G01X1278669Y587839D02*
Y606539D01*
G01X1278591Y588825D02*
Y587840D01*
G01Y606538D02*
Y605553D01*
G01X1278394Y605555D02*
Y610396D01*
G01Y583982D02*
Y588823D01*
G01X1278315Y604760D02*
Y605751D01*
G01Y588627D02*
Y589618D01*
G01X1278236Y584965D02*
Y583902D01*
G01Y610476D02*
Y609413D01*
G01X1277961Y584886D02*
Y583902D01*
G01Y610476D02*
Y609492D01*
G01X1277173D02*
Y610476D01*
G01Y584886D02*
Y583902D01*
G01X1276898Y584965D02*
Y583902D01*
G01Y610476D02*
Y609413D01*
G01X1276819Y589618D02*
Y588627D01*
G01Y605751D02*
Y604760D01*
G01X1276740Y605555D02*
Y610396D01*
G01Y583982D02*
Y588823D01*
G01X1276543Y587840D02*
Y588825D01*
G01Y605553D02*
Y606538D01*
G01X1276465Y606539D02*
Y587839D01*
G01X1276386Y589984D02*
Y583902D01*
G01Y610476D02*
Y604394D01*
G01X1276189Y588823D02*
Y587839D01*
G01Y606539D02*
Y605555D01*
G01X1276184Y606539D02*
Y605555D01*
G01X1276150Y590516D02*
Y586343D01*
G01Y608035D02*
Y603862D01*
G01X1275047D02*
Y608035D01*
G01Y586343D02*
Y590516D01*
G01X1275013Y606539D02*
Y605555D01*
G01X1275008Y588823D02*
Y587839D01*
G01X1275003Y588823D02*
Y587839D01*
G01X1274811Y589984D02*
Y583902D01*
G01Y610476D02*
Y604394D01*
G01X1274732Y587839D02*
Y606539D01*
G01X1274658Y606538D02*
Y605553D01*
G01X1274649Y588825D02*
Y587840D01*
G01X1274457Y601698D02*
Y606539D01*
G01Y587839D02*
Y592680D01*
G01X1274383Y604760D02*
Y605751D01*
G01X1274373Y588627D02*
Y589618D01*
G01X1274299Y592760D02*
Y591696D01*
G01Y602681D02*
Y601618D01*
G01X1274024D02*
Y602602D01*
G01Y592760D02*
Y591776D01*
G01X1273236Y601618D02*
Y602602D01*
G01Y591776D02*
Y592760D01*
G01X1272961D02*
Y591696D01*
G01Y602682D02*
Y601618D01*
G01X1272887Y605751D02*
Y604760D01*
G01X1272877Y589618D02*
Y588627D01*
G01X1272803Y601698D02*
Y606539D01*
G01Y587839D02*
Y592680D01*
G01X1272611Y605553D02*
Y606538D01*
G01X1272602Y587840D02*
Y588825D01*
G01X1272528Y606539D02*
Y587839D01*
G01X1272449Y589984D02*
Y583902D01*
G01Y610476D02*
Y604394D01*
G01X1272257Y606539D02*
Y605555D01*
G01X1272252Y606539D02*
Y605555D01*
G01X1272247Y588823D02*
Y587839D01*
G01X1272213Y590516D02*
Y586343D01*
G01Y608035D02*
Y603862D01*
G01X1271110D02*
Y608035D01*
G01Y586343D02*
Y590516D01*
G01X1271076Y588823D02*
Y587839D01*
G01X1271071Y588823D02*
Y587839D01*
G01Y606539D02*
Y605555D01*
G01X1270874Y589984D02*
Y583902D01*
G01Y610476D02*
Y604394D01*
G01X1270795Y587839D02*
Y606539D01*
G01X1270717Y588825D02*
Y587840D01*
G01Y606538D02*
Y605553D01*
G01X1270520Y605555D02*
Y610396D01*
G01Y583982D02*
Y588823D01*
G01X1270441Y604760D02*
Y605751D01*
G01Y588627D02*
Y589618D01*
G01X1270362Y584965D02*
Y583902D01*
G01Y610476D02*
Y609413D01*
G01X1270087Y584886D02*
Y583902D01*
G01Y610476D02*
Y609492D01*
G01X1269299D02*
Y610476D01*
G01Y584886D02*
Y583902D01*
G01X1269024Y584965D02*
Y583902D01*
G01Y610476D02*
Y609413D01*
G01X1268945Y589618D02*
Y588627D01*
G01Y605751D02*
Y604760D01*
G01X1268866Y605555D02*
Y610396D01*
G01Y583982D02*
Y588823D01*
G01X1268669Y587840D02*
Y588825D01*
G01Y605553D02*
Y606538D01*
G01X1268591Y606539D02*
Y587839D01*
G01X1268512Y589984D02*
Y583902D01*
G01Y610476D02*
Y604394D01*
G01X1268315Y588823D02*
Y587839D01*
G01Y606539D02*
Y605555D01*
G01X1268310Y606539D02*
Y605555D01*
G01X1268276Y590516D02*
Y586343D01*
G01Y608035D02*
Y603862D01*
G01X1267173D02*
Y608035D01*
G01Y586343D02*
Y590516D01*
G01X1267139Y606539D02*
Y605555D01*
G01X1267134Y588823D02*
Y587839D01*
G01X1267129Y588823D02*
Y587839D01*
G01X1266937Y589984D02*
Y583902D01*
G01Y610476D02*
Y604394D01*
G01X1266858Y587839D02*
Y606539D01*
G01X1266784Y606538D02*
Y605553D01*
G01X1266775Y588825D02*
Y587840D01*
G01X1266583Y601698D02*
Y606539D01*
G01Y587839D02*
Y592680D01*
G01X1266509Y604760D02*
Y605751D01*
G01X1266499Y588627D02*
Y589618D01*
G01X1266425Y592760D02*
Y591696D01*
G01Y602681D02*
Y601618D01*
G01X1266150Y592760D02*
Y591776D01*
G01Y602602D02*
Y601618D01*
G01X1265362Y592760D02*
Y591776D01*
G01Y602602D02*
Y601618D01*
G01X1265087Y592760D02*
Y591696D01*
G01Y602682D02*
Y601618D01*
G01X1265013Y605751D02*
Y604760D01*
G01X1265003Y589618D02*
Y588627D01*
G01X1264929Y601698D02*
Y606539D01*
G01Y587839D02*
Y592680D01*
G01X1264737Y605553D02*
Y606538D01*
G01X1264728Y587840D02*
Y588825D01*
G01X1264654Y606539D02*
Y587839D01*
G01X1264575Y589984D02*
Y583902D01*
G01Y610476D02*
Y604394D01*
G01X1264383Y606539D02*
Y605555D01*
G01X1264378Y606539D02*
Y605555D01*
G01X1264373Y588823D02*
Y587839D01*
G01X1264339Y590516D02*
Y586343D01*
G01Y608035D02*
Y603862D01*
G01X1263236D02*
Y608035D01*
G01Y586343D02*
Y590516D01*
G01X1263202Y588823D02*
Y587839D01*
G01X1263197Y588823D02*
Y587839D01*
G01Y606539D02*
Y605555D01*
G01X1263000Y589984D02*
Y583902D01*
G01Y610476D02*
Y604394D01*
G01X1262921Y587839D02*
Y606539D01*
G01X1262843Y588825D02*
Y587840D01*
G01Y606538D02*
Y605553D01*
G01X1262646Y605555D02*
Y610396D01*
G01Y583982D02*
Y588823D01*
G01X1262567Y604760D02*
Y605751D01*
G01Y588627D02*
Y589618D01*
G01X1262488Y584965D02*
Y583902D01*
G01Y610476D02*
Y609413D01*
G01X1262213Y584886D02*
Y583902D01*
G01Y610476D02*
Y609492D01*
G01X1281991Y605368D02*
X1282004Y604394D01*
G01X1281017Y589010D02*
X1281003Y589984D01*
G01X1278050Y605368D02*
X1278063Y604394D01*
G01X1277084Y589010D02*
X1277071Y589984D01*
G01X1274117Y605368D02*
X1274130Y604394D01*
G01X1273143Y589010D02*
X1273129Y589984D01*
G01X1270176Y605368D02*
X1270189Y604394D01*
G01X1269210Y589010D02*
X1269197Y589984D01*
G01X1266243Y605368D02*
X1266256Y604394D01*
G01X1265269Y589010D02*
X1265255Y589984D01*
G01X1262302Y605368D02*
X1262315Y604394D01*
G01X1280639Y600239D02*
X1280503Y606147D01*
G01X1280498Y605261D02*
X1280634Y599353D01*
G01X1278577Y589117D02*
X1278441Y595025D01*
G01X1278436Y594139D02*
X1278573Y588231D01*
G01X1276698Y600239D02*
X1276561Y606147D01*
G01X1276557Y605261D02*
X1276693Y599353D01*
G01X1274636Y589117D02*
X1274499Y595025D01*
G01X1274495Y594139D02*
X1274631Y588231D01*
G01X1272765Y600239D02*
X1272629Y606147D01*
G01X1272624Y605261D02*
X1272760Y599353D01*
G01X1270703Y589117D02*
X1270567Y595025D01*
G01X1270562Y594139D02*
X1270699Y588231D01*
G01X1268824Y600239D02*
X1268687Y606147D01*
G01X1268682Y605261D02*
X1268819Y599353D01*
G01X1266762Y589117D02*
X1266625Y595025D01*
G01X1266621Y594139D02*
X1266757Y588231D01*
G01X1264891Y600239D02*
X1264755Y606147D01*
G01X1264750Y605261D02*
X1264886Y599353D01*
G01X1262829Y589117D02*
X1262693Y595025D01*
G01X1262688Y594139D02*
X1262825Y588231D01*
G01X1276772Y594341D02*
X1276721Y595327D01*
G01X1276719Y594365D02*
X1276769Y593379D01*
G01X1274483Y600013D02*
X1274432Y600999D01*
G01X1274430Y600037D02*
X1274480Y599051D01*
G01X1272830Y594341D02*
X1272780Y595327D01*
G01X1272777Y594365D02*
X1272828Y593379D01*
G01X1270541Y600013D02*
X1270490Y600999D01*
G01X1270488Y600037D02*
X1270539Y599051D01*
G01X1268898Y594341D02*
X1268847Y595327D01*
G01X1268845Y594365D02*
X1268895Y593379D01*
G01X1266609Y600013D02*
X1266558Y600999D01*
G01X1266556Y600037D02*
X1266606Y599051D01*
G01X1264956Y594341D02*
X1264905Y595327D01*
G01X1264903Y594365D02*
X1264954Y593379D01*
G01X1262667Y600013D02*
X1262616Y600999D01*
G01X1262614Y600037D02*
X1262665Y599051D01*
G01X1284922Y589984D02*
X1284913Y589937D01*
G01X1285960Y604394D02*
X1285969Y604441D01*
G01X1280981Y589984D02*
X1280971Y589937D01*
G01X1282027Y604394D02*
X1282037Y604441D01*
G01X1277048Y589984D02*
X1277039Y589937D01*
G01X1278086Y604394D02*
X1278095Y604441D01*
G01X1273107Y589984D02*
X1273097Y589937D01*
G01X1274153Y604394D02*
X1274163Y604441D01*
G01X1269174Y589984D02*
X1269165Y589937D01*
G01X1270212Y604394D02*
X1270221Y604441D01*
G01X1265233Y589984D02*
X1265223Y589937D01*
G01X1266279Y604394D02*
X1266289Y604441D01*
G01X1266597Y595327D02*
X1266546Y594341D01*
G01X1264915Y599051D02*
X1264965Y600037D01*
G01X1264963Y600999D02*
X1264912Y600013D01*
G01X1262616Y593379D02*
X1262667Y594365D01*
G01X1262665Y595327D02*
X1262614Y594341D01*
G01X1262693Y599353D02*
X1262829Y605261D01*
G01X1262825Y606147D02*
X1262688Y600239D01*
G01X1304385Y588640D02*
X1304639Y589010D01*
G01X1304372Y589615D02*
X1304593Y589937D01*
G01X1300452Y588640D02*
X1300706Y589010D01*
G01X1300661Y589937D02*
X1300441Y589618D01*
G01X1296511Y588640D02*
X1296765Y589010D01*
G01X1296498Y589615D02*
X1296719Y589937D01*
G01X1305880Y604763D02*
X1305659Y604441D01*
G01X1305867Y605738D02*
X1305613Y605368D01*
G01X1292578Y588640D02*
X1292832Y589010D01*
G01X1292565Y589615D02*
X1292787Y589937D01*
G01X1301717Y604441D02*
X1301937Y604760D01*
G01X1301925Y605738D02*
X1301672Y605368D01*
G01X1288637Y588640D02*
X1288891Y589010D01*
G01X1288624Y589615D02*
X1288845Y589937D01*
G01X1298006Y604763D02*
X1297785Y604441D01*
G01X1297993Y605738D02*
X1297739Y605368D01*
G01X1284704Y588640D02*
X1284958Y589010D01*
G01X1284691Y589615D02*
X1284913Y589937D01*
G01X1294065Y604763D02*
X1293843Y604441D01*
G01X1294051Y605738D02*
X1293798Y605368D01*
G01X1280763Y588640D02*
X1281017Y589010D01*
G01X1280750Y589615D02*
X1280971Y589937D01*
G01X1262338Y604394D02*
X1262347Y604441D01*
G01X1290132Y604763D02*
X1289911Y604441D01*
G01X1290119Y605738D02*
X1289865Y605368D01*
G01X1276830Y588640D02*
X1277084Y589010D01*
G01X1276817Y589615D02*
X1277039Y589937D01*
G01X1286191Y604763D02*
X1285969Y604441D01*
G01X1286177Y605738D02*
X1285924Y605368D01*
G01X1272889Y588640D02*
X1273143Y589010D01*
G01X1272876Y589615D02*
X1273097Y589937D01*
G01X1282258Y604763D02*
X1282037Y604441D01*
G01X1282245Y605738D02*
X1281991Y605368D01*
G01X1268956Y588640D02*
X1269210Y589010D01*
G01X1268943Y589615D02*
X1269165Y589937D01*
G01X1278317Y604763D02*
X1278095Y604441D01*
G01X1278303Y605738D02*
X1278050Y605368D01*
G01X1265015Y588640D02*
X1265269Y589010D01*
G01X1265002Y589615D02*
X1265223Y589937D01*
G01X1274384Y604763D02*
X1274163Y604441D01*
G01X1274371Y605738D02*
X1274117Y605368D01*
G01X1270443Y604763D02*
X1270221Y604441D01*
G01X1270429Y605738D02*
X1270176Y605368D01*
G01X1266510Y604763D02*
X1266289Y604441D01*
G01X1266497Y605738D02*
X1266243Y605368D01*
G01X1262569Y604763D02*
X1262347Y604441D01*
G01X1262555Y605738D02*
X1262302Y605368D01*
G01X1246848Y771870D02*
X1247397Y771345D01*
X1248023Y771135D01*
X1248650Y771345D01*
X1249198Y771975D01*
X1249590Y772920D01*
X1249747Y773865D01*
Y775020D01*
X1249590Y775965D01*
X1249198Y776805D01*
X1248728Y777225D01*
X1248180Y777435D01*
X1247553Y777225D01*
X1247083Y776805D01*
X1246770Y776175D01*
X1246613Y775335D01*
X1246770Y774600D01*
X1247162Y773865D01*
X1247632Y773445D01*
X1248180Y773340D01*
X1248807Y773550D01*
X1249277Y774075D01*
X1249747Y775020D01*
G01X1327444Y-578426D02*
Y-595749D01*
G01X1340455Y-493350D02*
Y-472291D01*
X1345719D01*
X1347825Y-473344D01*
X1349405Y-474748D01*
X1350721Y-476853D01*
X1351774Y-479311D01*
X1352037Y-482821D01*
X1351774Y-486331D01*
X1350721Y-488788D01*
X1349405Y-490894D01*
X1347825Y-492297D01*
X1345719Y-493350D01*
X1340455D01*
G01X1372043D02*
Y-479311D01*
G01Y-481767D02*
X1370990Y-480364D01*
X1369411Y-479662D01*
X1367568Y-479311D01*
X1365726Y-480013D01*
X1364146Y-481417D01*
X1363093Y-483523D01*
X1362567Y-486331D01*
X1363093Y-489138D01*
X1364146Y-491245D01*
X1365726Y-492648D01*
X1367568Y-493350D01*
X1369411Y-492999D01*
X1370990Y-491946D01*
X1372043Y-490543D01*
G01X1388364Y-472291D02*
Y-493350D01*
G01X1384679Y-479311D02*
X1392049D01*
G01X1405475Y-483874D02*
X1413898D01*
X1413108Y-481417D01*
X1411792Y-480013D01*
X1409950Y-479311D01*
X1408107Y-479662D01*
X1406527Y-480715D01*
X1405475Y-483172D01*
X1404948Y-485278D01*
Y-487383D01*
X1405475Y-489489D01*
X1406791Y-491595D01*
X1408370Y-492999D01*
X1410213Y-493350D01*
X1412055Y-492648D01*
X1413898Y-490543D01*
G01X1317786Y-229732D02*
X1319735D01*
G01X1317786Y-238393D02*
Y-229732D01*
G01X1319735Y-238393D02*
X1317786D01*
G01X1311940Y-229732D02*
Y-238393D01*
G01X1325581Y-229732D02*
X1329479D01*
G01X1325581Y-238393D02*
Y-229732D01*
G01X1329479Y-238393D02*
X1325581D01*
G01X1320709Y-230453D02*
X1321684Y-231897D01*
G01X1319735Y-229732D02*
X1320709Y-230453D01*
G01Y-237671D02*
X1319735Y-238393D01*
G01X1321197Y-236949D02*
X1320709Y-237671D01*
G01X1321684Y-236228D02*
X1321197Y-236949D01*
G01X1322171Y-234062D02*
X1321684Y-236228D01*
G01Y-231897D02*
X1322171Y-234062D01*
G01X1325581D02*
X1328017D01*
G01X1317001Y-153033D02*
Y-164057D01*
G01X1316017D02*
Y-153033D01*
G01X1313851D02*
Y-164057D01*
G01X1312867D02*
Y-153033D01*
G01X1310702D02*
Y-164057D01*
G01X1309717D02*
Y-153033D01*
G01X1317001Y-164057D02*
X1319166D01*
G01X1313851D02*
X1316017D01*
G01X1310702D02*
X1312867D01*
G01Y-153033D02*
X1310702D01*
G01X1316017D02*
X1313851D01*
G01X1319166D02*
X1317001D01*
G01X1379973Y-167994D02*
X1381942Y-166026D01*
G01X1379973Y-167994D02*
X1381942Y-166026D01*
G01D02*
Y-137285D01*
G01Y-166026D02*
Y-137285D01*
G01X1379009Y-164057D02*
Y-153033D01*
G01X1376843D02*
Y-164057D01*
G01X1375859D02*
Y-153033D01*
G01X1373694D02*
Y-164057D01*
G01X1372710D02*
Y-153033D01*
G01X1370544D02*
Y-164057D01*
G01X1369560D02*
Y-153033D01*
G01X1367395D02*
Y-164057D01*
G01X1366410D02*
Y-153033D01*
G01X1364245D02*
Y-164057D01*
G01X1363261D02*
Y-153033D01*
G01X1361095D02*
Y-164057D01*
G01X1360111D02*
Y-153033D01*
G01X1357946D02*
Y-164057D01*
G01X1356962D02*
Y-153033D01*
G01X1354796D02*
Y-164057D01*
G01X1353812D02*
Y-153033D01*
G01X1351647D02*
Y-164057D01*
G01X1350662D02*
Y-153033D01*
G01X1348497D02*
Y-164057D01*
G01X1347513D02*
Y-153033D01*
G01X1345347D02*
Y-164057D01*
G01X1344363D02*
Y-153033D01*
G01X1342198D02*
Y-164057D01*
G01X1341214D02*
Y-153033D01*
G01X1339048D02*
Y-164057D01*
G01X1338064D02*
Y-153033D01*
G01X1335899D02*
Y-164057D01*
G01X1334914D02*
Y-153033D01*
G01X1332749D02*
Y-164057D01*
G01X1331765D02*
Y-153033D01*
G01X1329599D02*
Y-164057D01*
G01X1328615D02*
Y-153033D01*
G01X1326450D02*
Y-164057D01*
G01X1325466D02*
Y-153033D01*
G01X1323300D02*
Y-164057D01*
G01X1322316D02*
Y-153033D01*
G01X1320151D02*
Y-164057D01*
G01X1319166D02*
Y-153033D01*
G01X1376843Y-164057D02*
X1379009D01*
G01X1373694D02*
X1375859D01*
G01X1370544D02*
X1372710D01*
G01X1367395D02*
X1369560D01*
G01X1364245D02*
X1366410D01*
G01X1361095D02*
X1363261D01*
G01X1357946D02*
X1360111D01*
G01X1354796D02*
X1356962D01*
G01X1351647D02*
X1353812D01*
G01X1348497D02*
X1350662D01*
G01X1345347D02*
X1347513D01*
G01X1342198D02*
X1344363D01*
G01X1339048D02*
X1341214D01*
G01X1335899D02*
X1338064D01*
G01X1332749D02*
X1334914D01*
G01X1329599D02*
X1331765D01*
G01X1326450D02*
X1328615D01*
G01X1323300D02*
X1325466D01*
G01X1320151D02*
X1322316D01*
G01X1377491Y-152284D02*
X1377540Y-152259D01*
G01X1378795Y-152824D02*
X1378856Y-152786D01*
G01X1378253Y-152824D02*
X1378315Y-152786D01*
G01X1378647Y-152259D02*
X1378586Y-152296D01*
G01X1378106Y-152259D02*
X1378044Y-152296D01*
G01X1378782Y-152761D02*
X1378819Y-152736D01*
G01X1378241Y-152761D02*
X1378278Y-152736D01*
G01X1378659Y-152321D02*
X1378622Y-152347D01*
G01X1378118Y-152321D02*
X1378081Y-152347D01*
G01X1377552Y-152321D02*
X1377515Y-152347D01*
G01X1377269Y-152522D02*
X1377220Y-152560D01*
G01X1377823Y-152497D02*
X1377515Y-152774D01*
G01X1377417D02*
X1377761Y-152460D01*
G01X1378856Y-152786D02*
X1378893Y-152749D01*
G01X1378315Y-152786D02*
X1378352Y-152749D01*
G01X1378586Y-152296D02*
X1378549Y-152334D01*
G01X1378044Y-152296D02*
X1378007Y-152334D01*
G01X1377441D02*
X1377491Y-152284D01*
G01X1377208Y-152485D02*
X1377232Y-152460D01*
G01X1377171Y-152497D02*
X1377208Y-152485D01*
G01X1377306Y-152472D02*
X1377269Y-152522D01*
G01X1378819Y-152736D02*
X1378869Y-152661D01*
G01X1378622Y-152347D02*
X1378573Y-152422D01*
G01X1378278Y-152736D02*
X1378327Y-152661D01*
G01X1378081Y-152347D02*
X1378032Y-152422D01*
G01X1377847Y-152460D02*
X1377823Y-152497D01*
G01X1377515Y-152347D02*
X1377491Y-152384D01*
G01X1378893Y-152749D02*
X1378918Y-152698D01*
G01X1378352Y-152749D02*
X1378376Y-152698D01*
G01X1378549Y-152334D02*
X1378524Y-152384D01*
G01X1378007Y-152334D02*
X1377983Y-152384D01*
G01X1377761Y-152460D02*
X1377786Y-152409D01*
G01X1378918Y-152698D02*
X1378930Y-152661D01*
G01X1378524Y-152384D02*
X1378512Y-152422D01*
G01X1378376Y-152698D02*
X1378389Y-152661D01*
G01X1377983Y-152384D02*
X1377970Y-152422D01*
G01X1377318Y-152435D02*
X1377306Y-152472D01*
G01X1377232Y-152460D02*
X1377245Y-152422D01*
G01X1377860Y-152409D02*
X1377847Y-152460D01*
G01X1377429Y-152384D02*
X1377441Y-152334D01*
G01X1378930Y-152661D02*
X1378942Y-152598D01*
G01X1378512Y-152422D02*
X1378499Y-152485D01*
G01X1378389Y-152661D02*
X1378401Y-152598D01*
G01X1377970Y-152422D02*
X1377958Y-152485D01*
G01X1378869Y-152661D02*
X1378881Y-152585D01*
G01X1378573Y-152422D02*
X1378561Y-152497D01*
G01X1378327Y-152661D02*
X1378340Y-152585D01*
G01X1378032Y-152422D02*
X1378020Y-152497D01*
G01X1378942Y-152598D02*
Y-152485D01*
G01X1378881Y-152585D02*
Y-152497D01*
G01X1378561D02*
Y-152585D01*
G01X1378499Y-152485D02*
Y-152598D01*
G01X1378401D02*
Y-152485D01*
G01X1378340Y-152585D02*
Y-152497D01*
G01X1378020D02*
Y-152585D01*
G01X1377958Y-152485D02*
Y-152598D01*
G01X1377860Y-152774D02*
Y-152837D01*
G01Y-152384D02*
Y-152409D01*
G01X1377786D02*
Y-152384D01*
G01X1377417Y-152837D02*
Y-152774D01*
G01X1377318Y-152384D02*
Y-152435D01*
G01X1377245Y-152422D02*
Y-152384D01*
G01X1376937Y-152309D02*
Y-152497D01*
G01Y-152573D02*
Y-152837D01*
G01X1376863D02*
Y-152246D01*
G01X1378881Y-152497D02*
X1378869Y-152422D01*
G01X1378561Y-152585D02*
X1378573Y-152661D01*
G01X1378340Y-152497D02*
X1378327Y-152422D01*
G01X1378020Y-152585D02*
X1378032Y-152661D01*
G01X1378942Y-152485D02*
X1378930Y-152422D01*
G01X1378499Y-152598D02*
X1378512Y-152661D01*
G01X1378401Y-152485D02*
X1378389Y-152422D01*
G01X1377958Y-152598D02*
X1377970Y-152661D01*
G01X1377847Y-152334D02*
X1377860Y-152384D01*
G01X1378930Y-152422D02*
X1378918Y-152384D01*
G01X1378512Y-152661D02*
X1378524Y-152698D01*
G01X1378389Y-152422D02*
X1378376Y-152384D01*
G01X1377970Y-152661D02*
X1377983Y-152698D01*
G01X1377306Y-152347D02*
X1377318Y-152384D01*
G01X1377245D02*
X1377232Y-152347D01*
G01X1378918Y-152384D02*
X1378893Y-152334D01*
G01X1378376Y-152384D02*
X1378352Y-152334D01*
G01X1378524Y-152698D02*
X1378549Y-152749D01*
G01X1377983Y-152698D02*
X1378007Y-152749D01*
G01X1378869Y-152422D02*
X1378819Y-152347D01*
G01X1378573Y-152661D02*
X1378622Y-152736D01*
G01X1378327Y-152422D02*
X1378278Y-152347D01*
G01X1378032Y-152661D02*
X1378081Y-152736D01*
G01X1377786Y-152384D02*
X1377761Y-152347D01*
G01X1377269Y-152296D02*
X1377306Y-152347D01*
G01X1378893Y-152334D02*
X1378856Y-152296D01*
G01X1378352Y-152334D02*
X1378315Y-152296D01*
G01X1378549Y-152749D02*
X1378586Y-152786D01*
G01X1377798Y-152284D02*
X1377847Y-152334D01*
G01X1378007Y-152749D02*
X1378044Y-152786D01*
G01X1377232Y-152347D02*
X1377208Y-152321D01*
G01X1377220Y-152259D02*
X1377269Y-152296D01*
G01X1378819Y-152347D02*
X1378782Y-152321D01*
G01X1378278Y-152347D02*
X1378241Y-152321D01*
G01X1378622Y-152736D02*
X1378659Y-152761D01*
G01X1377761Y-152347D02*
X1377724Y-152321D01*
G01X1378081Y-152736D02*
X1378118Y-152761D01*
G01X1378856Y-152296D02*
X1378795Y-152259D01*
G01X1378315Y-152296D02*
X1378253Y-152259D01*
G01X1378586Y-152786D02*
X1378647Y-152824D01*
G01X1378044Y-152786D02*
X1378106Y-152824D01*
G01X1377749Y-152259D02*
X1377798Y-152284D01*
G01X1377208Y-152321D02*
X1377171Y-152309D01*
G01X1378782Y-152321D02*
X1378721Y-152309D01*
G01X1378241Y-152321D02*
X1378180Y-152309D01*
G01X1377724Y-152321D02*
X1377663Y-152309D01*
G01X1377158Y-152246D02*
X1377220Y-152259D01*
G01X1378659Y-152761D02*
X1378721Y-152774D01*
G01X1378118Y-152761D02*
X1378180Y-152774D01*
G01X1378795Y-152259D02*
X1378721Y-152246D01*
G01X1378253Y-152259D02*
X1378180Y-152246D01*
G01X1377675D02*
X1377749Y-152259D01*
G01X1378647Y-152824D02*
X1378721Y-152837D01*
G01X1378106Y-152824D02*
X1378180Y-152837D01*
G01X1377626Y-152246D02*
X1377675D01*
G01X1376863D02*
X1377158D01*
G01X1377663Y-152309D02*
X1377614D01*
G01X1377171D02*
X1376937D01*
G01X1377491Y-152384D02*
X1377429D01*
G01X1376937Y-152497D02*
X1377171D01*
G01X1377158Y-152573D02*
X1376937D01*
G01X1377515Y-152774D02*
X1377860D01*
G01Y-152837D02*
X1377417D01*
G01X1376937D02*
X1376863D01*
G01X1322316Y-153033D02*
X1320151D01*
G01X1325466D02*
X1323300D01*
G01X1328615D02*
X1326450D01*
G01X1331765D02*
X1329599D01*
G01X1334914D02*
X1332749D01*
G01X1338064D02*
X1335899D01*
G01X1341214D02*
X1339048D01*
G01X1344363D02*
X1342198D01*
G01X1347513D02*
X1345347D01*
G01X1350662D02*
X1348497D01*
G01X1353812D02*
X1351647D01*
G01X1356962D02*
X1354796D01*
G01X1360111D02*
X1357946D01*
G01X1363261D02*
X1361095D01*
G01X1366410D02*
X1364245D01*
G01X1369560D02*
X1367395D01*
G01X1372710D02*
X1370544D01*
G01X1375859D02*
X1373694D01*
G01X1379009D02*
X1376843D01*
G01X1377540Y-152259D02*
X1377626Y-152246D01*
G01X1378180D02*
X1378106Y-152259D01*
G01X1378721Y-152246D02*
X1378647Y-152259D01*
G01X1378180Y-152837D02*
X1378253Y-152824D01*
G01X1378721Y-152837D02*
X1378795Y-152824D01*
G01X1377614Y-152309D02*
X1377552Y-152321D01*
G01X1378180Y-152309D02*
X1378118Y-152321D01*
G01X1377220Y-152560D02*
X1377158Y-152573D01*
G01X1378721Y-152309D02*
X1378659Y-152321D01*
G01X1378180Y-152774D02*
X1378241Y-152761D01*
G01X1378721Y-152774D02*
X1378782Y-152761D01*
G01X1310131Y-136301D02*
Y-39746D01*
G01X1382729Y-136498D02*
G03X1381942Y-137285I0J-787D01*
G01X1382729Y-136498D02*
G03X1381942Y-137285I0J-787D01*
G01X1416391Y-136498D02*
X1382729D01*
G01X1416391D02*
X1382729D01*
G01X1403814Y-39746D02*
X1310131D01*
G01X1371981Y-2758D02*
Y42911D01*
G01X1371194Y38581D02*
Y42911D01*
G01X1324093Y101967D02*
Y147341D01*
G01X1380546Y223923D02*
X1381268Y222949D01*
G01X1379824Y224411D02*
X1380546Y223923D01*
G01X1378381Y224898D02*
X1379824Y224411D01*
G01X1375493Y224898D02*
X1378381D01*
G01X1374050Y224411D02*
X1375493Y224898D01*
G01X1373328Y223923D02*
X1374050Y224411D01*
G01X1372606Y222949D02*
X1373328Y223923D01*
G01Y221975D02*
X1372606Y222949D01*
G01X1374050Y221487D02*
X1373328Y221975D01*
G01X1375493Y221000D02*
X1374050Y221487D01*
G01X1378381Y221000D02*
X1375493D01*
G01X1379824Y221487D02*
X1378381Y221000D01*
G01X1380546Y221975D02*
X1379824Y221487D01*
G01X1381268Y222949D02*
X1380546Y221975D01*
G01X1372606Y215154D02*
X1381268D01*
G01X1378381Y251694D02*
X1376937Y252669D01*
G01X1379102Y251694D02*
X1378381D01*
G01X1379102Y256566D02*
X1380546Y255592D01*
G01X1378381Y256566D02*
X1379102D01*
G01X1380546Y245360D02*
X1379824Y244873D01*
G01X1381268Y246335D02*
X1380546Y245360D01*
G01Y247309D02*
X1381268Y246335D01*
G01X1379824Y247796D02*
X1380546Y247309D01*
G01X1378381Y248284D02*
X1379824Y247796D01*
G01X1375493Y248284D02*
X1378381D01*
G01X1374050Y247796D02*
X1375493Y248284D01*
G01X1373328Y247309D02*
X1374050Y247796D01*
G01X1372606Y246335D02*
X1373328Y247309D01*
G01Y245360D02*
X1372606Y246335D01*
G01X1374050Y244873D02*
X1373328Y245360D01*
G01X1375493Y244386D02*
X1374050Y244873D01*
G01X1376937D02*
X1375493Y244386D01*
G01X1377659Y246335D02*
X1376937Y244873D01*
G01Y247796D02*
X1377659Y246335D01*
G01X1375493Y248284D02*
X1376937Y247796D01*
G01X1381268Y228795D02*
Y232693D01*
G01X1379102Y229283D02*
X1381268Y228795D01*
G01X1377659Y230257D02*
X1379102Y229283D01*
G01X1376937Y231231D02*
X1377659Y230257D01*
G01X1376215Y232206D02*
X1376937Y231231D01*
G01X1375493Y232693D02*
X1376215Y232206D01*
G01X1374050Y232693D02*
X1375493D01*
G01X1373328Y232206D02*
X1374050Y232693D01*
G01X1372606Y231231D02*
X1373328Y232206D01*
G01X1372606Y230257D02*
Y231231D01*
G01X1373328Y229283D02*
X1372606Y230257D01*
G01X1374050Y228795D02*
X1373328Y229283D01*
G01X1376937Y255592D02*
X1378381Y256566D01*
G01X1376215Y254617D02*
X1376937Y255592D01*
G01X1376215Y253643D02*
Y254617D01*
G01X1376937Y252669D02*
X1376215Y253643D01*
G01X1381268Y254617D02*
Y253643D01*
G01X1380546Y255592D02*
X1381268Y254617D01*
G01X1380546Y238052D02*
X1381268Y238540D01*
G01Y238052D02*
X1380546D01*
G01X1381268Y238540D02*
Y238052D01*
G01X1375493Y255592D02*
X1376215Y254617D01*
G01X1374772Y256079D02*
X1375493Y255592D01*
G01X1374050Y256079D02*
X1374772D01*
G01X1373328Y255592D02*
X1374050Y256079D01*
G01X1372606Y254617D02*
X1373328Y255592D01*
G01X1372606Y253643D02*
Y254617D01*
G01X1373328Y252669D02*
X1372606Y253643D01*
G01X1374050Y252181D02*
X1373328Y252669D01*
G01X1374772Y252181D02*
X1374050D01*
G01X1375493Y252669D02*
X1374772Y252181D01*
G01X1376215Y253643D02*
X1375493Y252669D01*
G01X1380546D02*
X1379102Y251694D01*
G01X1381268Y253643D02*
X1380546Y252669D01*
G01X1383433Y299785D02*
Y262358D01*
G01X1381465Y300654D02*
X1383433Y302622D01*
G01X1381465Y300654D02*
X1383433Y302622D01*
G01D02*
Y331362D01*
G01Y302622D02*
Y331362D01*
G01X1380500Y304591D02*
Y315614D01*
G01X1378335D02*
Y304591D01*
G01X1377350D02*
Y315614D01*
G01X1375185D02*
Y304591D01*
G01X1374201D02*
Y315614D01*
G01X1372035D02*
Y304591D01*
G01X1371051D02*
Y315614D01*
G01X1368886D02*
Y304591D01*
G01X1367902D02*
Y315614D01*
G01X1378335Y304591D02*
X1380500D01*
G01X1375185D02*
X1377350D01*
G01X1372035D02*
X1374201D01*
G01X1368886D02*
X1371051D01*
G01X1365736D02*
X1367902D01*
G01Y315614D02*
X1365736D01*
G01X1371051D02*
X1368886D01*
G01X1374201D02*
X1372035D01*
G01X1377350D02*
X1375185D01*
G01X1380500D02*
X1378335D01*
G01X1318492D02*
Y304591D01*
G01X1317508D02*
Y315614D01*
G01X1315343D02*
Y304591D01*
G01X1314358D02*
Y315614D01*
G01X1312193D02*
Y304591D01*
G01X1311209D02*
Y315614D01*
G01X1309043D02*
Y304591D01*
G01X1308059D02*
Y315614D01*
G01X1318492Y304591D02*
X1320657D01*
G01X1315343D02*
X1317508D01*
G01X1312193D02*
X1314358D01*
G01X1309043D02*
X1311209D01*
G01Y315614D02*
X1309043D01*
G01X1314358D02*
X1312193D01*
G01X1317508D02*
X1315343D01*
G01X1320657D02*
X1318492D01*
G01X1365736D02*
Y304591D01*
G01X1364752D02*
Y315614D01*
G01X1362587D02*
Y304591D01*
G01X1361602D02*
Y315614D01*
G01X1359437D02*
Y304591D01*
G01X1358453D02*
Y315614D01*
G01X1356287D02*
Y304591D01*
G01X1355303D02*
Y315614D01*
G01X1353138D02*
Y304591D01*
G01X1352154D02*
Y315614D01*
G01X1349988D02*
Y304591D01*
G01X1349004D02*
Y315614D01*
G01X1346839D02*
Y304591D01*
G01X1345854D02*
Y315614D01*
G01X1343689D02*
Y304591D01*
G01X1342705D02*
Y315614D01*
G01X1340539D02*
Y304591D01*
G01X1339555D02*
Y315614D01*
G01X1337390D02*
Y304591D01*
G01X1336406D02*
Y315614D01*
G01X1334240D02*
Y304591D01*
G01X1333256D02*
Y315614D01*
G01X1331091D02*
Y304591D01*
G01X1330106D02*
Y315614D01*
G01X1327941D02*
Y304591D01*
G01X1326957D02*
Y315614D01*
G01X1324791D02*
Y304591D01*
G01X1323807D02*
Y315614D01*
G01X1321642D02*
Y304591D01*
G01X1320657D02*
Y315614D01*
G01X1362587Y304591D02*
X1364752D01*
G01X1359437D02*
X1361602D01*
G01X1356287D02*
X1358453D01*
G01X1353138D02*
X1355303D01*
G01X1349988D02*
X1352154D01*
G01X1346839D02*
X1349004D01*
G01X1343689D02*
X1345854D01*
G01X1340539D02*
X1342705D01*
G01X1337390D02*
X1339555D01*
G01X1334240D02*
X1336406D01*
G01X1331091D02*
X1333256D01*
G01X1327941D02*
X1330106D01*
G01X1324791D02*
X1326957D01*
G01X1321642D02*
X1323807D01*
G01X1384220Y332150D02*
G03X1383433Y331362I1J-788D01*
G01X1384220Y332150D02*
G03X1383433Y331362I1J-788D01*
G01X1417882Y332150D02*
X1384220D01*
G01X1417882D02*
X1384220D01*
G01X1323807Y315614D02*
X1321642D01*
G01X1326957D02*
X1324791D01*
G01X1330106D02*
X1327941D01*
G01X1333256D02*
X1331091D01*
G01X1336406D02*
X1334240D01*
G01X1339555D02*
X1337390D01*
G01X1342705D02*
X1340539D01*
G01X1345854D02*
X1343689D01*
G01X1349004D02*
X1346839D01*
G01X1352154D02*
X1349988D01*
G01X1355303D02*
X1353138D01*
G01X1358453D02*
X1356287D01*
G01X1361602D02*
X1359437D01*
G01X1364752D02*
X1362587D01*
G01X1317724Y502524D02*
Y497012D01*
G01X1375205Y502524D02*
Y497012D01*
G01X1372055Y502524D02*
Y497012D01*
G01X1368118Y502524D02*
Y497012D01*
G01X1364968Y502524D02*
Y497012D01*
G01X1372055D02*
X1391740D01*
G01X1348433D02*
X1368118D01*
G01X1324811D02*
X1344496D01*
G01X1351583Y502524D02*
Y497012D01*
G01X1348433Y502524D02*
Y497012D01*
G01X1344496Y502524D02*
Y497012D01*
G01X1341346Y502524D02*
Y497012D01*
G01X1327961Y502524D02*
Y497012D01*
G01X1324811Y502524D02*
Y497012D01*
G01X1320874Y502524D02*
Y497012D01*
G01X1309812Y525754D02*
X1309811Y525751D01*
G01X1309812Y525756D02*
Y525754D01*
G01X1309813Y525757D02*
X1309812Y525756D01*
G01X1317686Y525754D02*
X1317685Y525751D01*
G01X1317686Y525756D02*
Y525754D01*
G01X1317687Y525757D02*
X1317686Y525756D01*
G01X1308314Y508624D02*
X1308315Y508627D01*
G01X1308314Y508622D02*
Y508624D01*
G01X1308313Y508621D02*
X1308314Y508622D01*
G01X1316188Y508624D02*
X1316189Y508627D01*
G01X1316188Y508622D02*
Y508624D01*
G01X1316187Y508621D02*
X1316188Y508622D01*
G01X1308305Y508770D02*
X1308313Y508621D01*
G01X1308298Y509184D02*
X1308305Y508770D01*
G01X1308293Y509804D02*
X1308298Y509184D01*
G01X1308291Y510552D02*
X1308293Y509804D01*
G01X1308309Y524698D02*
X1308313Y524772D01*
G01X1308306Y524491D02*
X1308309Y524698D01*
G01X1308303Y524181D02*
X1308306Y524491D01*
G01X1308302Y523807D02*
X1308303Y524181D01*
G01X1308293Y524573D02*
X1308291Y523826D01*
G01X1308298Y525193D02*
X1308293Y524573D01*
G01X1308305Y525608D02*
X1308298Y525193D01*
G01X1308313Y525757D02*
X1308305Y525608D01*
G01X1309833Y509804D02*
X1309835Y510552D01*
G01X1309828Y509184D02*
X1309833Y509804D01*
G01X1309821Y508770D02*
X1309828Y509184D01*
G01X1309813Y508621D02*
X1309821Y508770D01*
G01X1308314Y509607D02*
X1308313Y509606D01*
G01X1308314Y509610D02*
Y509607D01*
G01X1308315Y509617D02*
X1308314Y509610D01*
G01X1309812Y524771D02*
X1309813Y524772D01*
G01X1309812Y524768D02*
Y524771D01*
G01X1309811Y524761D02*
X1309812Y524768D01*
G01X1308048Y508965D02*
X1308053Y509117D01*
G01X1308044Y508867D02*
X1308048Y508965D01*
G01X1308039Y508825D02*
X1308044Y508867D01*
G01X1310078Y525413D02*
X1310073Y525261D01*
G01X1310082Y525511D02*
X1310078Y525413D01*
G01X1310087Y525553D02*
X1310082Y525511D01*
G01X1311981Y508965D02*
X1311985Y509117D01*
G01X1311976Y508867D02*
X1311981Y508965D01*
G01X1311972Y508825D02*
X1311976Y508867D01*
G01X1314019Y525413D02*
X1314015Y525261D01*
G01X1314024Y525511D02*
X1314019Y525413D01*
G01X1314028Y525553D02*
X1314024Y525511D01*
G01X1310074Y526353D02*
X1310069Y526147D01*
G01X1310080Y526485D02*
X1310074Y526353D01*
G01X1310087Y526538D02*
X1310080Y526485D01*
G01X1308052Y508025D02*
X1308057Y508231D01*
G01X1308046Y507893D02*
X1308052Y508025D01*
G01X1308039Y507840D02*
X1308046Y507893D01*
G01X1314016Y526353D02*
X1314010Y526147D01*
G01X1314022Y526485D02*
X1314016Y526353D01*
G01X1314028Y526538D02*
X1314022Y526485D01*
G01X1311984Y508025D02*
X1311990Y508231D01*
G01X1311978Y507893D02*
X1311984Y508025D01*
G01X1311972Y507840D02*
X1311978Y507893D01*
G01X1312245Y524209D02*
X1312244Y523807D01*
G01X1312248Y524537D02*
X1312245Y524209D01*
G01X1312252Y524733D02*
X1312248Y524537D01*
G01X1312256Y524763D02*
X1312252Y524733D01*
G01X1313755Y510169D02*
X1313756Y510571D01*
G01X1313752Y509841D02*
X1313755Y510169D01*
G01X1313748Y509645D02*
X1313752Y509841D01*
G01X1313744Y509615D02*
X1313748Y509645D01*
G01X1317686Y524768D02*
X1317685Y524763D01*
G01X1317686Y524771D02*
Y524768D01*
G01X1317687Y524772D02*
X1317686Y524771D01*
G01X1316188Y509610D02*
X1316189Y509615D01*
G01X1316188Y509607D02*
Y509610D01*
G01X1316187Y509606D02*
X1316188Y509607D01*
G01Y524771D02*
X1316187Y524772D01*
G01X1316188Y524768D02*
Y524771D01*
G01X1316189Y524763D02*
X1316188Y524768D01*
G01X1317686Y509607D02*
X1317687Y509606D01*
G01X1317686Y509610D02*
Y509607D01*
G01X1317685Y509615D02*
X1317686Y509610D01*
G01X1308303Y510197D02*
X1308302Y510571D01*
G01X1308306Y509887D02*
X1308303Y510197D01*
G01X1308309Y509680D02*
X1308306Y509887D01*
G01X1308313Y509606D02*
X1308309Y509680D01*
G01X1309823Y524181D02*
X1309824Y523807D01*
G01X1309820Y524491D02*
X1309823Y524181D01*
G01X1309817Y524698D02*
X1309820Y524491D01*
G01X1309813Y524772D02*
X1309817Y524698D01*
G01X1308046Y526485D02*
X1308039Y526538D01*
G01X1308052Y526353D02*
X1308046Y526485D01*
G01X1308057Y526147D02*
X1308052Y526353D01*
G01X1310080Y507893D02*
X1310087Y507840D01*
G01X1310074Y508025D02*
X1310080Y507893D01*
G01X1310069Y508231D02*
X1310074Y508025D01*
G01X1311987Y526485D02*
X1311981Y526538D01*
G01X1311993Y526353D02*
X1311987Y526485D01*
G01X1311999Y526147D02*
X1311993Y526353D01*
G01X1314013Y507893D02*
X1314019Y507840D01*
G01X1314007Y508025D02*
X1314013Y507893D01*
G01X1314001Y508231D02*
X1314007Y508025D01*
G01X1315920Y526485D02*
X1315913Y526538D01*
G01X1315926Y526353D02*
X1315920Y526485D01*
G01X1315931Y526147D02*
X1315926Y526353D01*
G01X1317954Y507893D02*
X1317961Y507840D01*
G01X1317948Y508025D02*
X1317954Y507893D01*
G01X1317943Y508231D02*
X1317948Y508025D01*
G01X1319861Y526485D02*
X1319855Y526538D01*
G01X1319867Y526353D02*
X1319861Y526485D01*
G01X1319873Y526147D02*
X1319867Y526353D01*
G01X1308044Y525511D02*
X1308039Y525553D01*
G01X1308048Y525413D02*
X1308044Y525511D01*
G01X1308053Y525261D02*
X1308048Y525413D01*
G01X1310082Y508867D02*
X1310087Y508825D01*
G01X1310078Y508965D02*
X1310082Y508867D01*
G01X1310073Y509117D02*
X1310078Y508965D01*
G01X1311986Y525511D02*
X1311981Y525553D01*
G01X1311990Y525413D02*
X1311986Y525511D01*
G01X1311994Y525261D02*
X1311990Y525413D01*
G01X1314014Y508867D02*
X1314019Y508825D01*
G01X1314010Y508965D02*
X1314014Y508867D01*
G01X1314006Y509117D02*
X1314010Y508965D01*
G01X1315918Y525511D02*
X1315913Y525553D01*
G01X1315922Y525413D02*
X1315918Y525511D01*
G01X1315927Y525261D02*
X1315922Y525413D01*
G01X1317956Y508867D02*
X1317961Y508825D01*
G01X1317952Y508965D02*
X1317956Y508867D01*
G01X1317947Y509117D02*
X1317952Y508965D01*
G01X1319860Y525511D02*
X1319855Y525553D01*
G01X1319864Y525413D02*
X1319860Y525511D01*
G01X1319868Y525261D02*
X1319864Y525413D01*
G01X1312243Y509645D02*
X1312247Y509615D01*
G01X1312238Y509841D02*
X1312243Y509645D01*
G01X1312236Y510169D02*
X1312238Y509841D01*
G01X1312235Y510571D02*
X1312236Y510169D01*
G01X1313757Y524733D02*
X1313753Y524763D01*
G01X1313762Y524537D02*
X1313757Y524733D01*
G01X1313764Y524209D02*
X1313762Y524537D01*
G01X1313765Y523807D02*
X1313764Y524209D01*
G01X1320117Y509645D02*
X1320121Y509615D01*
G01X1320112Y509841D02*
X1320117Y509645D01*
G01X1320110Y510169D02*
X1320112Y509841D01*
G01X1320109Y510571D02*
X1320110Y510169D01*
G01X1309821Y525608D02*
X1309813Y525757D01*
G01X1309828Y525193D02*
X1309821Y525608D01*
G01X1309833Y524573D02*
X1309828Y525193D01*
G01X1309835Y523826D02*
X1309833Y524573D01*
G01X1316179Y508770D02*
X1316187Y508621D01*
G01X1316172Y509184D02*
X1316179Y508770D01*
G01X1316167Y509804D02*
X1316172Y509184D01*
G01X1316165Y510552D02*
X1316167Y509804D01*
G01X1316183Y509679D02*
X1316187Y509606D01*
G01X1316180Y509887D02*
X1316183Y509679D01*
G01X1316177Y510200D02*
X1316180Y509887D01*
G01X1316176Y510571D02*
X1316177Y510200D01*
G01X1317691Y524699D02*
X1317687Y524772D01*
G01X1317694Y524491D02*
X1317691Y524699D01*
G01X1317697Y524178D02*
X1317694Y524491D01*
G01X1317698Y523807D02*
X1317697Y524178D01*
G01X1317695Y525608D02*
X1317687Y525757D01*
G01X1317702Y525193D02*
X1317695Y525608D01*
G01X1317707Y524573D02*
X1317702Y525193D01*
G01X1317709Y523826D02*
X1317707Y524573D01*
G01X1309817Y509680D02*
X1309813Y509606D01*
G01X1309820Y509887D02*
X1309817Y509680D01*
G01X1309823Y510197D02*
X1309820Y509887D01*
G01X1309824Y510571D02*
X1309823Y510197D01*
G01X1316167Y524573D02*
X1316165Y523826D01*
G01X1316172Y525193D02*
X1316167Y524573D01*
G01X1316179Y525608D02*
X1316172Y525193D01*
G01X1316187Y525757D02*
X1316179Y525608D01*
G01X1317707Y509804D02*
X1317709Y510552D01*
G01X1317702Y509184D02*
X1317707Y509804D01*
G01X1317695Y508770D02*
X1317702Y509184D01*
G01X1317687Y508621D02*
X1317695Y508770D01*
G01X1316177Y524178D02*
X1316176Y523807D01*
G01X1316180Y524491D02*
X1316177Y524178D01*
G01X1316183Y524699D02*
X1316180Y524491D01*
G01X1316187Y524772D02*
X1316183Y524699D01*
G01X1317697Y510200D02*
X1317698Y510571D01*
G01X1317694Y509887D02*
X1317697Y510200D01*
G01X1317691Y509679D02*
X1317694Y509887D01*
G01X1317687Y509606D02*
X1317691Y509679D01*
G01X1315922Y508965D02*
X1315927Y509117D01*
G01X1315918Y508867D02*
X1315922Y508965D01*
G01X1315913Y508825D02*
X1315918Y508867D01*
G01X1317952Y525413D02*
X1317947Y525261D01*
G01X1317956Y525511D02*
X1317952Y525413D01*
G01X1317961Y525553D02*
X1317956Y525511D01*
G01X1319855Y508965D02*
X1319859Y509117D01*
G01X1319850Y508867D02*
X1319855Y508965D01*
G01X1319846Y508825D02*
X1319850Y508867D01*
G01X1317948Y526353D02*
X1317943Y526147D01*
G01X1317954Y526485D02*
X1317948Y526353D01*
G01X1317961Y526538D02*
X1317954Y526485D01*
G01X1315926Y508025D02*
X1315931Y508231D01*
G01X1315920Y507893D02*
X1315926Y508025D01*
G01X1315913Y507840D02*
X1315920Y507893D01*
G01X1319858Y508025D02*
X1319864Y508231D01*
G01X1319852Y507893D02*
X1319858Y508025D01*
G01X1319846Y507840D02*
X1319852Y507893D01*
G01X1320119Y524209D02*
X1320118Y523807D01*
G01X1320122Y524537D02*
X1320119Y524209D01*
G01X1320126Y524733D02*
X1320122Y524537D01*
G01X1320130Y524763D02*
X1320126Y524733D01*
G01X1309812Y509610D02*
X1309811Y509617D01*
G01X1309812Y509607D02*
Y509610D01*
G01X1309813Y509606D02*
X1309812Y509607D01*
G01Y508622D02*
X1309813Y508621D01*
G01X1309812Y508624D02*
Y508622D01*
G01X1309811Y508627D02*
X1309812Y508624D01*
G01X1308314Y525756D02*
X1308313Y525757D01*
G01X1308314Y525754D02*
Y525756D01*
G01X1308315Y525751D02*
X1308314Y525754D01*
G01X1317686Y508622D02*
X1317687Y508621D01*
G01X1317686Y508624D02*
Y508622D01*
G01X1317685Y508627D02*
X1317686Y508624D01*
G01X1316188Y525756D02*
X1316187Y525757D01*
G01X1316188Y525754D02*
Y525756D01*
G01X1316189Y525751D02*
X1316188Y525754D01*
G01X1319816Y508823D02*
X1319801D01*
G01X1319831Y508824D02*
X1319816Y508823D01*
G01X1319846Y508825D02*
X1319831Y508824D01*
G01X1315883Y508823D02*
X1315868D01*
G01X1315898Y508824D02*
X1315883Y508823D01*
G01X1315913Y508825D02*
X1315898Y508824D01*
G01X1311942Y508823D02*
X1311927D01*
G01X1311957Y508824D02*
X1311942Y508823D01*
G01X1311972Y508825D02*
X1311957Y508824D01*
G01X1308009Y508823D02*
X1307994D01*
G01X1308024Y508824D02*
X1308009Y508823D01*
G01X1308039Y508825D02*
X1308024Y508824D01*
G01X1319816Y507839D02*
X1319801D01*
G01X1319831D02*
X1319816D01*
G01X1319846Y507840D02*
X1319831Y507839D01*
G01X1315883D02*
X1315868D01*
G01X1315898D02*
X1315883D01*
G01X1315913Y507840D02*
X1315898Y507839D01*
G01X1311942D02*
X1311927D01*
G01X1311957D02*
X1311942D01*
G01X1311972Y507840D02*
X1311957Y507839D01*
G01X1310102D02*
X1310087Y507840D01*
G01X1310117Y507839D02*
X1310102D01*
G01X1310132D02*
X1310117D01*
G01X1314034D02*
X1314019Y507840D01*
G01X1314049Y507839D02*
X1314034D01*
G01X1314064D02*
X1314049D01*
G01X1317976D02*
X1317961Y507840D01*
G01X1317991Y507839D02*
X1317976D01*
G01X1318006D02*
X1317991D01*
G01X1310102Y508824D02*
X1310087Y508825D01*
G01X1310117Y508823D02*
X1310102Y508824D01*
G01X1310132Y508823D02*
X1310117D01*
G01X1314034Y508824D02*
X1314019Y508825D01*
G01X1314049Y508823D02*
X1314034Y508824D01*
G01X1314064Y508823D02*
X1314049D01*
G01X1317976Y508824D02*
X1317961Y508825D01*
G01X1317991Y508823D02*
X1317976Y508824D01*
G01X1318006Y508823D02*
X1317991D01*
G01X1308314Y524768D02*
X1308315Y524761D01*
G01X1308314Y524771D02*
Y524768D01*
G01X1308313Y524772D02*
X1308314Y524771D01*
G01X1317991Y525555D02*
X1318006D01*
G01X1317976Y525554D02*
X1317991Y525555D01*
G01X1317961Y525553D02*
X1317976Y525554D01*
G01X1310117Y525555D02*
X1310132D01*
G01X1310102Y525554D02*
X1310117Y525555D01*
G01X1310087Y525553D02*
X1310102Y525554D01*
G01X1317991Y526539D02*
X1318006D01*
G01X1317976D02*
X1317991D01*
G01X1317961Y526538D02*
X1317976Y526539D01*
G01X1314058D02*
X1314073D01*
G01X1314043D02*
X1314058D01*
G01X1314028Y526538D02*
X1314043Y526539D01*
G01X1308024D02*
X1308039Y526538D01*
G01X1308009Y526539D02*
X1308024D01*
G01X1307994D02*
X1308009D01*
G01X1311966D02*
X1311981Y526538D01*
G01X1311951Y526539D02*
X1311966D01*
G01X1311936D02*
X1311951D01*
G01X1315898D02*
X1315913Y526538D01*
G01X1315883Y526539D02*
X1315898D01*
G01X1315868D02*
X1315883D01*
G01X1319840D02*
X1319855Y526538D01*
G01X1319825Y526539D02*
X1319840D01*
G01X1319810D02*
X1319825D01*
G01X1308024Y525554D02*
X1308039Y525553D01*
G01X1308009Y525555D02*
X1308024Y525554D01*
G01X1307994Y525555D02*
X1308009D01*
G01X1311966Y525554D02*
X1311981Y525553D01*
G01X1311951Y525555D02*
X1311966Y525554D01*
G01X1311936Y525555D02*
X1311951D01*
G01X1315898Y525554D02*
X1315913Y525553D01*
G01X1315883Y525555D02*
X1315898Y525554D01*
G01X1315868Y525555D02*
X1315883D01*
G01X1319840Y525554D02*
X1319855Y525553D01*
G01X1319825Y525555D02*
X1319840Y525554D01*
G01X1319810Y525555D02*
X1319825D01*
G01X1310244Y530476D02*
X1307882D01*
G01X1314181D02*
X1311819D01*
G01X1318118D02*
X1315756D01*
G01X1322055D02*
X1319693D01*
G01X1309732Y529492D02*
X1308394D01*
G01X1317606D02*
X1316268D01*
G01X1316110Y529394D02*
X1317764D01*
G01X1308236D02*
X1309890D01*
G01X1310244Y529295D02*
X1307882D01*
G01X1314181D02*
X1311819D01*
G01X1318118D02*
X1315756D01*
G01X1322055D02*
X1319693D01*
G01X1309890Y528902D02*
X1308236D01*
G01X1317764D02*
X1316110D01*
G01X1314417Y528035D02*
X1311583D01*
G01X1318354D02*
X1315520D01*
G01X1322291D02*
X1319457D01*
G01X1309890Y527130D02*
X1308236D01*
G01X1317764D02*
X1316110D01*
G01Y526638D02*
X1317764D01*
G01X1308236D02*
X1309890D01*
G01X1314417Y526539D02*
X1311583D01*
G01X1318354D02*
X1315520D01*
G01X1322291D02*
X1319457D01*
G01Y526382D02*
X1320047D01*
G01X1317764D02*
X1318354D01*
G01X1315520D02*
X1316110D01*
G01X1313827D02*
X1314417D01*
G01X1311583D02*
X1312173D01*
G01X1309890D02*
X1310480D01*
G01X1319873Y526147D02*
X1321884D01*
G01X1315931D02*
X1317943D01*
G01X1311999D02*
X1314010D01*
G01X1308057D02*
X1310069D01*
G01X1309813Y525757D02*
X1308313D01*
G01X1313754D02*
X1312255D01*
G01X1317687D02*
X1316187D01*
G01X1321628D02*
X1320129D01*
G01X1320142Y525738D02*
X1321615D01*
G01X1316201D02*
X1317674D01*
G01X1312268D02*
X1313741D01*
G01X1308326D02*
X1309799D01*
G01X1310480Y525713D02*
X1309890D01*
G01X1312173D02*
X1311583D01*
G01X1314417D02*
X1313827D01*
G01X1316110D02*
X1315520D01*
G01X1318354D02*
X1317764D01*
G01X1320047D02*
X1319457D01*
G01Y525555D02*
X1322291D01*
G01X1315520D02*
X1318354D01*
G01X1311583D02*
X1314417D01*
G01X1313827Y525457D02*
X1312173D01*
G01X1321701D02*
X1320047D01*
G01X1309546Y525368D02*
X1308580D01*
G01X1313487D02*
X1312522D01*
G01X1317420D02*
X1316454D01*
G01X1319457Y525358D02*
X1319772D01*
G01X1315520D02*
X1315835D01*
G01X1311583D02*
X1311898D01*
G01X1310480D02*
X1310165D01*
G01X1314417D02*
X1314102D01*
G01X1318354D02*
X1318039D01*
G01X1310073Y525261D02*
X1308053D01*
G01X1314015D02*
X1311994D01*
G01X1317947D02*
X1315927D01*
G01X1321889D02*
X1319868D01*
G01X1320047Y524965D02*
X1321701D01*
G01X1312173D02*
X1313827D01*
G01X1309813Y524772D02*
X1308313D01*
G01X1313754D02*
X1312255D01*
G01X1317687D02*
X1316187D01*
G01X1321628D02*
X1320129D01*
G01X1309811Y524763D02*
X1308315D01*
G01X1313753D02*
X1312256D01*
G01X1317685D02*
X1316189D01*
G01X1321627D02*
X1320130D01*
G01X1316409Y524441D02*
X1317465D01*
G01X1312476D02*
X1313533D01*
G01X1308535D02*
X1309591D01*
G01X1307882Y524394D02*
X1310244D01*
G01X1314181D02*
X1311819D01*
G01X1318118D02*
X1315756D01*
G01X1322055D02*
X1319693D01*
G01X1319457Y523862D02*
X1319772D01*
G01X1318039D02*
X1318354D01*
G01X1315520D02*
X1315835D01*
G01X1314102D02*
X1314417D01*
G01X1311583D02*
X1311898D01*
G01X1310165D02*
X1310480D01*
G01X1320107Y523826D02*
X1321650D01*
G01X1316165D02*
X1317709D01*
G01X1312233D02*
X1313776D01*
G01X1308291D02*
X1309835D01*
G01X1320118Y523807D02*
X1321639D01*
G01X1316176D02*
X1317698D01*
G01X1312244D02*
X1313765D01*
G01X1308302D02*
X1309824D01*
G01X1320047Y523193D02*
X1321701D01*
G01X1312173D02*
X1313827D01*
G01Y522701D02*
X1312173D01*
G01X1321701D02*
X1320047D01*
G01X1313669Y522602D02*
X1312331D01*
G01X1321543D02*
X1320205D01*
G01Y521618D02*
X1321543D01*
G01X1312331D02*
X1313669D01*
G01X1309861Y520999D02*
X1308265D01*
G01X1313802D02*
X1312207D01*
G01X1317735D02*
X1316139D01*
G01X1321676D02*
X1320081D01*
G01X1310165Y520890D02*
X1307961D01*
G01X1314102D02*
X1311898D01*
G01X1318039D02*
X1315835D01*
G01X1321976D02*
X1319772D01*
G01X1309932Y520239D02*
X1308194D01*
G01X1313874D02*
X1312135D01*
G01X1317806D02*
X1316068D01*
G01X1321748D02*
X1320009D01*
G01X1320083Y520037D02*
X1321674D01*
G01X1316142D02*
X1317732D01*
G01X1312209D02*
X1313800D01*
G01X1308268D02*
X1309858D01*
G01X1320031Y520013D02*
X1321727D01*
G01X1316089D02*
X1317785D01*
G01X1312157D02*
X1313853D01*
G01X1308215D02*
X1309911D01*
G01X1309918Y519945D02*
X1308208D01*
G01X1313860D02*
X1312150D01*
G01X1317792D02*
X1316082D01*
G01X1321734D02*
X1320024D01*
G01X1320004Y519353D02*
X1321753D01*
G01X1316063D02*
X1317811D01*
G01X1312130D02*
X1313879D01*
G01X1308189D02*
X1309937D01*
G01X1309909Y519051D02*
X1308217D01*
G01X1313850D02*
X1312159D01*
G01X1317783D02*
X1316091D01*
G01X1321724D02*
X1320033D01*
G01X1309918Y518961D02*
X1308208D01*
G01X1313860D02*
X1312150D01*
G01X1317792D02*
X1316082D01*
G01X1321734D02*
X1320024D01*
G01X1319772Y518635D02*
X1321976D01*
G01X1315835D02*
X1318039D01*
G01X1311898D02*
X1314102D01*
G01X1307961D02*
X1310165D01*
G01X1319772Y518468D02*
X1321976D01*
G01X1315835D02*
X1318039D01*
G01X1311898D02*
X1314102D01*
G01X1307961D02*
X1310165D01*
G01Y515910D02*
X1307961D01*
G01X1314102D02*
X1311898D01*
G01X1318039D02*
X1315835D01*
G01X1321976D02*
X1319772D01*
G01X1310165Y515743D02*
X1307961D01*
G01X1314102D02*
X1311898D01*
G01X1318039D02*
X1315835D01*
G01X1321976D02*
X1319772D01*
G01X1320014Y515417D02*
X1321724D01*
G01X1316082D02*
X1317792D01*
G01X1312140D02*
X1313850D01*
G01X1308208D02*
X1309918D01*
G01X1320024Y515327D02*
X1321715D01*
G01X1316091D02*
X1317783D01*
G01X1312150D02*
X1313841D01*
G01X1308217D02*
X1309909D01*
G01X1309937Y515025D02*
X1308189D01*
G01X1313870D02*
X1312121D01*
G01X1317811D02*
X1316063D01*
G01X1321744D02*
X1319995D01*
G01X1320014Y514433D02*
X1321724D01*
G01X1316082D02*
X1317792D01*
G01X1312140D02*
X1313850D01*
G01X1308208D02*
X1309918D01*
G01X1309911Y514365D02*
X1308215D01*
G01X1313843D02*
X1312147D01*
G01X1317785D02*
X1316089D01*
G01X1321717D02*
X1320021D01*
G01X1309858Y514341D02*
X1308268D01*
G01X1313791D02*
X1312200D01*
G01X1317732D02*
X1316142D01*
G01X1321665D02*
X1320074D01*
G01X1320000Y514139D02*
X1321739D01*
G01X1316068D02*
X1317806D01*
G01X1312126D02*
X1313865D01*
G01X1308194D02*
X1309932D01*
G01X1319772Y513488D02*
X1321976D01*
G01X1315835D02*
X1318039D01*
G01X1311898D02*
X1314102D01*
G01X1307961D02*
X1310165D01*
G01X1320072Y513379D02*
X1321667D01*
G01X1316139D02*
X1317735D01*
G01X1312198D02*
X1313793D01*
G01X1308265D02*
X1309861D01*
G01X1313669Y512760D02*
X1312331D01*
G01X1321543D02*
X1320205D01*
G01X1313669Y511776D02*
X1312331D01*
G01X1321543D02*
X1320205D01*
G01X1320047Y511677D02*
X1321701D01*
G01X1312173D02*
X1313827D01*
G01Y511185D02*
X1312173D01*
G01X1321701D02*
X1320047D01*
G01X1320142Y525738D02*
X1320396Y525368D01*
G01X1320350Y524441D02*
X1320129Y524763D01*
G01X1316201Y525738D02*
X1316454Y525368D01*
G01X1316409Y524441D02*
X1316187Y524763D01*
G01X1312268Y525738D02*
X1312522Y525368D01*
G01X1312476Y524441D02*
X1312255Y524763D01*
G01X1308580Y525368D02*
X1308326Y525738D01*
G01X1308315Y524760D02*
X1308535Y524441D01*
G01X1317465Y509937D02*
X1317687Y509615D01*
G01X1317674Y508640D02*
X1317420Y509010D01*
G01X1313524Y509937D02*
X1313745Y509615D01*
G01X1313732Y508640D02*
X1313478Y509010D01*
G01X1309811Y509618D02*
X1309591Y509937D01*
G01X1309546Y509010D02*
X1309799Y508640D01*
G01X1309824Y510571D02*
X1308302D01*
G01X1313756D02*
X1312235D01*
G01X1317698D02*
X1316176D01*
G01X1321630D02*
X1320109D01*
G01X1309835Y510552D02*
X1308291D01*
G01X1313767D02*
X1312224D01*
G01X1317709D02*
X1316165D01*
G01X1321641D02*
X1320098D01*
G01X1310480Y510516D02*
X1310165D01*
G01X1311898D02*
X1311583D01*
G01X1314417D02*
X1314102D01*
G01X1315835D02*
X1315520D01*
G01X1319772D02*
X1319457D01*
G01X1318354D02*
X1318039D01*
G01X1310244Y509984D02*
X1307882D01*
G01X1314181D02*
X1311819D01*
G01X1318118D02*
X1315756D01*
G01X1322055D02*
X1319693D01*
G01X1309591Y509937D02*
X1308535D01*
G01X1313524D02*
X1312467D01*
G01X1317465D02*
X1316409D01*
G01X1320121Y509615D02*
X1321618D01*
G01X1316189D02*
X1317685D01*
G01X1312247D02*
X1313744D01*
G01X1308315D02*
X1309811D01*
G01X1320120Y509606D02*
X1321619D01*
G01X1316187D02*
X1317687D01*
G01X1312246D02*
X1313745D01*
G01X1308313D02*
X1309813D01*
G01X1313827Y509413D02*
X1312173D01*
G01X1321701D02*
X1320047D01*
G01X1319859Y509117D02*
X1321880D01*
G01X1315927D02*
X1317947D01*
G01X1311985D02*
X1314006D01*
G01X1308053D02*
X1310073D01*
G01X1318039Y509020D02*
X1318354D01*
G01X1314102D02*
X1314417D01*
G01X1310480D02*
X1310165D01*
G01X1311898D02*
X1311583D01*
G01X1315835D02*
X1315520D01*
G01X1319772D02*
X1319457D01*
G01X1316454Y509010D02*
X1317420D01*
G01X1312513D02*
X1313478D01*
G01X1308580D02*
X1309546D01*
G01X1320047Y508921D02*
X1321701D01*
G01X1312173D02*
X1313827D01*
G01X1319457Y508823D02*
X1322291D01*
G01X1315520D02*
X1318354D01*
G01X1311583D02*
X1314417D01*
G01X1319457Y508665D02*
X1320047D01*
G01X1317764D02*
X1318354D01*
G01X1315520D02*
X1316110D01*
G01X1313827D02*
X1314417D01*
G01X1311583D02*
X1312173D01*
G01X1309890D02*
X1310480D01*
G01X1309799Y508640D02*
X1308326D01*
G01X1313732D02*
X1312259D01*
G01X1317674D02*
X1316201D01*
G01X1321606D02*
X1320133D01*
G01X1320120Y508621D02*
X1321619D01*
G01X1316187D02*
X1317687D01*
G01X1312246D02*
X1313745D01*
G01X1308313D02*
X1309813D01*
G01X1310069Y508231D02*
X1308057D01*
G01X1314001D02*
X1311990D01*
G01X1317943D02*
X1315931D01*
G01X1321875D02*
X1319864D01*
G01X1310480Y507996D02*
X1309890D01*
G01X1312173D02*
X1311583D01*
G01X1314417D02*
X1313827D01*
G01X1316110D02*
X1315520D01*
G01X1318354D02*
X1317764D01*
G01X1320047D02*
X1319457D01*
G01X1314417Y507839D02*
X1311583D01*
G01X1318354D02*
X1315520D01*
G01X1322291D02*
X1319457D01*
G01X1309890Y507740D02*
X1308236D01*
G01X1317764D02*
X1316110D01*
G01Y507248D02*
X1317764D01*
G01X1308236D02*
X1309890D01*
G01X1319457Y506343D02*
X1322291D01*
G01X1315520D02*
X1318354D01*
G01X1311583D02*
X1314417D01*
G01X1316110Y505476D02*
X1317764D01*
G01X1308236D02*
X1309890D01*
G01X1307882Y505083D02*
X1310244D01*
G01X1314181D02*
X1311819D01*
G01X1318118D02*
X1315756D01*
G01X1322055D02*
X1319693D01*
G01X1309890Y504984D02*
X1308236D01*
G01X1317764D02*
X1316110D01*
G01X1309732Y504886D02*
X1308394D01*
G01X1317606D02*
X1316268D01*
G01X1319693Y503902D02*
X1322055D01*
G01X1315756D02*
X1318118D01*
G01X1311819D02*
X1314181D01*
G01X1307882D02*
X1310244D01*
G01X1316409Y524441D02*
X1316418Y524394D01*
G01X1317465Y509937D02*
X1317456Y509984D01*
G01X1312476Y524441D02*
X1312486Y524394D01*
G01X1313524Y509937D02*
X1313514Y509984D01*
G01X1308544Y524394D02*
X1308535Y524441D01*
G01X1309582Y509984D02*
X1309591Y509937D01*
G01X1320033Y519051D02*
X1320083Y520037D01*
G01X1320081Y520999D02*
X1320031Y520013D01*
G01X1317735Y513379D02*
X1317785Y514365D01*
G01X1317783Y515327D02*
X1317732Y514341D01*
G01X1316091Y519051D02*
X1316142Y520037D01*
G01X1316139Y520999D02*
X1316089Y520013D01*
G01X1313793Y513379D02*
X1313843Y514365D01*
G01X1313841Y515327D02*
X1313791Y514341D01*
G01X1312159Y519051D02*
X1312209Y520037D01*
G01X1312207Y520999D02*
X1312157Y520013D01*
G01X1319864Y508231D02*
X1320000Y514139D01*
G01X1319995Y515025D02*
X1319859Y509117D01*
G01X1317811Y519353D02*
X1317947Y525261D01*
G01X1317943Y526147D02*
X1317806Y520239D01*
G01X1315931Y508231D02*
X1316068Y514139D01*
G01X1316063Y515025D02*
X1315927Y509117D01*
G01X1313879Y519353D02*
X1314015Y525261D01*
G01X1314010Y526147D02*
X1313874Y520239D01*
G01X1311990Y508231D02*
X1312126Y514139D01*
G01X1312121Y515025D02*
X1311985Y509117D01*
G01X1317433Y509984D02*
X1317420Y509010D01*
G01X1316441Y524394D02*
X1316454Y525368D01*
G01X1313491Y509984D02*
X1313478Y509010D01*
G01X1312509Y524394D02*
X1312522Y525368D01*
G01X1309559Y509984D02*
X1309546Y509010D01*
G01X1320205Y512760D02*
Y511696D01*
G01Y522682D02*
Y521618D01*
G01X1320131Y525751D02*
Y524760D01*
G01X1320121Y509618D02*
Y508627D01*
G01X1320047Y521698D02*
Y526539D01*
G01Y507839D02*
Y512680D01*
G01X1319855Y525553D02*
Y526538D01*
G01X1319846Y507840D02*
Y508825D01*
G01X1319772Y526539D02*
Y507839D01*
G01X1319693Y509984D02*
Y503902D01*
G01Y530476D02*
Y524394D01*
G01X1319501Y526539D02*
Y525555D01*
G01X1319496Y526539D02*
Y525555D01*
G01X1319491Y508823D02*
Y507839D01*
G01X1319457Y510516D02*
Y506343D01*
G01Y528035D02*
Y523862D01*
G01X1318354D02*
Y528035D01*
G01Y506343D02*
Y510516D01*
G01X1318320Y508823D02*
Y507839D01*
G01X1318315Y508823D02*
Y507839D01*
G01Y526539D02*
Y525555D01*
G01X1318118Y509984D02*
Y503902D01*
G01Y530476D02*
Y524394D01*
G01X1318039Y507839D02*
Y526539D01*
G01X1317961Y508825D02*
Y507840D01*
G01Y526538D02*
Y525553D01*
G01X1317764Y525555D02*
Y530396D01*
G01Y503982D02*
Y508823D01*
G01X1317685Y524760D02*
Y525751D01*
G01Y508627D02*
Y509618D01*
G01X1317606Y504965D02*
Y503902D01*
G01Y530476D02*
Y529413D01*
G01X1317331Y504886D02*
Y503902D01*
G01Y530476D02*
Y529492D01*
G01X1316543D02*
Y530476D01*
G01Y504886D02*
Y503902D01*
G01X1316268Y504965D02*
Y503902D01*
G01Y530476D02*
Y529413D01*
G01X1316189Y509618D02*
Y508627D01*
G01Y525751D02*
Y524760D01*
G01X1316110Y525555D02*
Y530396D01*
G01Y503982D02*
Y508823D01*
G01X1315913Y507840D02*
Y508825D01*
G01Y525553D02*
Y526538D01*
G01X1315835Y526539D02*
Y507839D01*
G01X1315756Y509984D02*
Y503902D01*
G01Y530476D02*
Y524394D01*
G01X1315559Y508823D02*
Y507839D01*
G01Y526539D02*
Y525555D01*
G01X1315554Y526539D02*
Y525555D01*
G01X1315520Y510516D02*
Y506343D01*
G01Y528035D02*
Y523862D01*
G01X1314417D02*
Y528035D01*
G01Y506343D02*
Y510516D01*
G01X1314383Y526539D02*
Y525555D01*
G01X1314378Y508823D02*
Y507839D01*
G01X1314373Y508823D02*
Y507839D01*
G01X1314181Y509984D02*
Y503902D01*
G01Y530476D02*
Y524394D01*
G01X1314102Y507839D02*
Y526539D01*
G01X1314028Y526538D02*
Y525553D01*
G01X1314019Y508825D02*
Y507840D01*
G01X1313827Y521698D02*
Y526539D01*
G01Y507839D02*
Y512680D01*
G01X1313753Y524760D02*
Y525751D01*
G01X1313743Y508627D02*
Y509618D01*
G01X1313669Y512760D02*
Y511696D01*
G01Y522681D02*
Y521618D01*
G01X1313394D02*
Y522602D01*
G01Y512760D02*
Y511776D01*
G01X1312606Y521618D02*
Y522602D01*
G01Y511776D02*
Y512760D01*
G01X1312331D02*
Y511696D01*
G01Y522682D02*
Y521618D01*
G01X1312257Y525751D02*
Y524760D01*
G01X1312247Y509618D02*
Y508627D01*
G01X1312173Y521698D02*
Y526539D01*
G01Y507839D02*
Y512680D01*
G01X1311981Y525553D02*
Y526538D01*
G01X1311972Y507840D02*
Y508825D01*
G01X1311898Y526539D02*
Y507839D01*
G01X1311819Y509984D02*
Y503902D01*
G01Y530476D02*
Y524394D01*
G01X1311627Y526539D02*
Y525555D01*
G01X1311622Y526539D02*
Y525555D01*
G01X1311617Y508823D02*
Y507839D01*
G01X1311583Y510516D02*
Y506343D01*
G01Y528035D02*
Y523862D01*
G01X1310480D02*
Y528035D01*
G01Y506343D02*
Y510516D01*
G01X1310446Y508823D02*
Y507839D01*
G01X1310441Y508823D02*
Y507839D01*
G01Y526539D02*
Y525555D01*
G01X1310244Y509984D02*
Y503902D01*
G01Y530476D02*
Y524394D01*
G01X1310165Y507839D02*
Y526539D01*
G01X1310087Y508825D02*
Y507840D01*
G01Y526538D02*
Y525553D01*
G01X1309890Y525555D02*
Y530396D01*
G01Y503982D02*
Y508823D01*
G01X1309811Y524760D02*
Y525751D01*
G01Y508627D02*
Y509618D01*
G01X1309732Y504965D02*
Y503902D01*
G01Y530476D02*
Y529413D01*
G01X1309457Y503902D02*
Y504886D01*
G01Y530476D02*
Y529492D01*
G01X1308669Y504886D02*
Y503902D01*
G01Y530476D02*
Y529492D01*
G01X1317420Y525368D02*
X1317433Y524394D01*
G01X1316454Y509010D02*
X1316441Y509984D01*
G01X1313487Y525368D02*
X1313500Y524394D01*
G01X1312513Y509010D02*
X1312500Y509984D01*
G01X1309546Y525368D02*
X1309559Y524394D01*
G01X1308580Y509010D02*
X1308567Y509984D01*
G01X1320009Y520239D02*
X1319873Y526147D01*
G01X1319868Y525261D02*
X1320004Y519353D01*
G01X1317947Y509117D02*
X1317811Y515025D01*
G01X1317806Y514139D02*
X1317943Y508231D01*
G01X1316068Y520239D02*
X1315931Y526147D01*
G01X1315927Y525261D02*
X1316063Y519353D01*
G01X1314006Y509117D02*
X1313870Y515025D01*
G01X1313865Y514139D02*
X1314001Y508231D01*
G01X1312135Y520239D02*
X1311999Y526147D01*
G01X1311994Y525261D02*
X1312130Y519353D01*
G01X1310073Y509117D02*
X1309937Y515025D01*
G01X1309932Y514139D02*
X1310069Y508231D01*
G01X1308194Y520239D02*
X1308057Y526147D01*
G01X1308053Y525261D02*
X1308189Y519353D01*
G01X1320074Y514341D02*
X1320024Y515327D01*
G01X1320021Y514365D02*
X1320072Y513379D01*
G01X1317785Y520013D02*
X1317735Y520999D01*
G01X1317732Y520037D02*
X1317783Y519051D01*
G01X1316142Y514341D02*
X1316091Y515327D01*
G01X1316089Y514365D02*
X1316139Y513379D01*
G01X1313853Y520013D02*
X1313802Y520999D01*
G01X1313800Y520037D02*
X1313850Y519051D01*
G01X1312200Y514341D02*
X1312150Y515327D01*
G01X1312147Y514365D02*
X1312198Y513379D01*
G01X1309911Y520013D02*
X1309861Y520999D01*
G01X1309858Y520037D02*
X1309909Y519051D01*
G01X1308268Y514341D02*
X1308217Y515327D01*
G01X1308215Y514365D02*
X1308265Y513379D01*
G01X1320133Y508640D02*
X1320387Y509010D01*
G01X1320120Y509615D02*
X1320341Y509937D01*
G01X1316201Y508640D02*
X1316454Y509010D01*
G01X1316187Y509615D02*
X1316409Y509937D01*
G01X1316418Y509984D02*
X1316409Y509937D01*
G01X1317456Y524394D02*
X1317465Y524441D01*
G01X1312477Y509984D02*
X1312467Y509937D01*
G01X1313523Y524394D02*
X1313533Y524441D01*
G01X1308535Y509937D02*
X1308544Y509984D01*
G01X1309591Y524441D02*
X1309582Y524394D01*
G01X1309861Y513379D02*
X1309911Y514365D01*
G01X1309909Y515327D02*
X1309858Y514341D01*
G01X1308217Y519051D02*
X1308268Y520037D01*
G01X1308265Y520999D02*
X1308215Y520013D01*
G01X1309937Y519353D02*
X1310073Y525261D01*
G01X1310069Y526147D02*
X1309932Y520239D01*
G01X1308057Y508231D02*
X1308194Y514139D01*
G01X1308189Y515025D02*
X1308053Y509117D01*
G01X1308567Y524394D02*
X1308580Y525368D01*
G01X1308394Y504965D02*
Y503902D01*
G01Y530476D02*
Y529413D01*
G01X1308315Y509618D02*
Y508627D01*
G01Y525751D02*
Y524760D01*
G01X1308236Y525555D02*
Y530396D01*
G01Y503982D02*
Y508823D01*
G01X1308039Y507840D02*
Y508825D01*
G01Y525553D02*
Y526538D01*
G01X1307961Y526539D02*
Y507839D01*
G01X1307882Y509984D02*
Y503902D01*
G01Y530476D02*
Y524394D01*
G01X1312259Y508640D02*
X1312513Y509010D01*
G01X1312246Y509615D02*
X1312467Y509937D01*
G01X1308326Y508640D02*
X1308580Y509010D01*
G01X1308535Y509937D02*
X1308315Y509618D01*
G01X1317687Y524763D02*
X1317465Y524441D01*
G01X1317674Y525738D02*
X1317420Y525368D01*
G01X1313754Y524763D02*
X1313533Y524441D01*
G01X1313741Y525738D02*
X1313487Y525368D01*
G01X1309591Y524441D02*
X1309811Y524760D01*
G01X1309799Y525738D02*
X1309546Y525368D01*
G01X1317724Y582524D02*
Y577012D01*
G01X1325560Y525754D02*
X1325559Y525751D01*
G01X1325560Y525756D02*
Y525754D01*
G01X1325561Y525757D02*
X1325560Y525756D01*
G01X1333434Y525754D02*
X1333433Y525751D01*
G01X1333434Y525756D02*
Y525754D01*
G01X1333435Y525757D02*
X1333434Y525756D01*
G01X1325560Y524768D02*
X1325559Y524763D01*
G01X1325560Y524771D02*
Y524768D01*
G01X1325561Y524772D02*
X1325560Y524771D01*
G01X1324062Y509610D02*
X1324063Y509615D01*
G01X1324062Y509607D02*
Y509610D01*
G01X1324061Y509606D02*
X1324062Y509607D01*
G01X1333434Y524768D02*
X1333433Y524763D01*
G01X1333434Y524771D02*
Y524768D01*
G01X1333435Y524772D02*
X1333434Y524771D01*
G01X1331936Y509610D02*
X1331937Y509615D01*
G01X1331936Y509607D02*
Y509610D01*
G01X1331935Y509606D02*
X1331936Y509607D01*
G01X1324062Y508624D02*
X1324063Y508627D01*
G01X1324062Y508622D02*
Y508624D01*
G01X1324061Y508621D02*
X1324062Y508622D01*
G01X1341308Y525754D02*
X1341307Y525751D01*
G01X1341308Y525756D02*
Y525754D01*
G01X1341309Y525757D02*
X1341308Y525756D01*
G01X1331936Y508624D02*
X1331937Y508627D01*
G01X1331936Y508622D02*
Y508624D01*
G01X1331935Y508621D02*
X1331936Y508622D01*
G01X1349182Y525754D02*
X1349181Y525751D01*
G01X1349182Y525756D02*
Y525754D01*
G01X1349183Y525757D02*
X1349182Y525756D01*
G01X1339810Y508624D02*
X1339811Y508627D01*
G01X1339810Y508622D02*
Y508624D01*
G01X1339809Y508621D02*
X1339810Y508622D01*
G01X1357056Y525754D02*
X1357055Y525751D01*
G01X1357056Y525756D02*
Y525754D01*
G01X1357057Y525757D02*
X1357056Y525756D01*
G01X1347684Y508624D02*
X1347685Y508627D01*
G01X1347684Y508622D02*
Y508624D01*
G01X1347683Y508621D02*
X1347684Y508622D01*
G01X1364930Y525754D02*
X1364929Y525751D01*
G01X1364930Y525756D02*
Y525754D01*
G01X1364931Y525757D02*
X1364930Y525756D01*
G01X1324062Y524771D02*
X1324061Y524772D01*
G01X1324062Y524768D02*
Y524771D01*
G01X1324063Y524763D02*
X1324062Y524768D01*
G01X1325560Y509607D02*
X1325561Y509606D01*
G01X1325560Y509610D02*
Y509607D01*
G01X1325559Y509615D02*
X1325560Y509610D01*
G01X1321887Y507893D02*
X1321893Y507840D01*
G01X1321881Y508025D02*
X1321887Y507893D01*
G01X1321875Y508231D02*
X1321881Y508025D01*
G01X1323794Y526485D02*
X1323787Y526538D01*
G01X1323800Y526353D02*
X1323794Y526485D01*
G01X1323805Y526147D02*
X1323800Y526353D01*
G01X1325828Y507893D02*
X1325835Y507840D01*
G01X1325822Y508025D02*
X1325828Y507893D01*
G01X1325817Y508231D02*
X1325822Y508025D01*
G01X1327735Y526485D02*
X1327729Y526538D01*
G01X1327741Y526353D02*
X1327735Y526485D01*
G01X1327747Y526147D02*
X1327741Y526353D01*
G01X1329761Y507893D02*
X1329767Y507840D01*
G01X1329755Y508025D02*
X1329761Y507893D01*
G01X1329749Y508231D02*
X1329755Y508025D01*
G01X1321888Y508867D02*
X1321893Y508825D01*
G01X1321884Y508965D02*
X1321888Y508867D01*
G01X1321880Y509117D02*
X1321884Y508965D01*
G01X1323792Y525511D02*
X1323787Y525553D01*
G01X1323796Y525413D02*
X1323792Y525511D01*
G01X1323801Y525261D02*
X1323796Y525413D01*
G01X1325830Y508867D02*
X1325835Y508825D01*
G01X1325826Y508965D02*
X1325830Y508867D01*
G01X1325821Y509117D02*
X1325826Y508965D01*
G01X1327734Y525511D02*
X1327729Y525553D01*
G01X1327738Y525413D02*
X1327734Y525511D01*
G01X1327742Y525261D02*
X1327738Y525413D01*
G01X1329762Y508867D02*
X1329767Y508825D01*
G01X1329758Y508965D02*
X1329762Y508867D01*
G01X1329754Y509117D02*
X1329758Y508965D01*
G01X1321631Y524733D02*
X1321627Y524763D01*
G01X1321636Y524537D02*
X1321631Y524733D01*
G01X1321638Y524209D02*
X1321636Y524537D01*
G01X1321639Y523807D02*
X1321638Y524209D01*
G01X1327991Y509645D02*
X1327995Y509615D01*
G01X1327986Y509841D02*
X1327991Y509645D01*
G01X1327984Y510169D02*
X1327986Y509841D01*
G01X1327983Y510571D02*
X1327984Y510169D01*
G01X1329506Y524733D02*
X1329501Y524763D01*
G01X1329510Y524537D02*
X1329506Y524733D01*
G01X1329512Y524209D02*
X1329510Y524537D01*
G01X1329513Y523807D02*
X1329512Y524209D01*
G01X1324053Y508770D02*
X1324061Y508621D01*
G01X1324046Y509184D02*
X1324053Y508770D01*
G01X1324041Y509804D02*
X1324046Y509184D01*
G01X1324039Y510552D02*
X1324041Y509804D01*
G01X1324057Y509679D02*
X1324061Y509606D01*
G01X1324054Y509887D02*
X1324057Y509679D01*
G01X1324051Y510200D02*
X1324054Y509887D01*
G01X1324050Y510571D02*
X1324051Y510200D01*
G01X1325565Y524699D02*
X1325561Y524772D01*
G01X1325568Y524491D02*
X1325565Y524699D01*
G01X1325571Y524178D02*
X1325568Y524491D01*
G01X1325572Y523807D02*
X1325571Y524178D01*
G01X1325569Y525608D02*
X1325561Y525757D01*
G01X1325576Y525193D02*
X1325569Y525608D01*
G01X1325581Y524573D02*
X1325576Y525193D01*
G01X1325583Y523826D02*
X1325581Y524573D01*
G01X1331927Y508770D02*
X1331935Y508621D01*
G01X1331920Y509184D02*
X1331927Y508770D01*
G01X1331915Y509804D02*
X1331920Y509184D01*
G01X1331913Y510552D02*
X1331915Y509804D01*
G01X1331931Y509679D02*
X1331935Y509606D01*
G01X1331928Y509887D02*
X1331931Y509679D01*
G01X1331925Y510200D02*
X1331928Y509887D01*
G01X1331924Y510571D02*
X1331925Y510200D01*
G01X1324041Y524573D02*
X1324039Y523826D01*
G01X1324046Y525193D02*
X1324041Y524573D01*
G01X1324053Y525608D02*
X1324046Y525193D01*
G01X1324061Y525757D02*
X1324053Y525608D01*
G01X1325581Y509804D02*
X1325583Y510552D01*
G01X1325576Y509184D02*
X1325581Y509804D01*
G01X1325569Y508770D02*
X1325576Y509184D01*
G01X1325561Y508621D02*
X1325569Y508770D01*
G01X1331915Y524573D02*
X1331913Y523826D01*
G01X1331920Y525193D02*
X1331915Y524573D01*
G01X1331927Y525608D02*
X1331920Y525193D01*
G01X1331935Y525757D02*
X1331927Y525608D01*
G01X1333455Y509804D02*
X1333457Y510552D01*
G01X1333450Y509184D02*
X1333455Y509804D01*
G01X1333443Y508770D02*
X1333450Y509184D01*
G01X1333435Y508621D02*
X1333443Y508770D01*
G01X1324051Y524178D02*
X1324050Y523807D01*
G01X1324054Y524491D02*
X1324051Y524178D01*
G01X1324057Y524699D02*
X1324054Y524491D01*
G01X1324061Y524772D02*
X1324057Y524699D01*
G01X1325571Y510200D02*
X1325572Y510571D01*
G01X1325568Y509887D02*
X1325571Y510200D01*
G01X1325565Y509679D02*
X1325568Y509887D01*
G01X1325561Y509606D02*
X1325565Y509679D01*
G01X1331925Y524178D02*
X1331924Y523807D01*
G01X1331928Y524491D02*
X1331925Y524178D01*
G01X1331931Y524699D02*
X1331928Y524491D01*
G01X1331935Y524772D02*
X1331931Y524699D01*
G01X1333445Y510200D02*
X1333446Y510571D01*
G01X1333442Y509887D02*
X1333445Y510200D01*
G01X1333439Y509679D02*
X1333442Y509887D01*
G01X1333435Y509606D02*
X1333439Y509679D01*
G01X1321893Y525413D02*
X1321889Y525261D01*
G01X1321898Y525511D02*
X1321893Y525413D01*
G01X1321902Y525553D02*
X1321898Y525511D01*
G01X1323796Y508965D02*
X1323801Y509117D01*
G01X1323792Y508867D02*
X1323796Y508965D01*
G01X1323787Y508825D02*
X1323792Y508867D01*
G01X1325826Y525413D02*
X1325821Y525261D01*
G01X1325830Y525511D02*
X1325826Y525413D01*
G01X1325835Y525553D02*
X1325830Y525511D01*
G01X1327729Y508965D02*
X1327733Y509117D01*
G01X1327724Y508867D02*
X1327729Y508965D01*
G01X1327720Y508825D02*
X1327724Y508867D01*
G01X1329767Y525413D02*
X1329763Y525261D01*
G01X1329772Y525511D02*
X1329767Y525413D01*
G01X1329776Y525553D02*
X1329772Y525511D01*
G01X1331670Y508965D02*
X1331675Y509117D01*
G01X1331666Y508867D02*
X1331670Y508965D01*
G01X1331661Y508825D02*
X1331666Y508867D01*
G01X1333700Y525413D02*
X1333695Y525261D01*
G01X1333704Y525511D02*
X1333700Y525413D01*
G01X1333709Y525553D02*
X1333704Y525511D01*
G01X1335603Y508965D02*
X1335607Y509117D01*
G01X1335598Y508867D02*
X1335603Y508965D01*
G01X1335594Y508825D02*
X1335598Y508867D01*
G01X1337641Y525413D02*
X1337637Y525261D01*
G01X1337646Y525511D02*
X1337641Y525413D01*
G01X1337650Y525553D02*
X1337646Y525511D01*
G01X1321890Y526353D02*
X1321884Y526147D01*
G01X1321896Y526485D02*
X1321890Y526353D01*
G01X1321902Y526538D02*
X1321896Y526485D01*
G01X1325822Y526353D02*
X1325817Y526147D01*
G01X1325828Y526485D02*
X1325822Y526353D01*
G01X1325835Y526538D02*
X1325828Y526485D01*
G01X1323800Y508025D02*
X1323805Y508231D01*
G01X1323794Y507893D02*
X1323800Y508025D01*
G01X1323787Y507840D02*
X1323794Y507893D01*
G01X1329764Y526353D02*
X1329758Y526147D01*
G01X1329770Y526485D02*
X1329764Y526353D01*
G01X1329776Y526538D02*
X1329770Y526485D01*
G01X1327732Y508025D02*
X1327738Y508231D01*
G01X1327726Y507893D02*
X1327732Y508025D01*
G01X1327720Y507840D02*
X1327726Y507893D01*
G01X1333696Y526353D02*
X1333691Y526147D01*
G01X1333702Y526485D02*
X1333696Y526353D01*
G01X1333709Y526538D02*
X1333702Y526485D01*
G01X1331674Y508025D02*
X1331679Y508231D01*
G01X1331668Y507893D02*
X1331674Y508025D01*
G01X1331661Y507840D02*
X1331668Y507893D01*
G01X1337638Y526353D02*
X1337632Y526147D01*
G01X1337644Y526485D02*
X1337638Y526353D01*
G01X1337650Y526538D02*
X1337644Y526485D01*
G01X1335606Y508025D02*
X1335612Y508231D01*
G01X1335600Y507893D02*
X1335606Y508025D01*
G01X1335594Y507840D02*
X1335600Y507893D01*
G01X1321629Y510169D02*
X1321630Y510571D01*
G01X1321626Y509841D02*
X1321629Y510169D01*
G01X1321622Y509645D02*
X1321626Y509841D01*
G01X1321618Y509615D02*
X1321622Y509645D01*
G01X1327993Y524209D02*
X1327992Y523807D01*
G01X1327996Y524537D02*
X1327993Y524209D01*
G01X1328000Y524733D02*
X1327996Y524537D01*
G01X1328004Y524763D02*
X1328000Y524733D01*
G01X1329503Y510169D02*
X1329504Y510571D01*
G01X1329500Y509841D02*
X1329503Y510169D01*
G01X1329496Y509645D02*
X1329500Y509841D01*
G01X1329492Y509615D02*
X1329496Y509645D01*
G01X1335867Y524209D02*
X1335866Y523807D01*
G01X1335870Y524537D02*
X1335867Y524209D01*
G01X1335874Y524733D02*
X1335870Y524537D01*
G01X1335878Y524763D02*
X1335874Y524733D01*
G01X1337377Y510169D02*
X1337378Y510571D01*
G01X1337374Y509841D02*
X1337377Y510169D01*
G01X1337370Y509645D02*
X1337374Y509841D01*
G01X1337366Y509615D02*
X1337370Y509645D01*
G01X1341308Y524768D02*
X1341307Y524763D01*
G01X1341308Y524771D02*
Y524768D01*
G01X1341309Y524772D02*
X1341308Y524771D01*
G01X1339810Y509610D02*
X1339811Y509615D01*
G01X1339810Y509607D02*
Y509610D01*
G01X1339809Y509606D02*
X1339810Y509607D01*
G01X1349182Y524768D02*
X1349181Y524763D01*
G01X1349182Y524771D02*
Y524768D01*
G01X1349183Y524772D02*
X1349182Y524771D01*
G01X1347684Y509610D02*
X1347685Y509615D01*
G01X1347684Y509607D02*
Y509610D01*
G01X1347683Y509606D02*
X1347684Y509607D01*
G01X1357056Y524768D02*
X1357055Y524763D01*
G01X1357056Y524771D02*
Y524768D01*
G01X1357057Y524772D02*
X1357056Y524771D01*
G01X1355558Y509610D02*
X1355559Y509615D01*
G01X1355558Y509607D02*
Y509610D01*
G01X1355557Y509606D02*
X1355558Y509607D01*
G01X1364930Y524768D02*
X1364929Y524763D01*
G01X1364930Y524771D02*
Y524768D01*
G01X1364931Y524772D02*
X1364930Y524771D01*
G01X1355558Y508624D02*
X1355559Y508627D01*
G01X1355558Y508622D02*
Y508624D01*
G01X1355557Y508621D02*
X1355558Y508622D01*
G01X1372804Y525754D02*
X1372803Y525751D01*
G01X1372804Y525756D02*
Y525754D01*
G01X1372805Y525757D02*
X1372804Y525756D01*
G01X1363432Y508624D02*
X1363433Y508627D01*
G01X1363432Y508622D02*
Y508624D01*
G01X1363431Y508621D02*
X1363432Y508622D01*
G01X1380678Y525754D02*
X1380677Y525751D01*
G01X1380678Y525756D02*
Y525754D01*
G01X1380679Y525757D02*
X1380678Y525756D01*
G01X1371307Y508624D02*
Y508627D01*
G01X1371306Y508622D02*
X1371307Y508624D01*
G01X1371305Y508621D02*
X1371306Y508622D01*
G01X1379181Y508624D02*
Y508627D01*
G01X1379180Y508622D02*
X1379181Y508624D01*
G01X1379179Y508621D02*
X1379180Y508622D01*
G01X1331936Y524771D02*
X1331935Y524772D01*
G01X1331936Y524768D02*
Y524771D01*
G01X1331937Y524763D02*
X1331936Y524768D01*
G01X1333434Y509607D02*
X1333435Y509606D01*
G01X1333434Y509610D02*
Y509607D01*
G01X1333433Y509615D02*
X1333434Y509610D01*
G01X1339810Y524771D02*
X1339809Y524772D01*
G01X1339810Y524768D02*
Y524771D01*
G01X1339811Y524763D02*
X1339810Y524768D01*
G01X1341308Y509607D02*
X1341309Y509606D01*
G01X1341308Y509610D02*
Y509607D01*
G01X1341307Y509615D02*
X1341308Y509610D01*
G01X1347684Y524771D02*
X1347683Y524772D01*
G01X1347684Y524768D02*
Y524771D01*
G01X1347685Y524763D02*
X1347684Y524768D01*
G01X1349182Y509607D02*
X1349183Y509606D01*
G01X1349182Y509610D02*
Y509607D01*
G01X1349181Y509615D02*
X1349182Y509610D01*
G01X1331668Y526485D02*
X1331661Y526538D01*
G01X1331674Y526353D02*
X1331668Y526485D01*
G01X1331679Y526147D02*
X1331674Y526353D01*
G01X1333702Y507893D02*
X1333709Y507840D01*
G01X1333696Y508025D02*
X1333702Y507893D01*
G01X1333691Y508231D02*
X1333696Y508025D01*
G01X1335609Y526485D02*
X1335603Y526538D01*
G01X1335615Y526353D02*
X1335609Y526485D01*
G01X1335621Y526147D02*
X1335615Y526353D01*
G01X1337635Y507893D02*
X1337641Y507840D01*
G01X1337629Y508025D02*
X1337635Y507893D01*
G01X1337623Y508231D02*
X1337629Y508025D01*
G01X1339542Y526485D02*
X1339535Y526538D01*
G01X1339548Y526353D02*
X1339542Y526485D01*
G01X1339553Y526147D02*
X1339548Y526353D01*
G01X1341576Y507893D02*
X1341583Y507840D01*
G01X1341570Y508025D02*
X1341576Y507893D01*
G01X1341565Y508231D02*
X1341570Y508025D01*
G01X1343483Y526485D02*
X1343477Y526538D01*
G01X1343489Y526353D02*
X1343483Y526485D01*
G01X1343495Y526147D02*
X1343489Y526353D01*
G01X1345509Y507893D02*
X1345515Y507840D01*
G01X1345503Y508025D02*
X1345509Y507893D01*
G01X1345497Y508231D02*
X1345503Y508025D01*
G01X1347416Y526485D02*
X1347409Y526538D01*
G01X1347422Y526353D02*
X1347416Y526485D01*
G01X1347427Y526147D02*
X1347422Y526353D01*
G01X1349451Y507893D02*
X1349457Y507840D01*
G01X1349444Y508025D02*
X1349451Y507893D01*
G01X1349439Y508231D02*
X1349444Y508025D01*
G01X1351357Y526485D02*
X1351351Y526538D01*
G01X1351363Y526353D02*
X1351357Y526485D01*
G01X1351369Y526147D02*
X1351363Y526353D01*
G01X1353383Y507893D02*
X1353389Y507840D01*
G01X1353377Y508025D02*
X1353383Y507893D01*
G01X1353371Y508231D02*
X1353377Y508025D01*
G01X1355290Y526485D02*
X1355283Y526538D01*
G01X1355296Y526353D02*
X1355290Y526485D01*
G01X1355301Y526147D02*
X1355296Y526353D01*
G01X1331666Y525511D02*
X1331661Y525553D01*
G01X1331670Y525413D02*
X1331666Y525511D01*
G01X1331675Y525261D02*
X1331670Y525413D01*
G01X1333704Y508867D02*
X1333709Y508825D01*
G01X1333700Y508965D02*
X1333704Y508867D01*
G01X1333695Y509117D02*
X1333700Y508965D01*
G01X1335608Y525511D02*
X1335603Y525553D01*
G01X1335612Y525413D02*
X1335608Y525511D01*
G01X1335616Y525261D02*
X1335612Y525413D01*
G01X1337636Y508867D02*
X1337641Y508825D01*
G01X1337632Y508965D02*
X1337636Y508867D01*
G01X1337628Y509117D02*
X1337632Y508965D01*
G01X1339540Y525511D02*
X1339535Y525553D01*
G01X1339544Y525413D02*
X1339540Y525511D01*
G01X1339549Y525261D02*
X1339544Y525413D01*
G01X1341578Y508867D02*
X1341583Y508825D01*
G01X1341574Y508965D02*
X1341578Y508867D01*
G01X1341569Y509117D02*
X1341574Y508965D01*
G01X1343482Y525511D02*
X1343477Y525553D01*
G01X1343486Y525413D02*
X1343482Y525511D01*
G01X1343490Y525261D02*
X1343486Y525413D01*
G01X1345510Y508867D02*
X1345515Y508825D01*
G01X1345506Y508965D02*
X1345510Y508867D01*
G01X1345502Y509117D02*
X1345506Y508965D01*
G01X1347414Y525511D02*
X1347409Y525553D01*
G01X1347418Y525413D02*
X1347414Y525511D01*
G01X1347423Y525261D02*
X1347418Y525413D01*
G01X1349452Y508867D02*
X1349457Y508825D01*
G01X1349448Y508965D02*
X1349452Y508867D01*
G01X1349443Y509117D02*
X1349448Y508965D01*
G01X1351356Y525511D02*
X1351351Y525553D01*
G01X1351360Y525413D02*
X1351356Y525511D01*
G01X1351364Y525261D02*
X1351360Y525413D01*
G01X1353384Y508867D02*
X1353389Y508825D01*
G01X1353380Y508965D02*
X1353384Y508867D01*
G01X1353376Y509117D02*
X1353380Y508965D01*
G01X1355288Y525511D02*
X1355283Y525553D01*
G01X1355292Y525413D02*
X1355288Y525511D01*
G01X1355297Y525261D02*
X1355292Y525413D01*
G01X1335865Y509645D02*
X1335869Y509615D01*
G01X1335861Y509841D02*
X1335865Y509645D01*
G01X1335858Y510169D02*
X1335861Y509841D01*
G01X1335857Y510571D02*
X1335858Y510169D01*
G01X1337380Y524733D02*
X1337375Y524763D01*
G01X1337384Y524537D02*
X1337380Y524733D01*
G01X1337386Y524209D02*
X1337384Y524537D01*
G01X1337387Y523807D02*
X1337386Y524209D01*
G01X1343739Y509645D02*
X1343743Y509615D01*
G01X1343735Y509841D02*
X1343739Y509645D01*
G01X1343732Y510169D02*
X1343735Y509841D01*
G01X1343731Y510571D02*
X1343732Y510169D01*
G01X1345254Y524733D02*
X1345249Y524763D01*
G01X1345258Y524537D02*
X1345254Y524733D01*
G01X1345260Y524209D02*
X1345258Y524537D01*
G01X1345261Y523807D02*
X1345260Y524209D01*
G01X1351613Y509645D02*
X1351617Y509615D01*
G01X1351609Y509841D02*
X1351613Y509645D01*
G01X1351606Y510169D02*
X1351609Y509841D01*
G01X1351605Y510571D02*
X1351606Y510169D01*
G01X1353128Y524733D02*
X1353123Y524763D01*
G01X1353132Y524537D02*
X1353128Y524733D01*
G01X1353134Y524209D02*
X1353132Y524537D01*
G01X1353135Y523807D02*
X1353134Y524209D01*
G01X1333439Y524699D02*
X1333435Y524772D01*
G01X1333442Y524491D02*
X1333439Y524699D01*
G01X1333445Y524178D02*
X1333442Y524491D01*
G01X1333446Y523807D02*
X1333445Y524178D01*
G01X1333443Y525608D02*
X1333435Y525757D01*
G01X1333450Y525193D02*
X1333443Y525608D01*
G01X1333455Y524573D02*
X1333450Y525193D01*
G01X1333457Y523826D02*
X1333455Y524573D01*
G01X1339801Y508770D02*
X1339809Y508621D01*
G01X1339794Y509184D02*
X1339801Y508770D01*
G01X1339789Y509804D02*
X1339794Y509184D01*
G01X1339787Y510552D02*
X1339789Y509804D01*
G01X1339805Y509679D02*
X1339809Y509606D01*
G01X1339802Y509887D02*
X1339805Y509679D01*
G01X1339799Y510200D02*
X1339802Y509887D01*
G01X1339798Y510571D02*
X1339799Y510200D01*
G01X1341313Y524699D02*
X1341309Y524772D01*
G01X1341316Y524491D02*
X1341313Y524699D01*
G01X1341319Y524178D02*
X1341316Y524491D01*
G01X1341320Y523807D02*
X1341319Y524178D01*
G01X1341317Y525608D02*
X1341309Y525757D01*
G01X1341324Y525193D02*
X1341317Y525608D01*
G01X1341329Y524573D02*
X1341324Y525193D01*
G01X1341331Y523826D02*
X1341329Y524573D01*
G01X1347675Y508770D02*
X1347683Y508621D01*
G01X1347668Y509184D02*
X1347675Y508770D01*
G01X1347663Y509804D02*
X1347668Y509184D01*
G01X1347661Y510552D02*
X1347663Y509804D01*
G01X1347679Y509679D02*
X1347683Y509606D01*
G01X1347676Y509887D02*
X1347679Y509679D01*
G01X1347673Y510200D02*
X1347676Y509887D01*
G01X1347672Y510571D02*
X1347673Y510200D01*
G01X1349187Y524699D02*
X1349183Y524772D01*
G01X1349190Y524491D02*
X1349187Y524699D01*
G01X1349193Y524178D02*
X1349190Y524491D01*
G01X1349194Y523807D02*
X1349193Y524178D01*
G01X1349191Y525608D02*
X1349183Y525757D01*
G01X1349198Y525193D02*
X1349191Y525608D01*
G01X1349203Y524573D02*
X1349198Y525193D01*
G01X1349205Y523826D02*
X1349203Y524573D01*
G01X1355549Y508770D02*
X1355557Y508621D01*
G01X1355542Y509184D02*
X1355549Y508770D01*
G01X1355537Y509804D02*
X1355542Y509184D01*
G01X1355535Y510552D02*
X1355537Y509804D01*
G01X1355553Y509679D02*
X1355557Y509606D01*
G01X1355550Y509887D02*
X1355553Y509679D01*
G01X1355547Y510200D02*
X1355550Y509887D01*
G01X1355546Y510571D02*
X1355547Y510200D01*
G01X1357061Y524699D02*
X1357057Y524772D01*
G01X1357064Y524491D02*
X1357061Y524699D01*
G01X1357067Y524178D02*
X1357064Y524491D01*
G01X1357068Y523807D02*
X1357067Y524178D01*
G01X1357065Y525608D02*
X1357057Y525757D01*
G01X1357072Y525193D02*
X1357065Y525608D01*
G01X1357077Y524573D02*
X1357072Y525193D01*
G01X1357079Y523826D02*
X1357077Y524573D01*
G01X1339789D02*
X1339787Y523826D01*
G01X1339794Y525193D02*
X1339789Y524573D01*
G01X1339801Y525608D02*
X1339794Y525193D01*
G01X1339809Y525757D02*
X1339801Y525608D01*
G01X1341329Y509804D02*
X1341331Y510552D01*
G01X1341324Y509184D02*
X1341329Y509804D01*
G01X1341317Y508770D02*
X1341324Y509184D01*
G01X1341309Y508621D02*
X1341317Y508770D01*
G01X1347663Y524573D02*
X1347661Y523826D01*
G01X1347668Y525193D02*
X1347663Y524573D01*
G01X1347675Y525608D02*
X1347668Y525193D01*
G01X1347683Y525757D02*
X1347675Y525608D01*
G01X1349203Y509804D02*
X1349205Y510552D01*
G01X1349198Y509184D02*
X1349203Y509804D01*
G01X1349191Y508770D02*
X1349198Y509184D01*
G01X1349183Y508621D02*
X1349191Y508770D01*
G01X1355537Y524573D02*
X1355535Y523826D01*
G01X1355542Y525193D02*
X1355537Y524573D01*
G01X1355549Y525608D02*
X1355542Y525193D01*
G01X1355557Y525757D02*
X1355549Y525608D01*
G01X1357077Y509804D02*
X1357079Y510552D01*
G01X1357072Y509184D02*
X1357077Y509804D01*
G01X1357065Y508770D02*
X1357072Y509184D01*
G01X1357057Y508621D02*
X1357065Y508770D01*
G01X1339799Y524178D02*
X1339798Y523807D01*
G01X1339802Y524491D02*
X1339799Y524178D01*
G01X1339805Y524699D02*
X1339802Y524491D01*
G01X1339809Y524772D02*
X1339805Y524699D01*
G01X1341319Y510200D02*
X1341320Y510571D01*
G01X1341316Y509887D02*
X1341319Y510200D01*
G01X1341313Y509679D02*
X1341316Y509887D01*
G01X1341309Y509606D02*
X1341313Y509679D01*
G01X1347673Y524178D02*
X1347672Y523807D01*
G01X1347676Y524491D02*
X1347673Y524178D01*
G01X1347679Y524699D02*
X1347676Y524491D01*
G01X1347683Y524772D02*
X1347679Y524699D01*
G01X1349193Y510200D02*
X1349194Y510571D01*
G01X1349190Y509887D02*
X1349193Y510200D01*
G01X1349187Y509679D02*
X1349190Y509887D01*
G01X1349183Y509606D02*
X1349187Y509679D01*
G01X1355547Y524178D02*
X1355546Y523807D01*
G01X1355550Y524491D02*
X1355547Y524178D01*
G01X1355553Y524699D02*
X1355550Y524491D01*
G01X1355557Y524772D02*
X1355553Y524699D01*
G01X1357067Y510200D02*
X1357068Y510571D01*
G01X1357064Y509887D02*
X1357067Y510200D01*
G01X1357061Y509679D02*
X1357064Y509887D01*
G01X1357057Y509606D02*
X1357061Y509679D01*
G01X1339544Y508965D02*
X1339549Y509117D01*
G01X1339540Y508867D02*
X1339544Y508965D01*
G01X1339535Y508825D02*
X1339540Y508867D01*
G01X1341574Y525413D02*
X1341569Y525261D01*
G01X1341578Y525511D02*
X1341574Y525413D01*
G01X1341583Y525553D02*
X1341578Y525511D01*
G01X1343477Y508965D02*
X1343481Y509117D01*
G01X1343472Y508867D02*
X1343477Y508965D01*
G01X1343468Y508825D02*
X1343472Y508867D01*
G01X1345515Y525413D02*
X1345511Y525261D01*
G01X1345520Y525511D02*
X1345515Y525413D01*
G01X1345524Y525553D02*
X1345520Y525511D01*
G01X1347418Y508965D02*
X1347423Y509117D01*
G01X1347414Y508867D02*
X1347418Y508965D01*
G01X1347409Y508825D02*
X1347414Y508867D01*
G01X1349448Y525413D02*
X1349443Y525261D01*
G01X1349452Y525511D02*
X1349448Y525413D01*
G01X1349457Y525553D02*
X1349452Y525511D01*
G01X1351351Y508965D02*
X1351355Y509117D01*
G01X1351346Y508867D02*
X1351351Y508965D01*
G01X1351342Y508825D02*
X1351346Y508867D01*
G01X1353389Y525413D02*
X1353385Y525261D01*
G01X1353394Y525511D02*
X1353389Y525413D01*
G01X1353398Y525553D02*
X1353394Y525511D01*
G01X1355292Y508965D02*
X1355297Y509117D01*
G01X1355288Y508867D02*
X1355292Y508965D01*
G01X1355283Y508825D02*
X1355288Y508867D01*
G01X1357322Y525413D02*
X1357317Y525261D01*
G01X1357326Y525511D02*
X1357322Y525413D01*
G01X1357331Y525553D02*
X1357326Y525511D01*
G01X1359225Y508965D02*
X1359229Y509117D01*
G01X1359220Y508867D02*
X1359225Y508965D01*
G01X1359216Y508825D02*
X1359220Y508867D01*
G01X1361263Y525413D02*
X1361259Y525261D01*
G01X1361268Y525511D02*
X1361263Y525413D01*
G01X1361272Y525553D02*
X1361268Y525511D01*
G01X1363166Y508965D02*
X1363171Y509117D01*
G01X1363162Y508867D02*
X1363166Y508965D01*
G01X1363157Y508825D02*
X1363162Y508867D01*
G01X1341570Y526353D02*
X1341565Y526147D01*
G01X1341576Y526485D02*
X1341570Y526353D01*
G01X1341583Y526538D02*
X1341576Y526485D01*
G01X1339548Y508025D02*
X1339553Y508231D01*
G01X1339542Y507893D02*
X1339548Y508025D01*
G01X1339535Y507840D02*
X1339542Y507893D01*
G01X1345512Y526353D02*
X1345506Y526147D01*
G01X1345518Y526485D02*
X1345512Y526353D01*
G01X1345524Y526538D02*
X1345518Y526485D01*
G01X1343480Y508025D02*
X1343486Y508231D01*
G01X1343474Y507893D02*
X1343480Y508025D01*
G01X1343468Y507840D02*
X1343474Y507893D01*
G01X1349444Y526353D02*
X1349439Y526147D01*
G01X1349451Y526485D02*
X1349444Y526353D01*
G01X1349457Y526538D02*
X1349451Y526485D01*
G01X1347422Y508025D02*
X1347427Y508231D01*
G01X1347416Y507893D02*
X1347422Y508025D01*
G01X1347409Y507840D02*
X1347416Y507893D01*
G01X1353386Y526353D02*
X1353380Y526147D01*
G01X1353392Y526485D02*
X1353386Y526353D01*
G01X1353398Y526538D02*
X1353392Y526485D01*
G01X1351354Y508025D02*
X1351360Y508231D01*
G01X1351348Y507893D02*
X1351354Y508025D01*
G01X1351342Y507840D02*
X1351348Y507893D01*
G01X1357318Y526353D02*
X1357313Y526147D01*
G01X1357325Y526485D02*
X1357318Y526353D01*
G01X1357331Y526538D02*
X1357325Y526485D01*
G01X1355296Y508025D02*
X1355301Y508231D01*
G01X1355290Y507893D02*
X1355296Y508025D01*
G01X1355283Y507840D02*
X1355290Y507893D01*
G01X1361260Y526353D02*
X1361254Y526147D01*
G01X1361266Y526485D02*
X1361260Y526353D01*
G01X1361272Y526538D02*
X1361266Y526485D01*
G01X1359228Y508025D02*
X1359234Y508231D01*
G01X1359222Y507893D02*
X1359228Y508025D01*
G01X1359216Y507840D02*
X1359222Y507893D01*
G01X1365192Y526353D02*
X1365187Y526147D01*
G01X1365199Y526485D02*
X1365192Y526353D01*
G01X1365205Y526538D02*
X1365199Y526485D01*
G01X1363170Y508025D02*
X1363175Y508231D01*
G01X1363164Y507893D02*
X1363170Y508025D01*
G01X1363157Y507840D02*
X1363164Y507893D01*
G01X1343741Y524209D02*
X1343740Y523807D01*
G01X1343744Y524537D02*
X1343741Y524209D01*
G01X1343748Y524733D02*
X1343744Y524537D01*
G01X1343753Y524763D02*
X1343748Y524733D01*
G01X1345251Y510169D02*
X1345252Y510571D01*
G01X1345248Y509841D02*
X1345251Y510169D01*
G01X1345244Y509645D02*
X1345248Y509841D01*
G01X1345240Y509615D02*
X1345244Y509645D01*
G01X1351615Y524209D02*
X1351614Y523807D01*
G01X1351618Y524537D02*
X1351615Y524209D01*
G01X1351622Y524733D02*
X1351618Y524537D01*
G01X1351627Y524763D02*
X1351622Y524733D01*
G01X1353125Y510169D02*
X1353126Y510571D01*
G01X1353122Y509841D02*
X1353125Y510169D01*
G01X1353118Y509645D02*
X1353122Y509841D01*
G01X1353114Y509615D02*
X1353118Y509645D01*
G01X1359489Y524209D02*
X1359488Y523807D01*
G01X1359492Y524537D02*
X1359489Y524209D01*
G01X1359496Y524733D02*
X1359492Y524537D01*
G01X1359501Y524763D02*
X1359496Y524733D01*
G01X1360999Y510169D02*
X1361000Y510571D01*
G01X1360996Y509841D02*
X1360999Y510169D01*
G01X1360992Y509645D02*
X1360996Y509841D01*
G01X1360988Y509615D02*
X1360992Y509645D01*
G01X1367363Y524209D02*
X1367362Y523807D01*
G01X1367366Y524537D02*
X1367363Y524209D01*
G01X1367370Y524733D02*
X1367366Y524537D01*
G01X1367375Y524763D02*
X1367370Y524733D01*
G01X1363432Y509610D02*
X1363433Y509615D01*
G01X1363432Y509607D02*
Y509610D01*
G01X1363431Y509606D02*
X1363432Y509607D01*
G01X1387054Y509610D02*
X1387055Y509615D01*
G01X1387054Y509607D02*
Y509610D01*
G01X1387053Y509606D02*
X1387054Y509607D01*
G01X1387055Y508624D02*
Y508627D01*
G01X1387054Y508622D02*
X1387055Y508624D01*
G01X1387053Y508621D02*
X1387054Y508622D01*
G01X1386750Y508823D02*
X1386734D01*
G01X1386765Y508824D02*
X1386750Y508823D01*
G01X1386780Y508825D02*
X1386765Y508824D01*
G01X1382808Y508823D02*
X1382793D01*
G01X1382823Y508824D02*
X1382808Y508823D01*
G01X1382838Y508825D02*
X1382823Y508824D01*
G01X1378876Y508823D02*
X1378860D01*
G01X1378890Y508824D02*
X1378876Y508823D01*
G01X1378906Y508825D02*
X1378890Y508824D01*
G01X1371001Y508823D02*
X1370986D01*
G01X1371016Y508824D02*
X1371001Y508823D01*
G01X1371031Y508825D02*
X1371016Y508824D01*
G01X1363127Y508823D02*
X1363112D01*
G01X1363142Y508824D02*
X1363127Y508823D01*
G01X1363157Y508825D02*
X1363142Y508824D01*
G01X1359186Y508823D02*
X1359171D01*
G01X1359201Y508824D02*
X1359186Y508823D01*
G01X1359216Y508825D02*
X1359201Y508824D01*
G01X1355253Y508823D02*
X1355238D01*
G01X1355268Y508824D02*
X1355253Y508823D01*
G01X1355283Y508825D02*
X1355268Y508824D01*
G01X1351312Y508823D02*
X1351297D01*
G01X1351327Y508824D02*
X1351312Y508823D01*
G01X1351342Y508825D02*
X1351327Y508824D01*
G01X1347379Y508823D02*
X1347364D01*
G01X1347394Y508824D02*
X1347379Y508823D01*
G01X1347409Y508825D02*
X1347394Y508824D01*
G01X1343438Y508823D02*
X1343423D01*
G01X1343453Y508824D02*
X1343438Y508823D01*
G01X1343468Y508825D02*
X1343453Y508824D01*
G01X1339505Y508823D02*
X1339490D01*
G01X1339520Y508824D02*
X1339505Y508823D01*
G01X1339535Y508825D02*
X1339520Y508824D01*
G01X1335564Y508823D02*
X1335549D01*
G01X1335579Y508824D02*
X1335564Y508823D01*
G01X1335594Y508825D02*
X1335579Y508824D01*
G01X1331631Y508823D02*
X1331616D01*
G01X1331646Y508824D02*
X1331631Y508823D01*
G01X1331661Y508825D02*
X1331646Y508824D01*
G01X1327690Y508823D02*
X1327675D01*
G01X1327705Y508824D02*
X1327690Y508823D01*
G01X1327720Y508825D02*
X1327705Y508824D01*
G01X1323757Y508823D02*
X1323742D01*
G01X1323772Y508824D02*
X1323757Y508823D01*
G01X1323787Y508825D02*
X1323772Y508824D01*
G01X1386750Y507839D02*
X1386734D01*
G01X1386765D02*
X1386750D01*
G01X1386780Y507840D02*
X1386765Y507839D01*
G01X1382808D02*
X1382793D01*
G01X1382823D02*
X1382808D01*
G01X1382838Y507840D02*
X1382823Y507839D01*
G01X1374934D02*
X1374919D01*
G01X1374949D02*
X1374934D01*
G01X1374964Y507840D02*
X1374949Y507839D01*
G01X1367060D02*
X1367045D01*
G01X1367075D02*
X1367060D01*
G01X1367090Y507840D02*
X1367075Y507839D01*
G01X1363127D02*
X1363112D01*
G01X1363142D02*
X1363127D01*
G01X1363157Y507840D02*
X1363142Y507839D01*
G01X1359186D02*
X1359171D01*
G01X1359201D02*
X1359186D01*
G01X1359216Y507840D02*
X1359201Y507839D01*
G01X1355253D02*
X1355238D01*
G01X1355268D02*
X1355253D01*
G01X1355283Y507840D02*
X1355268Y507839D01*
G01X1351312D02*
X1351297D01*
G01X1351327D02*
X1351312D01*
G01X1351342Y507840D02*
X1351327Y507839D01*
G01X1347379D02*
X1347364D01*
G01X1347394D02*
X1347379D01*
G01X1347409Y507840D02*
X1347394Y507839D01*
G01X1343438D02*
X1343423D01*
G01X1343453D02*
X1343438D01*
G01X1343468Y507840D02*
X1343453Y507839D01*
G01X1339505D02*
X1339490D01*
G01X1339520D02*
X1339505D01*
G01X1339535Y507840D02*
X1339520Y507839D01*
G01X1335564D02*
X1335549D01*
G01X1335579D02*
X1335564D01*
G01X1335594Y507840D02*
X1335579Y507839D01*
G01X1331631D02*
X1331616D01*
G01X1331646D02*
X1331631D01*
G01X1331661Y507840D02*
X1331646Y507839D01*
G01X1327690D02*
X1327675D01*
G01X1327705D02*
X1327690D01*
G01X1327720Y507840D02*
X1327705Y507839D01*
G01X1323757D02*
X1323742D01*
G01X1323772D02*
X1323757D01*
G01X1323787Y507840D02*
X1323772Y507839D01*
G01X1321908D02*
X1321893Y507840D01*
G01X1321923Y507839D02*
X1321908D01*
G01X1321938D02*
X1321923D01*
G01X1325850D02*
X1325835Y507840D01*
G01X1325865Y507839D02*
X1325850D01*
G01X1325880D02*
X1325865D01*
G01X1329782D02*
X1329767Y507840D01*
G01X1329797Y507839D02*
X1329782D01*
G01X1329812D02*
X1329797D01*
G01X1333724D02*
X1333709Y507840D01*
G01X1333739Y507839D02*
X1333724D01*
G01X1333754D02*
X1333739D01*
G01X1337656D02*
X1337641Y507840D01*
G01X1337671Y507839D02*
X1337656D01*
G01X1337686D02*
X1337671D01*
G01X1341598D02*
X1341583Y507840D01*
G01X1341613Y507839D02*
X1341598D01*
G01X1341628D02*
X1341613D01*
G01X1345530D02*
X1345515Y507840D01*
G01X1345545Y507839D02*
X1345530D01*
G01X1345560D02*
X1345545D01*
G01X1349472D02*
X1349457Y507840D01*
G01X1349487Y507839D02*
X1349472D01*
G01X1349502D02*
X1349487D01*
G01X1353404D02*
X1353389Y507840D01*
G01X1353419Y507839D02*
X1353404D01*
G01X1353434D02*
X1353419D01*
G01X1357346D02*
X1357331Y507840D01*
G01X1357361Y507839D02*
X1357346D01*
G01X1357376D02*
X1357361D01*
G01X1361278D02*
X1361263Y507840D01*
G01X1361293Y507839D02*
X1361278D01*
G01X1361308D02*
X1361293D01*
G01X1365220D02*
X1365205Y507840D01*
G01X1365235Y507839D02*
X1365220D01*
G01X1365250D02*
X1365235D01*
G01X1369152D02*
X1369137Y507840D01*
G01X1369167Y507839D02*
X1369152D01*
G01X1369182D02*
X1369167D01*
G01X1373094D02*
X1373079Y507840D01*
G01X1373109Y507839D02*
X1373094D01*
G01X1373124D02*
X1373109D01*
G01X1377026D02*
X1377011Y507840D01*
G01X1377041Y507839D02*
X1377026D01*
G01X1377056D02*
X1377041D01*
G01X1380968D02*
X1380953Y507840D01*
G01X1380983Y507839D02*
X1380968D01*
G01X1380998D02*
X1380983D01*
G01X1384900D02*
X1384885Y507840D01*
G01X1384915Y507839D02*
X1384900D01*
G01X1384930D02*
X1384915D01*
G01X1321908Y508824D02*
X1321893Y508825D01*
G01X1321923Y508823D02*
X1321908Y508824D01*
G01X1321938Y508823D02*
X1321923D01*
G01X1325850Y508824D02*
X1325835Y508825D01*
G01X1325865Y508823D02*
X1325850Y508824D01*
G01X1325880Y508823D02*
X1325865D01*
G01X1329782Y508824D02*
X1329767Y508825D01*
G01X1329797Y508823D02*
X1329782Y508824D01*
G01X1329812Y508823D02*
X1329797D01*
G01X1333724Y508824D02*
X1333709Y508825D01*
G01X1333739Y508823D02*
X1333724Y508824D01*
G01X1333754Y508823D02*
X1333739D01*
G01X1337656Y508824D02*
X1337641Y508825D01*
G01X1337671Y508823D02*
X1337656Y508824D01*
G01X1337686Y508823D02*
X1337671D01*
G01X1341598Y508824D02*
X1341583Y508825D01*
G01X1341613Y508823D02*
X1341598Y508824D01*
G01X1341628Y508823D02*
X1341613D01*
G01X1345530Y508824D02*
X1345515Y508825D01*
G01X1345545Y508823D02*
X1345530Y508824D01*
G01X1345560Y508823D02*
X1345545D01*
G01X1349472Y508824D02*
X1349457Y508825D01*
G01X1349487Y508823D02*
X1349472Y508824D01*
G01X1349502Y508823D02*
X1349487D01*
G01X1353404Y508824D02*
X1353389Y508825D01*
G01X1353419Y508823D02*
X1353404Y508824D01*
G01X1353434Y508823D02*
X1353419D01*
G01X1357346Y508824D02*
X1357331Y508825D01*
G01X1357361Y508823D02*
X1357346Y508824D01*
G01X1357376Y508823D02*
X1357361D01*
G01X1361278Y508824D02*
X1361263Y508825D01*
G01X1361293Y508823D02*
X1361278Y508824D01*
G01X1361308Y508823D02*
X1361293D01*
G01X1365220Y508824D02*
X1365205Y508825D01*
G01X1365235Y508823D02*
X1365220Y508824D01*
G01X1365250Y508823D02*
X1365235D01*
G01X1373094Y508824D02*
X1373079Y508825D01*
G01X1373109Y508823D02*
X1373094Y508824D01*
G01X1373124Y508823D02*
X1373109D01*
G01X1380968Y508824D02*
X1380953Y508825D01*
G01X1380983Y508823D02*
X1380968Y508824D01*
G01X1380998Y508823D02*
X1380983D01*
G01X1384900Y508824D02*
X1384885Y508825D01*
G01X1384915Y508823D02*
X1384900Y508824D01*
G01X1384930Y508823D02*
X1384915D01*
G01X1325560Y508622D02*
X1325561Y508621D01*
G01X1325560Y508624D02*
Y508622D01*
G01X1325559Y508627D02*
X1325560Y508624D01*
G01X1324062Y525756D02*
X1324061Y525757D01*
G01X1324062Y525754D02*
Y525756D01*
G01X1324063Y525751D02*
X1324062Y525754D01*
G01X1333434Y508622D02*
X1333435Y508621D01*
G01X1333434Y508624D02*
Y508622D01*
G01X1333433Y508627D02*
X1333434Y508624D01*
G01X1331936Y525756D02*
X1331935Y525757D01*
G01X1331936Y525754D02*
Y525756D01*
G01X1331937Y525751D02*
X1331936Y525754D01*
G01X1341308Y508622D02*
X1341309Y508621D01*
G01X1341308Y508624D02*
Y508622D01*
G01X1341307Y508627D02*
X1341308Y508624D01*
G01X1339810Y525756D02*
X1339809Y525757D01*
G01X1339810Y525754D02*
Y525756D01*
G01X1339811Y525751D02*
X1339810Y525754D01*
G01X1349182Y508622D02*
X1349183Y508621D01*
G01X1349182Y508624D02*
Y508622D01*
G01X1349181Y508627D02*
X1349182Y508624D01*
G01X1355558Y524771D02*
X1355557Y524772D01*
G01X1355558Y524768D02*
Y524771D01*
G01X1355559Y524763D02*
X1355558Y524768D01*
G01X1357056Y509607D02*
X1357057Y509606D01*
G01X1357056Y509610D02*
Y509607D01*
G01X1357055Y509615D02*
X1357056Y509610D01*
G01X1363432Y524771D02*
X1363431Y524772D01*
G01X1363432Y524768D02*
Y524771D01*
G01X1363433Y524763D02*
X1363432Y524768D01*
G01X1364930Y509607D02*
X1364931Y509606D01*
G01X1364930Y509610D02*
Y509607D01*
G01X1364929Y509615D02*
X1364930Y509610D01*
G01X1371295Y510197D02*
X1371294Y510571D01*
G01X1371298Y509887D02*
X1371295Y510197D01*
G01X1371301Y509680D02*
X1371298Y509887D01*
G01X1371305Y509606D02*
X1371301Y509680D01*
G01X1372815Y524181D02*
X1372816Y523807D01*
G01X1372813Y524491D02*
X1372815Y524181D01*
G01X1372809Y524698D02*
X1372813Y524491D01*
G01X1372805Y524772D02*
X1372809Y524698D01*
G01X1379169Y510197D02*
X1379168Y510571D01*
G01X1379172Y509887D02*
X1379169Y510197D01*
G01X1379175Y509680D02*
X1379172Y509887D01*
G01X1379179Y509606D02*
X1379175Y509680D01*
G01X1357325Y507893D02*
X1357331Y507840D01*
G01X1357318Y508025D02*
X1357325Y507893D01*
G01X1357313Y508231D02*
X1357318Y508025D01*
G01X1359231Y526485D02*
X1359225Y526538D01*
G01X1359237Y526353D02*
X1359231Y526485D01*
G01X1359243Y526147D02*
X1359237Y526353D01*
G01X1361257Y507893D02*
X1361263Y507840D01*
G01X1361251Y508025D02*
X1361257Y507893D01*
G01X1361245Y508231D02*
X1361251Y508025D01*
G01X1363164Y526485D02*
X1363157Y526538D01*
G01X1363170Y526353D02*
X1363164Y526485D01*
G01X1363175Y526147D02*
X1363170Y526353D01*
G01X1365199Y507893D02*
X1365205Y507840D01*
G01X1365192Y508025D02*
X1365199Y507893D01*
G01X1365187Y508231D02*
X1365192Y508025D01*
G01X1367105Y526485D02*
X1367099Y526538D01*
G01X1367111Y526353D02*
X1367105Y526485D01*
G01X1367117Y526147D02*
X1367111Y526353D01*
G01X1369131Y507893D02*
X1369137Y507840D01*
G01X1369125Y508025D02*
X1369131Y507893D01*
G01X1369119Y508231D02*
X1369125Y508025D01*
G01X1371038Y526485D02*
X1371031Y526538D01*
G01X1371044Y526353D02*
X1371038Y526485D01*
G01X1371049Y526147D02*
X1371044Y526353D01*
G01X1373073Y507893D02*
X1373079Y507840D01*
G01X1373067Y508025D02*
X1373073Y507893D01*
G01X1373061Y508231D02*
X1373067Y508025D01*
G01X1374979Y526485D02*
X1374973Y526538D01*
G01X1374985Y526353D02*
X1374979Y526485D01*
G01X1374991Y526147D02*
X1374985Y526353D01*
G01X1377005Y507893D02*
X1377011Y507840D01*
G01X1376999Y508025D02*
X1377005Y507893D01*
G01X1376993Y508231D02*
X1376999Y508025D01*
G01X1378912Y526485D02*
X1378906Y526538D01*
G01X1378918Y526353D02*
X1378912Y526485D01*
G01X1378924Y526147D02*
X1378918Y526353D01*
G01X1357326Y508867D02*
X1357331Y508825D01*
G01X1357322Y508965D02*
X1357326Y508867D01*
G01X1357317Y509117D02*
X1357322Y508965D01*
G01X1359230Y525511D02*
X1359225Y525553D01*
G01X1359234Y525413D02*
X1359230Y525511D01*
G01X1359238Y525261D02*
X1359234Y525413D01*
G01X1361258Y508867D02*
X1361263Y508825D01*
G01X1361254Y508965D02*
X1361258Y508867D01*
G01X1361250Y509117D02*
X1361254Y508965D01*
G01X1363162Y525511D02*
X1363157Y525553D01*
G01X1363166Y525413D02*
X1363162Y525511D01*
G01X1363171Y525261D02*
X1363166Y525413D01*
G01X1365200Y508867D02*
X1365205Y508825D01*
G01X1365196Y508965D02*
X1365200Y508867D01*
G01X1365192Y509117D02*
X1365196Y508965D01*
G01X1367104Y525511D02*
X1367099Y525553D01*
G01X1367108Y525413D02*
X1367104Y525511D01*
G01X1367112Y525261D02*
X1367108Y525413D01*
G01X1369133Y508867D02*
X1369137Y508825D01*
G01X1369128Y508965D02*
X1369133Y508867D01*
G01X1369124Y509117D02*
X1369128Y508965D01*
G01X1371036Y525511D02*
X1371031Y525553D01*
G01X1371040Y525413D02*
X1371036Y525511D01*
G01X1371045Y525261D02*
X1371040Y525413D01*
G01X1373074Y508867D02*
X1373079Y508825D01*
G01X1373070Y508965D02*
X1373074Y508867D01*
G01X1373066Y509117D02*
X1373070Y508965D01*
G01X1374978Y525511D02*
X1374973Y525553D01*
G01X1374982Y525413D02*
X1374978Y525511D01*
G01X1374986Y525261D02*
X1374982Y525413D01*
G01X1377007Y508867D02*
X1377011Y508825D01*
G01X1377002Y508965D02*
X1377007Y508867D01*
G01X1376998Y509117D02*
X1377002Y508965D01*
G01X1378910Y525511D02*
X1378906Y525553D01*
G01X1378914Y525413D02*
X1378910Y525511D01*
G01X1378919Y525261D02*
X1378914Y525413D01*
G01X1359487Y509645D02*
X1359491Y509615D01*
G01X1359483Y509841D02*
X1359487Y509645D01*
G01X1359480Y510169D02*
X1359483Y509841D01*
G01X1359479Y510571D02*
X1359480Y510169D01*
G01X1361002Y524733D02*
X1360997Y524763D01*
G01X1361006Y524537D02*
X1361002Y524733D01*
G01X1361008Y524209D02*
X1361006Y524537D01*
G01X1361009Y523807D02*
X1361008Y524209D01*
G01X1367361Y509645D02*
X1367365Y509615D01*
G01X1367357Y509841D02*
X1367361Y509645D01*
G01X1367354Y510169D02*
X1367357Y509841D01*
G01X1367353Y510571D02*
X1367354Y510169D01*
G01X1368876Y524733D02*
X1368871Y524763D01*
G01X1368880Y524537D02*
X1368876Y524733D01*
G01X1368882Y524209D02*
X1368880Y524537D01*
G01X1368883Y523807D02*
X1368882Y524209D01*
G01X1375235Y509645D02*
X1375239Y509615D01*
G01X1375231Y509841D02*
X1375235Y509645D01*
G01X1375228Y510169D02*
X1375231Y509841D01*
G01X1375227Y510571D02*
X1375228Y510169D01*
G01X1376750Y524733D02*
X1376745Y524763D01*
G01X1376754Y524537D02*
X1376750Y524733D01*
G01X1376756Y524209D02*
X1376754Y524537D01*
G01X1376758Y523807D02*
X1376756Y524209D01*
G01X1363423Y508770D02*
X1363431Y508621D01*
G01X1363416Y509184D02*
X1363423Y508770D01*
G01X1363411Y509804D02*
X1363416Y509184D01*
G01X1363409Y510552D02*
X1363411Y509804D01*
G01X1363427Y509679D02*
X1363431Y509606D01*
G01X1363424Y509887D02*
X1363427Y509679D01*
G01X1363421Y510200D02*
X1363424Y509887D01*
G01X1363420Y510571D02*
X1363421Y510200D01*
G01X1364935Y524699D02*
X1364931Y524772D01*
G01X1364939Y524491D02*
X1364935Y524699D01*
G01X1364941Y524178D02*
X1364939Y524491D01*
G01X1364942Y523807D02*
X1364941Y524178D01*
G01X1364939Y525608D02*
X1364931Y525757D01*
G01X1364946Y525193D02*
X1364939Y525608D01*
G01X1364951Y524573D02*
X1364946Y525193D01*
G01X1364953Y523826D02*
X1364951Y524573D01*
G01X1371297Y508770D02*
X1371305Y508621D01*
G01X1371290Y509184D02*
X1371297Y508770D01*
G01X1371285Y509804D02*
X1371290Y509184D01*
G01X1371283Y510552D02*
X1371285Y509804D01*
G01X1372813Y525608D02*
X1372805Y525757D01*
G01X1372820Y525193D02*
X1372813Y525608D01*
G01X1372825Y524573D02*
X1372820Y525193D01*
G01X1372827Y523826D02*
X1372825Y524573D01*
G01X1379171Y508770D02*
X1379179Y508621D01*
G01X1379164Y509184D02*
X1379171Y508770D01*
G01X1379159Y509804D02*
X1379164Y509184D01*
G01X1379157Y510552D02*
X1379159Y509804D01*
G01X1380687Y525608D02*
X1380679Y525757D01*
G01X1380694Y525193D02*
X1380687Y525608D01*
G01X1380699Y524573D02*
X1380694Y525193D01*
G01X1380701Y523826D02*
X1380699Y524573D01*
G01X1371301Y524698D02*
X1371305Y524772D01*
G01X1371298Y524491D02*
X1371301Y524698D01*
G01X1371295Y524181D02*
X1371298Y524491D01*
G01X1371294Y523807D02*
X1371295Y524181D01*
G01X1372809Y509680D02*
X1372805Y509606D01*
G01X1372813Y509887D02*
X1372809Y509680D01*
G01X1372815Y510197D02*
X1372813Y509887D01*
G01X1372816Y510571D02*
X1372815Y510197D01*
G01X1379175Y524698D02*
X1379179Y524772D01*
G01X1379172Y524491D02*
X1379175Y524698D01*
G01X1379169Y524181D02*
X1379172Y524491D01*
G01X1379168Y523807D02*
X1379169Y524181D01*
G01X1380683Y509680D02*
X1380679Y509606D01*
G01X1380687Y509887D02*
X1380683Y509680D01*
G01X1380689Y510197D02*
X1380687Y509887D01*
G01X1380690Y510571D02*
X1380689Y510197D01*
G01X1363411Y524573D02*
X1363409Y523826D01*
G01X1363416Y525193D02*
X1363411Y524573D01*
G01X1363423Y525608D02*
X1363416Y525193D01*
G01X1363431Y525757D02*
X1363423Y525608D01*
G01X1364951Y509804D02*
X1364953Y510552D01*
G01X1364946Y509184D02*
X1364951Y509804D01*
G01X1364939Y508770D02*
X1364946Y509184D01*
G01X1364931Y508621D02*
X1364939Y508770D01*
G01X1371285Y524573D02*
X1371283Y523826D01*
G01X1371290Y525193D02*
X1371285Y524573D01*
G01X1371297Y525608D02*
X1371290Y525193D01*
G01X1371305Y525757D02*
X1371297Y525608D01*
G01X1372825Y509804D02*
X1372827Y510552D01*
G01X1372820Y509184D02*
X1372825Y509804D01*
G01X1372813Y508770D02*
X1372820Y509184D01*
G01X1372805Y508621D02*
X1372813Y508770D01*
G01X1379159Y524573D02*
X1379157Y523826D01*
G01X1379164Y525193D02*
X1379159Y524573D01*
G01X1379171Y525608D02*
X1379164Y525193D01*
G01X1379179Y525757D02*
X1379171Y525608D01*
G01X1380699Y509804D02*
X1380701Y510552D01*
G01X1380694Y509184D02*
X1380699Y509804D01*
G01X1380687Y508770D02*
X1380694Y509184D01*
G01X1380679Y508621D02*
X1380687Y508770D01*
G01X1363421Y524178D02*
X1363420Y523807D01*
G01X1363424Y524491D02*
X1363421Y524178D01*
G01X1363427Y524699D02*
X1363424Y524491D01*
G01X1363431Y524772D02*
X1363427Y524699D01*
G01X1364941Y510200D02*
X1364942Y510571D01*
G01X1364939Y509887D02*
X1364941Y510200D01*
G01X1364935Y509679D02*
X1364939Y509887D01*
G01X1364931Y509606D02*
X1364935Y509679D01*
G01X1371306Y509607D02*
X1371305Y509606D01*
G01X1371306Y509610D02*
Y509607D01*
G01X1371307Y509617D02*
X1371306Y509610D01*
G01X1372804Y524771D02*
X1372805Y524772D01*
G01X1372804Y524768D02*
Y524771D01*
G01X1372803Y524761D02*
X1372804Y524768D01*
G01X1379180Y509607D02*
X1379179Y509606D01*
G01X1379180Y509610D02*
Y509607D01*
G01X1379181Y509617D02*
X1379180Y509610D01*
G01X1380678Y524771D02*
X1380679Y524772D01*
G01X1380678Y524768D02*
Y524771D01*
G01X1380677Y524761D02*
X1380678Y524768D01*
G01X1365196Y525413D02*
X1365192Y525261D01*
G01X1365200Y525511D02*
X1365196Y525413D01*
G01X1365205Y525553D02*
X1365200Y525511D01*
G01X1367099Y508965D02*
X1367103Y509117D01*
G01X1367094Y508867D02*
X1367099Y508965D01*
G01X1367090Y508825D02*
X1367094Y508867D01*
G01X1369137Y525413D02*
X1369133Y525261D01*
G01X1369142Y525511D02*
X1369137Y525413D01*
G01X1369146Y525553D02*
X1369142Y525511D01*
G01X1371040Y508965D02*
X1371045Y509117D01*
G01X1371036Y508867D02*
X1371040Y508965D01*
G01X1371031Y508825D02*
X1371036Y508867D01*
G01X1373070Y525413D02*
X1373066Y525261D01*
G01X1373074Y525511D02*
X1373070Y525413D01*
G01X1373079Y525553D02*
X1373074Y525511D01*
G01X1374973Y508965D02*
X1374977Y509117D01*
G01X1374968Y508867D02*
X1374973Y508965D01*
G01X1374964Y508825D02*
X1374968Y508867D01*
G01X1377011Y525413D02*
X1377007Y525261D01*
G01X1377016Y525511D02*
X1377011Y525413D01*
G01X1377020Y525553D02*
X1377016Y525511D01*
G01X1378914Y508965D02*
X1378919Y509117D01*
G01X1378910Y508867D02*
X1378914Y508965D01*
G01X1378906Y508825D02*
X1378910Y508867D01*
G01X1380944Y525413D02*
X1380940Y525261D01*
G01X1380948Y525511D02*
X1380944Y525413D01*
G01X1380953Y525553D02*
X1380948Y525511D01*
G01X1382847Y508965D02*
X1382851Y509117D01*
G01X1382842Y508867D02*
X1382847Y508965D01*
G01X1382838Y508825D02*
X1382842Y508867D01*
G01X1384885Y525413D02*
X1384881Y525261D01*
G01X1384890Y525511D02*
X1384885Y525413D01*
G01X1384894Y525553D02*
X1384890Y525511D01*
G01X1386788Y508965D02*
X1386793Y509117D01*
G01X1386784Y508867D02*
X1386788Y508965D01*
G01X1386780Y508825D02*
X1386784Y508867D01*
G01X1369134Y526353D02*
X1369128Y526147D01*
G01X1369140Y526485D02*
X1369134Y526353D01*
G01X1369146Y526538D02*
X1369140Y526485D01*
G01X1367102Y508025D02*
X1367108Y508231D01*
G01X1367096Y507893D02*
X1367102Y508025D01*
G01X1367090Y507840D02*
X1367096Y507893D01*
G01X1373067Y526353D02*
X1373061Y526147D01*
G01X1373073Y526485D02*
X1373067Y526353D01*
G01X1373079Y526538D02*
X1373073Y526485D01*
G01X1371044Y508025D02*
X1371049Y508231D01*
G01X1371038Y507893D02*
X1371044Y508025D01*
G01X1371031Y507840D02*
X1371038Y507893D01*
G01X1377008Y526353D02*
X1377002Y526147D01*
G01X1377014Y526485D02*
X1377008Y526353D01*
G01X1377020Y526538D02*
X1377014Y526485D01*
G01X1374976Y508025D02*
X1374982Y508231D01*
G01X1374970Y507893D02*
X1374976Y508025D01*
G01X1374964Y507840D02*
X1374970Y507893D01*
G01X1380941Y526353D02*
X1380935Y526147D01*
G01X1380947Y526485D02*
X1380941Y526353D01*
G01X1380953Y526538D02*
X1380947Y526485D01*
G01X1378918Y508025D02*
X1378924Y508231D01*
G01X1378912Y507893D02*
X1378918Y508025D01*
G01X1378906Y507840D02*
X1378912Y507893D01*
G01X1384882Y526353D02*
X1384876Y526147D01*
G01X1384888Y526485D02*
X1384882Y526353D01*
G01X1384894Y526538D02*
X1384888Y526485D01*
G01X1382850Y508025D02*
X1382856Y508231D01*
G01X1382844Y507893D02*
X1382850Y508025D01*
G01X1382838Y507840D02*
X1382844Y507893D01*
G01X1386792Y508025D02*
X1386798Y508231D01*
G01X1386786Y507893D02*
X1386792Y508025D01*
G01X1386780Y507840D02*
X1386786Y507893D01*
G01X1368873Y510169D02*
X1368874Y510571D01*
G01X1368870Y509841D02*
X1368873Y510169D01*
G01X1368866Y509645D02*
X1368870Y509841D01*
G01X1368862Y509615D02*
X1368866Y509645D01*
G01X1375237Y524209D02*
X1375236Y523807D01*
G01X1375240Y524537D02*
X1375237Y524209D01*
G01X1375244Y524733D02*
X1375240Y524537D01*
G01X1375249Y524763D02*
X1375244Y524733D01*
G01X1376747Y510169D02*
X1376748Y510571D01*
G01X1376744Y509841D02*
X1376747Y510169D01*
G01X1376740Y509645D02*
X1376744Y509841D01*
G01X1376736Y509615D02*
X1376740Y509645D01*
G01X1383111Y524209D02*
X1383110Y523807D01*
G01X1383114Y524537D02*
X1383111Y524209D01*
G01X1383118Y524733D02*
X1383114Y524537D01*
G01X1383123Y524763D02*
X1383118Y524733D01*
G01X1384621Y510169D02*
X1384622Y510571D01*
G01X1384618Y509841D02*
X1384621Y510169D01*
G01X1384614Y509645D02*
X1384618Y509841D01*
G01X1384610Y509615D02*
X1384614Y509645D01*
G01X1380983Y525555D02*
X1380998D01*
G01X1380968Y525554D02*
X1380983Y525555D01*
G01X1380953Y525553D02*
X1380968Y525554D01*
G01X1377050Y525555D02*
X1377065D01*
G01X1377035Y525554D02*
X1377050Y525555D01*
G01X1377020Y525553D02*
X1377035Y525554D01*
G01X1373109Y525555D02*
X1373124D01*
G01X1373094Y525554D02*
X1373109Y525555D01*
G01X1373079Y525553D02*
X1373094Y525554D01*
G01X1369176Y525555D02*
X1369191D01*
G01X1369161Y525554D02*
X1369176Y525555D01*
G01X1369146Y525553D02*
X1369161Y525554D01*
G01X1365235Y525555D02*
X1365250D01*
G01X1365220Y525554D02*
X1365235Y525555D01*
G01X1365205Y525553D02*
X1365220Y525554D01*
G01X1361302Y525555D02*
X1361317D01*
G01X1361287Y525554D02*
X1361302Y525555D01*
G01X1361272Y525553D02*
X1361287Y525554D01*
G01X1357361Y525555D02*
X1357376D01*
G01X1357346Y525554D02*
X1357361Y525555D01*
G01X1357331Y525553D02*
X1357346Y525554D01*
G01X1349487Y525555D02*
X1349502D01*
G01X1349472Y525554D02*
X1349487Y525555D01*
G01X1349457Y525553D02*
X1349472Y525554D01*
G01X1341613Y525555D02*
X1341628D01*
G01X1341598Y525554D02*
X1341613Y525555D01*
G01X1341583Y525553D02*
X1341598Y525554D01*
G01X1337680Y525555D02*
X1337695D01*
G01X1337665Y525554D02*
X1337680Y525555D01*
G01X1337650Y525553D02*
X1337665Y525554D01*
G01X1333739Y525555D02*
X1333754D01*
G01X1333724Y525554D02*
X1333739Y525555D01*
G01X1333709Y525553D02*
X1333724Y525554D01*
G01X1329806Y525555D02*
X1329821D01*
G01X1329791Y525554D02*
X1329806Y525555D01*
G01X1329776Y525553D02*
X1329791Y525554D01*
G01X1325865Y525555D02*
X1325880D01*
G01X1325850Y525554D02*
X1325865Y525555D01*
G01X1325835Y525553D02*
X1325850Y525554D01*
G01X1384924Y526539D02*
X1384939D01*
G01X1384909D02*
X1384924D01*
G01X1384894Y526538D02*
X1384909Y526539D01*
G01X1369176D02*
X1369191D01*
G01X1369161D02*
X1369176D01*
G01X1369146Y526538D02*
X1369161Y526539D01*
G01X1365235D02*
X1365250D01*
G01X1365220D02*
X1365235D01*
G01X1365205Y526538D02*
X1365220Y526539D01*
G01X1361302D02*
X1361317D01*
G01X1361287D02*
X1361302D01*
G01X1361272Y526538D02*
X1361287Y526539D01*
G01X1357361D02*
X1357376D01*
G01X1357346D02*
X1357361D01*
G01X1357331Y526538D02*
X1357346Y526539D01*
G01X1353428D02*
X1353443D01*
G01X1353413D02*
X1353428D01*
G01X1353398Y526538D02*
X1353413Y526539D01*
G01X1349487D02*
X1349502D01*
G01X1349472D02*
X1349487D01*
G01X1349457Y526538D02*
X1349472Y526539D01*
G01X1345554D02*
X1345569D01*
G01X1345539D02*
X1345554D01*
G01X1345524Y526538D02*
X1345539Y526539D01*
G01X1341613D02*
X1341628D01*
G01X1341598D02*
X1341613D01*
G01X1341583Y526538D02*
X1341598Y526539D01*
G01X1337680D02*
X1337695D01*
G01X1337665D02*
X1337680D01*
G01X1337650Y526538D02*
X1337665Y526539D01*
G01X1333739D02*
X1333754D01*
G01X1333724D02*
X1333739D01*
G01X1333709Y526538D02*
X1333724Y526539D01*
G01X1329806D02*
X1329821D01*
G01X1329791D02*
X1329806D01*
G01X1329776Y526538D02*
X1329791Y526539D01*
G01X1325865D02*
X1325880D01*
G01X1325850D02*
X1325865D01*
G01X1325835Y526538D02*
X1325850Y526539D01*
G01X1321932D02*
X1321947D01*
G01X1321917D02*
X1321932D01*
G01X1321902Y526538D02*
X1321917Y526539D01*
G01X1323772D02*
X1323787Y526538D01*
G01X1323757Y526539D02*
X1323772D01*
G01X1323742D02*
X1323757D01*
G01X1327714D02*
X1327729Y526538D01*
G01X1327699Y526539D02*
X1327714D01*
G01X1327684D02*
X1327699D01*
G01X1331646D02*
X1331661Y526538D01*
G01X1331631Y526539D02*
X1331646D01*
G01X1331616D02*
X1331631D01*
G01X1335588D02*
X1335603Y526538D01*
G01X1335573Y526539D02*
X1335588D01*
G01X1335558D02*
X1335573D01*
G01X1339520D02*
X1339535Y526538D01*
G01X1339505Y526539D02*
X1339520D01*
G01X1339490D02*
X1339505D01*
G01X1343462D02*
X1343477Y526538D01*
G01X1343447Y526539D02*
X1343462D01*
G01X1343432D02*
X1343447D01*
G01X1347394D02*
X1347409Y526538D01*
G01X1347379Y526539D02*
X1347394D01*
G01X1347364D02*
X1347379D01*
G01X1351336D02*
X1351351Y526538D01*
G01X1351321Y526539D02*
X1351336D01*
G01X1351306D02*
X1351321D01*
G01X1355268D02*
X1355283Y526538D01*
G01X1355253Y526539D02*
X1355268D01*
G01X1355238D02*
X1355253D01*
G01X1359210D02*
X1359225Y526538D01*
G01X1359195Y526539D02*
X1359210D01*
G01X1359180D02*
X1359195D01*
G01X1363142D02*
X1363157Y526538D01*
G01X1363127Y526539D02*
X1363142D01*
G01X1363112D02*
X1363127D01*
G01X1367084D02*
X1367099Y526538D01*
G01X1367069Y526539D02*
X1367084D01*
G01X1367054D02*
X1367069D01*
G01X1371016D02*
X1371031Y526538D01*
G01X1371001Y526539D02*
X1371016D01*
G01X1370986D02*
X1371001D01*
G01X1374958D02*
X1374973Y526538D01*
G01X1374943Y526539D02*
X1374958D01*
G01X1374928D02*
X1374943D01*
G01X1378890D02*
X1378906Y526538D01*
G01X1378875Y526539D02*
X1378890D01*
G01X1378860D02*
X1378875D01*
G01X1382832D02*
X1382847Y526538D01*
G01X1382817Y526539D02*
X1382832D01*
G01X1382802D02*
X1382817D01*
G01X1386765D02*
X1386780Y526538D01*
G01X1386750Y526539D02*
X1386765D01*
G01X1386734D02*
X1386750D01*
G01X1323772Y525554D02*
X1323787Y525553D01*
G01X1323757Y525555D02*
X1323772Y525554D01*
G01X1323742Y525555D02*
X1323757D01*
G01X1331646Y525554D02*
X1331661Y525553D01*
G01X1331631Y525555D02*
X1331646Y525554D01*
G01X1331616Y525555D02*
X1331631D01*
G01X1339520Y525554D02*
X1339535Y525553D01*
G01X1339505Y525555D02*
X1339520Y525554D01*
G01X1339490Y525555D02*
X1339505D01*
G01X1343462Y525554D02*
X1343477Y525553D01*
G01X1343447Y525555D02*
X1343462Y525554D01*
G01X1343432Y525555D02*
X1343447D01*
G01X1347394Y525554D02*
X1347409Y525553D01*
G01X1347379Y525555D02*
X1347394Y525554D01*
G01X1347364Y525555D02*
X1347379D01*
G01X1351336Y525554D02*
X1351351Y525553D01*
G01X1351321Y525555D02*
X1351336Y525554D01*
G01X1351306Y525555D02*
X1351321D01*
G01X1355268Y525554D02*
X1355283Y525553D01*
G01X1355253Y525555D02*
X1355268Y525554D01*
G01X1355238Y525555D02*
X1355253D01*
G01X1363142Y525554D02*
X1363157Y525553D01*
G01X1363127Y525555D02*
X1363142Y525554D01*
G01X1363112Y525555D02*
X1363127D01*
G01X1367084Y525554D02*
X1367099Y525553D01*
G01X1367069Y525555D02*
X1367084Y525554D01*
G01X1367054Y525555D02*
X1367069D01*
G01X1371016Y525554D02*
X1371031Y525553D01*
G01X1371001Y525555D02*
X1371016Y525554D01*
G01X1370986Y525555D02*
X1371001D01*
G01X1374958Y525554D02*
X1374973Y525553D01*
G01X1374943Y525555D02*
X1374958Y525554D01*
G01X1374928Y525555D02*
X1374943D01*
G01X1378890Y525554D02*
X1378906Y525553D01*
G01X1378875Y525555D02*
X1378890Y525554D01*
G01X1378860Y525555D02*
X1378875D01*
G01X1382832Y525554D02*
X1382847Y525553D01*
G01X1382817Y525555D02*
X1382832Y525554D01*
G01X1382802Y525555D02*
X1382817D01*
G01X1386765Y525554D02*
X1386780Y525553D01*
G01X1386750Y525555D02*
X1386765Y525554D01*
G01X1386734Y525555D02*
X1386750D01*
G01X1369167Y508823D02*
X1369182D01*
G01X1369152Y508824D02*
X1369167Y508823D01*
G01X1369137Y508825D02*
X1369152Y508824D01*
G01X1377041Y508823D02*
X1377056D01*
G01X1377026Y508824D02*
X1377041Y508823D01*
G01X1377011Y508825D02*
X1377026Y508824D01*
G01X1327699Y525555D02*
X1327684D01*
G01X1327714Y525554D02*
X1327699Y525555D01*
G01X1327729Y525553D02*
X1327714Y525554D01*
G01X1335573Y525555D02*
X1335558D01*
G01X1335588Y525554D02*
X1335573Y525555D01*
G01X1335603Y525553D02*
X1335588Y525554D01*
G01X1359195Y525555D02*
X1359180D01*
G01X1359210Y525554D02*
X1359195Y525555D01*
G01X1359225Y525553D02*
X1359210Y525554D01*
G01X1347684Y525756D02*
X1347683Y525757D01*
G01X1347684Y525754D02*
Y525756D01*
G01X1347685Y525751D02*
X1347684Y525754D01*
G01X1357056Y508622D02*
X1357057Y508621D01*
G01X1357056Y508624D02*
Y508622D01*
G01X1357055Y508627D02*
X1357056Y508624D01*
G01X1355558Y525756D02*
X1355557Y525757D01*
G01X1355558Y525754D02*
Y525756D01*
G01X1355559Y525751D02*
X1355558Y525754D01*
G01X1364930Y508622D02*
X1364931Y508621D01*
G01X1364930Y508624D02*
Y508622D01*
G01X1364929Y508627D02*
X1364930Y508624D01*
G01X1363432Y525756D02*
X1363431Y525757D01*
G01X1363432Y525754D02*
Y525756D01*
G01X1363433Y525751D02*
X1363432Y525754D01*
G01X1372804Y508622D02*
X1372805Y508621D01*
G01X1372804Y508624D02*
Y508622D01*
G01X1372803Y508627D02*
X1372804Y508624D01*
G01X1371306Y525756D02*
X1371305Y525757D01*
G01X1371307Y525754D02*
X1371306Y525756D01*
G01X1371307Y525751D02*
Y525754D01*
G01X1387054Y524771D02*
X1387053Y524772D01*
G01X1387054Y524768D02*
Y524771D01*
G01X1387055Y524763D02*
X1387054Y524768D01*
G01X1380689Y524181D02*
X1380690Y523807D01*
G01X1380687Y524491D02*
X1380689Y524181D01*
G01X1380683Y524698D02*
X1380687Y524491D01*
G01X1380679Y524772D02*
X1380683Y524698D01*
G01X1380947Y507893D02*
X1380953Y507840D01*
G01X1380941Y508025D02*
X1380947Y507893D01*
G01X1380935Y508231D02*
X1380941Y508025D01*
G01X1382853Y526485D02*
X1382847Y526538D01*
G01X1382859Y526353D02*
X1382853Y526485D01*
G01X1382865Y526147D02*
X1382859Y526353D01*
G01X1384879Y507893D02*
X1384885Y507840D01*
G01X1384873Y508025D02*
X1384879Y507893D01*
G01X1384867Y508231D02*
X1384873Y508025D01*
G01X1386786Y526485D02*
X1386780Y526538D01*
G01X1386792Y526353D02*
X1386786Y526485D01*
G01X1386798Y526147D02*
X1386792Y526353D01*
G01X1380948Y508867D02*
X1380953Y508825D01*
G01X1380944Y508965D02*
X1380948Y508867D01*
G01X1380940Y509117D02*
X1380944Y508965D01*
G01X1382852Y525511D02*
X1382847Y525553D01*
G01X1382856Y525413D02*
X1382852Y525511D01*
G01X1382860Y525261D02*
X1382856Y525413D01*
G01X1384881Y508867D02*
X1384885Y508825D01*
G01X1384876Y508965D02*
X1384881Y508867D01*
G01X1384872Y509117D02*
X1384876Y508965D01*
G01X1386784Y525511D02*
X1386780Y525553D01*
G01X1386788Y525413D02*
X1386784Y525511D01*
G01X1386793Y525261D02*
X1386788Y525413D01*
G01X1383109Y509645D02*
X1383113Y509615D01*
G01X1383105Y509841D02*
X1383109Y509645D01*
G01X1383102Y510169D02*
X1383105Y509841D01*
G01X1383101Y510571D02*
X1383102Y510169D01*
G01X1384624Y524733D02*
X1384619Y524763D01*
G01X1384628Y524537D02*
X1384624Y524733D01*
G01X1384630Y524209D02*
X1384628Y524537D01*
G01X1384632Y523807D02*
X1384630Y524209D01*
G01X1387045Y508770D02*
X1387053Y508621D01*
G01X1387038Y509184D02*
X1387045Y508770D01*
G01X1387033Y509804D02*
X1387038Y509184D01*
G01X1387031Y510552D02*
X1387033Y509804D01*
G01X1387049Y509679D02*
X1387053Y509606D01*
G01X1387046Y509887D02*
X1387049Y509679D01*
G01X1387043Y510200D02*
X1387046Y509887D01*
G01X1387042Y510571D02*
X1387043Y510200D01*
G01X1387033Y524573D02*
X1387031Y523826D01*
G01X1387038Y525193D02*
X1387033Y524573D01*
G01X1387045Y525608D02*
X1387038Y525193D01*
G01X1387053Y525757D02*
X1387045Y525608D01*
G01X1387043Y524178D02*
X1387042Y523807D01*
G01X1387046Y524491D02*
X1387043Y524178D01*
G01X1387049Y524699D02*
X1387046Y524491D01*
G01X1387053Y524772D02*
X1387049Y524699D01*
G01X1372804Y509610D02*
X1372803Y509617D01*
G01X1372804Y509607D02*
Y509610D01*
G01X1372805Y509606D02*
X1372804Y509607D01*
G01X1371306Y524768D02*
X1371307Y524761D01*
G01X1371306Y524771D02*
Y524768D01*
G01X1371305Y524772D02*
X1371306Y524771D01*
G01X1380678Y509610D02*
X1380677Y509617D01*
G01X1380678Y509607D02*
Y509610D01*
G01X1380679Y509606D02*
X1380678Y509607D01*
G01X1379180Y524768D02*
X1379181Y524761D01*
G01X1379180Y524771D02*
Y524768D01*
G01X1379179Y524772D02*
X1379180Y524771D01*
G01X1380678Y508622D02*
X1380679Y508621D01*
G01X1380678Y508624D02*
Y508622D01*
G01X1380677Y508627D02*
X1380678Y508624D01*
G01X1379180Y525756D02*
X1379179Y525757D01*
G01X1379181Y525754D02*
X1379180Y525756D01*
G01X1379181Y525751D02*
Y525754D01*
G01X1387054Y525756D02*
X1387053Y525757D01*
G01X1387055Y525754D02*
X1387054Y525756D01*
G01X1387055Y525751D02*
Y525754D01*
G01X1374093Y550386D02*
X1374585Y549381D01*
G01X1375077Y551140D02*
X1376061Y549632D01*
G01X1387067Y525738D02*
X1387320Y525368D01*
G01X1387275Y524441D02*
X1387054Y524763D01*
G01X1383134Y525738D02*
X1383388Y525368D01*
G01X1383343Y524441D02*
X1383121Y524763D01*
G01X1374585Y549381D02*
X1375323Y548627D01*
G01X1376061Y549632D02*
X1376799Y549130D01*
G01X1375323Y548627D02*
X1376553Y547873D01*
G01X1366218Y551140D02*
X1361543Y553653D01*
G01X1376799Y549130D02*
X1378030Y548879D01*
G01X1374831Y552648D02*
X1375077Y551140D01*
G01X1373600Y552397D02*
X1373846Y551140D01*
G01X1387275Y524441D02*
X1387284Y524394D01*
G01X1383343Y524441D02*
X1383352Y524394D01*
G01X1384390Y509937D02*
X1384380Y509984D01*
G01X1379410Y524394D02*
X1379401Y524441D01*
G01X1380448Y509984D02*
X1380457Y509937D01*
G01X1375469Y524441D02*
X1375478Y524394D01*
G01X1376516Y509937D02*
X1376506Y509984D01*
G01X1371536Y524394D02*
X1371527Y524441D01*
G01X1373846Y551140D02*
X1374093Y550386D01*
G01X1379446Y525368D02*
X1379193Y525738D01*
G01X1379181Y524760D02*
X1379401Y524441D01*
G01X1375514Y525368D02*
X1375260Y525738D01*
G01X1375469Y524441D02*
X1375247Y524763D01*
G01X1384390Y509937D02*
X1384611Y509615D01*
G01X1384598Y508640D02*
X1384344Y509010D01*
G01X1371572Y525368D02*
X1371319Y525738D01*
G01X1371307Y524760D02*
X1371527Y524441D01*
G01X1380677Y509618D02*
X1380457Y509937D01*
G01X1380412Y509010D02*
X1380666Y508640D01*
G01X1367640Y525368D02*
X1367386Y525738D01*
G01X1367594Y524441D02*
X1367373Y524763D01*
G01X1376516Y509937D02*
X1376737Y509615D01*
G01X1376470Y509010D02*
X1376724Y508640D01*
G01X1363445Y525738D02*
X1363698Y525368D01*
G01X1363653Y524441D02*
X1363431Y524763D01*
G01X1372803Y509618D02*
X1372583Y509937D01*
G01X1372538Y509010D02*
X1372792Y508640D01*
G01X1359512Y525738D02*
X1359766Y525368D01*
G01X1359720Y524441D02*
X1359499Y524763D01*
G01X1368642Y509937D02*
X1368863Y509615D01*
G01X1368596Y509010D02*
X1368850Y508640D01*
G01X1355571Y525738D02*
X1355824Y525368D01*
G01X1355779Y524441D02*
X1355557Y524763D01*
G01X1364709Y509937D02*
X1364931Y509615D01*
G01X1364918Y508640D02*
X1364664Y509010D01*
G01X1376553Y547873D02*
X1378030Y547622D01*
G01X1351209D02*
X1349732D01*
G01X1359575D02*
X1358098D01*
G01X1371632D02*
X1370156D01*
G01X1385657D02*
X1384427D01*
G01X1386957Y519051D02*
X1387008Y520037D01*
G01X1387006Y520999D02*
X1386955Y520013D01*
G01X1386798Y508231D02*
X1386934Y514139D01*
G01X1386929Y515025D02*
X1386793Y509117D01*
G01X1384745Y519353D02*
X1384881Y525261D01*
G01X1384876Y526147D02*
X1384740Y520239D01*
G01X1387307Y524394D02*
X1387320Y525368D01*
G01X1384357Y509984D02*
X1384344Y509010D01*
G01X1383375Y524394D02*
X1383388Y525368D01*
G01X1387409Y529492D02*
Y530476D01*
G01Y504886D02*
Y503902D01*
G01X1387134Y504965D02*
Y503902D01*
G01Y530476D02*
Y529413D01*
G01X1387055Y509618D02*
Y508627D01*
G01Y525751D02*
Y524760D01*
G01X1386976Y525555D02*
Y530396D01*
G01Y503982D02*
Y508823D01*
G01X1386780Y525553D02*
Y526538D01*
G01Y507840D02*
Y508825D01*
G01X1386701Y526539D02*
Y507839D01*
G01X1386622Y509984D02*
Y503902D01*
G01Y530476D02*
Y524394D01*
G01X1386425Y508823D02*
Y507839D01*
G01Y526539D02*
Y525555D01*
G01X1386421Y526539D02*
Y525555D01*
G01X1386386Y510516D02*
Y506343D01*
G01Y528035D02*
Y523862D01*
G01X1385657Y553905D02*
Y547622D01*
G01X1385283Y523862D02*
Y528035D01*
G01Y506343D02*
Y510516D01*
G01X1385249Y526539D02*
Y525555D01*
G01X1385244Y508823D02*
Y507839D01*
G01X1385239Y508823D02*
Y507839D01*
G01X1385047Y509984D02*
Y503902D01*
G01Y530476D02*
Y524394D01*
G01X1384968Y507839D02*
Y526539D01*
G01X1384894Y526538D02*
Y525553D01*
G01X1384885Y508825D02*
Y507840D01*
G01X1384693Y521698D02*
Y526539D01*
G01Y507839D02*
Y512680D01*
G01X1384619Y524760D02*
Y525751D01*
G01X1384610Y508627D02*
Y509618D01*
G01X1384535Y512760D02*
Y511696D01*
G01Y522681D02*
Y521618D01*
G01X1384427Y547622D02*
Y555664D01*
G01X1384260Y521618D02*
Y522602D01*
G01Y512760D02*
Y511776D01*
G01X1383472Y521618D02*
Y522602D01*
G01Y511776D02*
Y512760D01*
G01X1383197D02*
Y511696D01*
G01Y522682D02*
Y521618D01*
G01X1383123Y525751D02*
Y524760D01*
G01X1383113Y509618D02*
Y508627D01*
G01X1383039Y521698D02*
Y526539D01*
G01Y507839D02*
Y512680D01*
G01X1382847Y525553D02*
Y526538D01*
G01X1382838Y507840D02*
Y508825D01*
G01X1382764Y526539D02*
Y507839D01*
G01X1382685Y509984D02*
Y503902D01*
G01Y530476D02*
Y524394D01*
G01X1382493Y526539D02*
Y525555D01*
G01X1382488Y526539D02*
Y525555D01*
G01X1382484Y508823D02*
Y507839D01*
G01X1382449Y510516D02*
Y506343D01*
G01Y528035D02*
Y523862D01*
G01X1387320Y509010D02*
X1387307Y509984D01*
G01X1384353Y525368D02*
X1384367Y524394D01*
G01X1383379Y509010D02*
X1383366Y509984D01*
G01X1386934Y520239D02*
X1386798Y526147D01*
G01X1386793Y525261D02*
X1386929Y519353D01*
G01X1384872Y509117D02*
X1384736Y515025D01*
G01X1384731Y514139D02*
X1384867Y508231D01*
G01X1383001Y520239D02*
X1382865Y526147D01*
G01X1382860Y525261D02*
X1382997Y519353D01*
G01X1387008Y514341D02*
X1386957Y515327D01*
G01X1386955Y514365D02*
X1387006Y513379D01*
G01X1384719Y520013D02*
X1384668Y520999D01*
G01X1384666Y520037D02*
X1384717Y519051D01*
G01X1383066Y514341D02*
X1383016Y515327D01*
G01X1383013Y514365D02*
X1383064Y513379D01*
G01X1380777Y520013D02*
X1380727Y520999D01*
G01X1380724Y520037D02*
X1380775Y519051D01*
G01X1372574Y509984D02*
X1372583Y509937D01*
G01X1367594Y524441D02*
X1367604Y524394D01*
G01X1368642Y509937D02*
X1368632Y509984D01*
G01X1363653Y524441D02*
X1363662Y524394D01*
G01X1364709Y509937D02*
X1364700Y509984D01*
G01X1359720Y524441D02*
X1359730Y524394D01*
G01X1360768Y509937D02*
X1360758Y509984D01*
G01X1355779Y524441D02*
X1355788Y524394D01*
G01X1356835Y509937D02*
X1356826Y509984D01*
G01X1351846Y524441D02*
X1351856Y524394D01*
G01X1352894Y509937D02*
X1352884Y509984D01*
G01X1347905Y524441D02*
X1347914Y524394D01*
G01X1348961Y509937D02*
X1348952Y509984D01*
G01X1351638Y525738D02*
X1351892Y525368D01*
G01X1351846Y524441D02*
X1351625Y524763D01*
G01X1360768Y509937D02*
X1360989Y509615D01*
G01X1360976Y508640D02*
X1360722Y509010D01*
G01X1347697Y525738D02*
X1347950Y525368D01*
G01X1347905Y524441D02*
X1347683Y524763D01*
G01X1356835Y509937D02*
X1357057Y509615D01*
G01X1357044Y508640D02*
X1356790Y509010D01*
G01X1343764Y525738D02*
X1344018Y525368D01*
G01X1343972Y524441D02*
X1343751Y524763D01*
G01X1352894Y509937D02*
X1353115Y509615D01*
G01X1353102Y508640D02*
X1352848Y509010D01*
G01X1339823Y525738D02*
X1340076Y525368D01*
G01X1340031Y524441D02*
X1339809Y524763D01*
G01X1348961Y509937D02*
X1349183Y509615D01*
G01X1349170Y508640D02*
X1348916Y509010D01*
G01X1335890Y525738D02*
X1336144Y525368D01*
G01X1336098Y524441D02*
X1335877Y524763D01*
G01X1345020Y509937D02*
X1345241Y509615D01*
G01X1345228Y508640D02*
X1344974Y509010D01*
G01X1331949Y525738D02*
X1332202Y525368D01*
G01X1332157Y524441D02*
X1331935Y524763D01*
G01X1341087Y509937D02*
X1341309Y509615D01*
G01X1341296Y508640D02*
X1341042Y509010D01*
G01X1328016Y525738D02*
X1328270Y525368D01*
G01X1328224Y524441D02*
X1328003Y524763D01*
G01X1337146Y509937D02*
X1337367Y509615D01*
G01X1337354Y508640D02*
X1337100Y509010D01*
G01X1324075Y525738D02*
X1324328Y525368D01*
G01X1324283Y524441D02*
X1324061Y524763D01*
G01X1325992Y530476D02*
X1323630D01*
G01X1329929D02*
X1327567D01*
G01X1333866D02*
X1331504D01*
G01X1337803D02*
X1335441D01*
G01X1341740D02*
X1339378D01*
G01X1345677D02*
X1343315D01*
G01X1349614D02*
X1347252D01*
G01X1353551D02*
X1351189D01*
G01X1357488D02*
X1355126D01*
G01X1361425D02*
X1359063D01*
G01X1365362D02*
X1363000D01*
G01X1369299D02*
X1366937D01*
G01X1373236D02*
X1370874D01*
G01X1377173D02*
X1374811D01*
G01X1381110D02*
X1378748D01*
G01X1385047D02*
X1382685D01*
G01X1388984D02*
X1386622D01*
G01X1325480Y529492D02*
X1324142D01*
G01X1333354D02*
X1332016D01*
G01X1341228D02*
X1339890D01*
G01X1349102D02*
X1347764D01*
G01X1356976D02*
X1355638D01*
G01X1364850D02*
X1363512D01*
G01X1372724D02*
X1371386D01*
G01X1380598D02*
X1379260D01*
G01X1388472D02*
X1387134D01*
G01X1386976Y529394D02*
X1388630D01*
G01X1379102D02*
X1380756D01*
G01X1371228D02*
X1372882D01*
G01X1363354D02*
X1365008D01*
G01X1355480D02*
X1357134D01*
G01X1347606D02*
X1349260D01*
G01X1339732D02*
X1341386D01*
G01X1331858D02*
X1333512D01*
G01X1323984D02*
X1325638D01*
G01X1325992Y529295D02*
X1323630D01*
G01X1329929D02*
X1327567D01*
G01X1333866D02*
X1331504D01*
G01X1337803D02*
X1335441D01*
G01X1341740D02*
X1339378D01*
G01X1345677D02*
X1343315D01*
G01X1349614D02*
X1347252D01*
G01X1353551D02*
X1351189D01*
G01X1357488D02*
X1355126D01*
G01X1361425D02*
X1359063D01*
G01X1365362D02*
X1363000D01*
G01X1369299D02*
X1366937D01*
G01X1373236D02*
X1370874D01*
G01X1377173D02*
X1374811D01*
G01X1381110D02*
X1378748D01*
G01X1385047D02*
X1382685D01*
G01X1388984D02*
X1386622D01*
G01X1325638Y528902D02*
X1323984D01*
G01X1333512D02*
X1331858D01*
G01X1341386D02*
X1339732D01*
G01X1349260D02*
X1347606D01*
G01X1357134D02*
X1355480D01*
G01X1365008D02*
X1363354D01*
G01X1372882D02*
X1371228D01*
G01X1380756D02*
X1379102D01*
G01X1388630D02*
X1386976D01*
G01X1326228Y528035D02*
X1323394D01*
G01X1330165D02*
X1327331D01*
G01X1334102D02*
X1331268D01*
G01X1338039D02*
X1335205D01*
G01X1341976D02*
X1339142D01*
G01X1345913D02*
X1343079D01*
G01X1349850D02*
X1347016D01*
G01X1353787D02*
X1350953D01*
G01X1357724D02*
X1354890D01*
G01X1361661D02*
X1358827D01*
G01X1365598D02*
X1362764D01*
G01X1369535D02*
X1366701D01*
G01X1373472D02*
X1370638D01*
G01X1377409D02*
X1374575D01*
G01X1381346D02*
X1378512D01*
G01X1385283D02*
X1382449D01*
G01X1389220D02*
X1386386D01*
G01X1325638Y527130D02*
X1323984D01*
G01X1333512D02*
X1331858D01*
G01X1341386D02*
X1339732D01*
G01X1349260D02*
X1347606D01*
G01X1357134D02*
X1355480D01*
G01X1365008D02*
X1363354D01*
G01X1372882D02*
X1371228D01*
G01X1380756D02*
X1379102D01*
G01X1388630D02*
X1386976D01*
G01Y526638D02*
X1388630D01*
G01X1379102D02*
X1380756D01*
G01X1371228D02*
X1372882D01*
G01X1363354D02*
X1365008D01*
G01X1355480D02*
X1357134D01*
G01X1347606D02*
X1349260D01*
G01X1339732D02*
X1341386D01*
G01X1331858D02*
X1333512D01*
G01X1323984D02*
X1325638D01*
G01X1326228Y526539D02*
X1323394D01*
G01X1330165D02*
X1327331D01*
G01X1334102D02*
X1331268D01*
G01X1338039D02*
X1335205D01*
G01X1341976D02*
X1339142D01*
G01X1345913D02*
X1343079D01*
G01X1349850D02*
X1347016D01*
G01X1353787D02*
X1350953D01*
G01X1357724D02*
X1354890D01*
G01X1361661D02*
X1358827D01*
G01X1365598D02*
X1362764D01*
G01X1369535D02*
X1366701D01*
G01X1373472D02*
X1370638D01*
G01X1377409D02*
X1374575D01*
G01X1381346D02*
X1378512D01*
G01X1385283D02*
X1382449D01*
G01X1389220D02*
X1386386D01*
G01Y526382D02*
X1386976D01*
G01X1384693D02*
X1385283D01*
G01X1382449D02*
X1383039D01*
G01X1380756D02*
X1381346D01*
G01X1378512D02*
X1379102D01*
G01X1376819D02*
X1377409D01*
G01X1374575D02*
X1375165D01*
G01X1372882D02*
X1373472D01*
G01X1370638D02*
X1371228D01*
G01X1368945D02*
X1369535D01*
G01X1366701D02*
X1367291D01*
G01X1365008D02*
X1365598D01*
G01X1362764D02*
X1363354D01*
G01X1361071D02*
X1361661D01*
G01X1358827D02*
X1359417D01*
G01X1357134D02*
X1357724D01*
G01X1354890D02*
X1355480D01*
G01X1353197D02*
X1353787D01*
G01X1350953D02*
X1351543D01*
G01X1349260D02*
X1349850D01*
G01X1347016D02*
X1347606D01*
G01X1345323D02*
X1345913D01*
G01X1343079D02*
X1343669D01*
G01X1341386D02*
X1341976D01*
G01X1339142D02*
X1339732D01*
G01X1337449D02*
X1338039D01*
G01X1335205D02*
X1335795D01*
G01X1333512D02*
X1334102D01*
G01X1331268D02*
X1331858D01*
G01X1329575D02*
X1330165D01*
G01X1327331D02*
X1327921D01*
G01X1325638D02*
X1326228D01*
G01X1323394D02*
X1323984D01*
G01X1321701D02*
X1322291D01*
G01X1386798Y526147D02*
X1388809D01*
G01X1382865D02*
X1384876D01*
G01X1378924D02*
X1380935D01*
G01X1374991D02*
X1377002D01*
G01X1371049D02*
X1373061D01*
G01X1367117D02*
X1369128D01*
G01X1363175D02*
X1365187D01*
G01X1359243D02*
X1361254D01*
G01X1355301D02*
X1357313D01*
G01X1351369D02*
X1353380D01*
G01X1347427D02*
X1349439D01*
G01X1343495D02*
X1345506D01*
G01X1339553D02*
X1341565D01*
G01X1335621D02*
X1337632D01*
G01X1331679D02*
X1333691D01*
G01X1327747D02*
X1329758D01*
G01X1323805D02*
X1325817D01*
G01X1325561Y525757D02*
X1324061D01*
G01X1329502D02*
X1328003D01*
G01X1333435D02*
X1331935D01*
G01X1337376D02*
X1335877D01*
G01X1341309D02*
X1339809D01*
G01X1345250D02*
X1343751D01*
G01X1349183D02*
X1347683D01*
G01X1353124D02*
X1351625D01*
G01X1357057D02*
X1355557D01*
G01X1360998D02*
X1359499D01*
G01X1364931D02*
X1363431D01*
G01X1368872D02*
X1367373D01*
G01X1372805D02*
X1371305D01*
G01X1376747D02*
X1375247D01*
G01X1380679D02*
X1379179D01*
G01X1384621D02*
X1383121D01*
G01X1388553D02*
X1387053D01*
G01X1387067Y525738D02*
X1388540D01*
G01X1383134D02*
X1384607D01*
G01X1379193D02*
X1380666D01*
G01X1375260D02*
X1376733D01*
G01X1371319D02*
X1372792D01*
G01X1367386D02*
X1368859D01*
G01X1363445D02*
X1364918D01*
G01X1359512D02*
X1360985D01*
G01X1355571D02*
X1357044D01*
G01X1351638D02*
X1353111D01*
G01X1347697D02*
X1349170D01*
G01X1343764D02*
X1345237D01*
G01X1339823D02*
X1341296D01*
G01X1335890D02*
X1337363D01*
G01X1331949D02*
X1333422D01*
G01X1328016D02*
X1329489D01*
G01X1324075D02*
X1325548D01*
G01X1322291Y525713D02*
X1321701D01*
G01X1323984D02*
X1323394D01*
G01X1326228D02*
X1325638D01*
G01X1327921D02*
X1327331D01*
G01X1330165D02*
X1329575D01*
G01X1331858D02*
X1331268D01*
G01X1334102D02*
X1333512D01*
G01X1335795D02*
X1335205D01*
G01X1338039D02*
X1337449D01*
G01X1339732D02*
X1339142D01*
G01X1341976D02*
X1341386D01*
G01X1343669D02*
X1343079D01*
G01X1345913D02*
X1345323D01*
G01X1347606D02*
X1347016D01*
G01X1349850D02*
X1349260D01*
G01X1351543D02*
X1350953D01*
G01X1353787D02*
X1353197D01*
G01X1355480D02*
X1354890D01*
G01X1357724D02*
X1357134D01*
G01X1359417D02*
X1358827D01*
G01X1361661D02*
X1361071D01*
G01X1363354D02*
X1362764D01*
G01X1365598D02*
X1365008D01*
G01X1367291D02*
X1366701D01*
G01X1369535D02*
X1368945D01*
G01X1371228D02*
X1370638D01*
G01X1373472D02*
X1372882D01*
G01X1375165D02*
X1374575D01*
G01X1377409D02*
X1376819D01*
G01X1379102D02*
X1378512D01*
G01X1381346D02*
X1380756D01*
G01X1383039D02*
X1382449D01*
G01X1385283D02*
X1384693D01*
G01X1386976D02*
X1386386D01*
G01Y525555D02*
X1389220D01*
G01X1382449D02*
X1385283D01*
G01X1378512D02*
X1381346D01*
G01X1374575D02*
X1377409D01*
G01X1370638D02*
X1373472D01*
G01X1366701D02*
X1369535D01*
G01X1362764D02*
X1365598D01*
G01X1354890D02*
X1357724D01*
G01X1350953D02*
X1353787D01*
G01X1347016D02*
X1349850D01*
G01X1343079D02*
X1345913D01*
G01X1339142D02*
X1341976D01*
G01X1335205D02*
X1338039D01*
G01X1331268D02*
X1334102D01*
G01X1323394D02*
X1326228D01*
G01X1330165D02*
X1327331D01*
G01X1361661D02*
X1358827D01*
G01X1329575Y525457D02*
X1327921D01*
G01X1337449D02*
X1335795D01*
G01X1345323D02*
X1343669D01*
G01X1353197D02*
X1351543D01*
G01X1361071D02*
X1359417D01*
G01X1368945D02*
X1367291D01*
G01X1376819D02*
X1375165D01*
G01X1384693D02*
X1383039D01*
G01X1321361Y525368D02*
X1320396D01*
G01X1325294D02*
X1324328D01*
G01X1329235D02*
X1328270D01*
G01X1333168D02*
X1332202D01*
G01X1337109D02*
X1336144D01*
G01X1341042D02*
X1340076D01*
G01X1344983D02*
X1344018D01*
G01X1348916D02*
X1347950D01*
G01X1352857D02*
X1351892D01*
G01X1356790D02*
X1355824D01*
G01X1360731D02*
X1359766D01*
G01X1364664D02*
X1363698D01*
G01X1368605D02*
X1367640D01*
G01X1372538D02*
X1371572D01*
G01X1376479D02*
X1375514D01*
G01X1380412D02*
X1379446D01*
G01X1384353D02*
X1383388D01*
G01X1388286D02*
X1387320D01*
G01X1386386Y525358D02*
X1386701D01*
G01X1382449D02*
X1382764D01*
G01X1374575D02*
X1374890D01*
G01X1366701D02*
X1367016D01*
G01X1362764D02*
X1363079D01*
G01X1358827D02*
X1359142D01*
G01X1354890D02*
X1355205D01*
G01X1350953D02*
X1351268D01*
G01X1347016D02*
X1347331D01*
G01X1343079D02*
X1343394D01*
G01X1339142D02*
X1339457D01*
G01X1335205D02*
X1335520D01*
G01X1331268D02*
X1331583D01*
G01X1327331D02*
X1327646D01*
G01X1323394D02*
X1323709D01*
G01X1322291D02*
X1321976D01*
G01X1326228D02*
X1325913D01*
G01X1330165D02*
X1329850D01*
G01X1334102D02*
X1333787D01*
G01X1338039D02*
X1337724D01*
G01X1341976D02*
X1341661D01*
G01X1345913D02*
X1345598D01*
G01X1349850D02*
X1349535D01*
G01X1353787D02*
X1353472D01*
G01X1357724D02*
X1357409D01*
G01X1361661D02*
X1361346D01*
G01X1365598D02*
X1365283D01*
G01X1369535D02*
X1369220D01*
G01X1370953D02*
X1370638D01*
G01X1373472D02*
X1373157D01*
G01X1377409D02*
X1377094D01*
G01X1378827D02*
X1378512D01*
G01X1381346D02*
X1381031D01*
G01X1385283D02*
X1384968D01*
G01X1325821Y525261D02*
X1323801D01*
G01X1329763D02*
X1327742D01*
G01X1333695D02*
X1331675D01*
G01X1337637D02*
X1335616D01*
G01X1341569D02*
X1339549D01*
G01X1345511D02*
X1343490D01*
G01X1349443D02*
X1347423D01*
G01X1353385D02*
X1351364D01*
G01X1357317D02*
X1355297D01*
G01X1361259D02*
X1359238D01*
G01X1365192D02*
X1363171D01*
G01X1369133D02*
X1367112D01*
G01X1373066D02*
X1371045D01*
G01X1377007D02*
X1374986D01*
G01X1380940D02*
X1378919D01*
G01X1384881D02*
X1382860D01*
G01X1388814D02*
X1386793D01*
G01X1383039Y524965D02*
X1384693D01*
G01X1375165D02*
X1376819D01*
G01X1367291D02*
X1368945D01*
G01X1359417D02*
X1361071D01*
G01X1351543D02*
X1353197D01*
G01X1343669D02*
X1345323D01*
G01X1335795D02*
X1337449D01*
G01X1327921D02*
X1329575D01*
G01X1325561Y524772D02*
X1324061D01*
G01X1329502D02*
X1328003D01*
G01X1333435D02*
X1331935D01*
G01X1337376D02*
X1335877D01*
G01X1341309D02*
X1339809D01*
G01X1345250D02*
X1343751D01*
G01X1349183D02*
X1347683D01*
G01X1353124D02*
X1351625D01*
G01X1357057D02*
X1355557D01*
G01X1360998D02*
X1359499D01*
G01X1364931D02*
X1363431D01*
G01X1368873D02*
X1367373D01*
G01X1372805D02*
X1371305D01*
G01X1376747D02*
X1375247D01*
G01X1380679D02*
X1379179D01*
G01X1384621D02*
X1383121D01*
G01X1388553D02*
X1387053D01*
G01X1325559Y524763D02*
X1324063D01*
G01X1329501D02*
X1328004D01*
G01X1333433D02*
X1331937D01*
G01X1337375D02*
X1335878D01*
G01X1341307D02*
X1339811D01*
G01X1345249D02*
X1343753D01*
G01X1349181D02*
X1347685D01*
G01X1353123D02*
X1351627D01*
G01X1357055D02*
X1355559D01*
G01X1360997D02*
X1359501D01*
G01X1364929D02*
X1363433D01*
G01X1368871D02*
X1367375D01*
G01X1372803D02*
X1371307D01*
G01X1376745D02*
X1375249D01*
G01X1380677D02*
X1379181D01*
G01X1384619D02*
X1383123D01*
G01X1388551D02*
X1387055D01*
G01X1387275Y524441D02*
X1388331D01*
G01X1383343D02*
X1384399D01*
G01X1379401D02*
X1380457D01*
G01X1375469D02*
X1376525D01*
G01X1371527D02*
X1372583D01*
G01X1367594D02*
X1368651D01*
G01X1363653D02*
X1364709D01*
G01X1359720D02*
X1360777D01*
G01X1355779D02*
X1356835D01*
G01X1351846D02*
X1352903D01*
G01X1347905D02*
X1348961D01*
G01X1343972D02*
X1345029D01*
G01X1340031D02*
X1341087D01*
G01X1336098D02*
X1337155D01*
G01X1332157D02*
X1333213D01*
G01X1328224D02*
X1329281D01*
G01X1324283D02*
X1325339D01*
G01X1320350D02*
X1321407D01*
G01X1378748Y524394D02*
X1381110D01*
G01X1374811D02*
X1377173D01*
G01X1370874D02*
X1373236D01*
G01X1325992D02*
X1323630D01*
G01X1329929D02*
X1327567D01*
G01X1333866D02*
X1331504D01*
G01X1337803D02*
X1335441D01*
G01X1341740D02*
X1339378D01*
G01X1345677D02*
X1343315D01*
G01X1349614D02*
X1347252D01*
G01X1353551D02*
X1351189D01*
G01X1357488D02*
X1355126D01*
G01X1361425D02*
X1359063D01*
G01X1365362D02*
X1363000D01*
G01X1369299D02*
X1366937D01*
G01X1385047D02*
X1382685D01*
G01X1388984D02*
X1386622D01*
G01X1386386Y523862D02*
X1386701D01*
G01X1384968D02*
X1385283D01*
G01X1382449D02*
X1382764D01*
G01X1381031D02*
X1381346D01*
G01X1378512D02*
X1378827D01*
G01X1377094D02*
X1377409D01*
G01X1374575D02*
X1374890D01*
G01X1373157D02*
X1373472D01*
G01X1369220D02*
X1369535D01*
G01X1370638D02*
X1370953D01*
G01X1366701D02*
X1367016D01*
G01X1365283D02*
X1365598D01*
G01X1362764D02*
X1363079D01*
G01X1361346D02*
X1361661D01*
G01X1358827D02*
X1359142D01*
G01X1357409D02*
X1357724D01*
G01X1354890D02*
X1355205D01*
G01X1353472D02*
X1353787D01*
G01X1350953D02*
X1351268D01*
G01X1349535D02*
X1349850D01*
G01X1347016D02*
X1347331D01*
G01X1345598D02*
X1345913D01*
G01X1343079D02*
X1343394D01*
G01X1341661D02*
X1341976D01*
G01X1337724D02*
X1338039D01*
G01X1339142D02*
X1339457D01*
G01X1335205D02*
X1335520D01*
G01X1333787D02*
X1334102D01*
G01X1331268D02*
X1331583D01*
G01X1329850D02*
X1330165D01*
G01X1327331D02*
X1327646D01*
G01X1325913D02*
X1326228D01*
G01X1323394D02*
X1323709D01*
G01X1321976D02*
X1322291D01*
G01X1387031Y523826D02*
X1388575D01*
G01X1383099D02*
X1384642D01*
G01X1379157D02*
X1380701D01*
G01X1375225D02*
X1376768D01*
G01X1371283D02*
X1372827D01*
G01X1367351D02*
X1368894D01*
G01X1363409D02*
X1364953D01*
G01X1359477D02*
X1361020D01*
G01X1355535D02*
X1357079D01*
G01X1351603D02*
X1353146D01*
G01X1347661D02*
X1349205D01*
G01X1343729D02*
X1345272D01*
G01X1339787D02*
X1341331D01*
G01X1335855D02*
X1337398D01*
G01X1331913D02*
X1333457D01*
G01X1327981D02*
X1329524D01*
G01X1324039D02*
X1325583D01*
G01X1387042Y523807D02*
X1388564D01*
G01X1383110D02*
X1384632D01*
G01X1379168D02*
X1380690D01*
G01X1375236D02*
X1376758D01*
G01X1371294D02*
X1372816D01*
G01X1367362D02*
X1368883D01*
G01X1363420D02*
X1364942D01*
G01X1359488D02*
X1361009D01*
G01X1355546D02*
X1357068D01*
G01X1351614D02*
X1353135D01*
G01X1347672D02*
X1349194D01*
G01X1343740D02*
X1345261D01*
G01X1339798D02*
X1341320D01*
G01X1335866D02*
X1337387D01*
G01X1331924D02*
X1333446D01*
G01X1327992D02*
X1329513D01*
G01X1324050D02*
X1325572D01*
G01X1383039Y523193D02*
X1384693D01*
G01X1375165D02*
X1376819D01*
G01X1367291D02*
X1368945D01*
G01X1359417D02*
X1361071D01*
G01X1351543D02*
X1353197D01*
G01X1343669D02*
X1345323D01*
G01X1335795D02*
X1337449D01*
G01X1327921D02*
X1329575D01*
G01Y522701D02*
X1327921D01*
G01X1337449D02*
X1335795D01*
G01X1345323D02*
X1343669D01*
G01X1353197D02*
X1351543D01*
G01X1361071D02*
X1359417D01*
G01X1368945D02*
X1367291D01*
G01X1376819D02*
X1375165D01*
G01X1384693D02*
X1383039D01*
G01X1329417Y522602D02*
X1328079D01*
G01X1337291D02*
X1335953D01*
G01X1345165D02*
X1343827D01*
G01X1353039D02*
X1351701D01*
G01X1360913D02*
X1359575D01*
G01X1368787D02*
X1367449D01*
G01X1376661D02*
X1375323D01*
G01X1384535D02*
X1383197D01*
G01Y521618D02*
X1384535D01*
G01X1375323D02*
X1376661D01*
G01X1367449D02*
X1368787D01*
G01X1359575D02*
X1360913D01*
G01X1351701D02*
X1353039D01*
G01X1343827D02*
X1345165D01*
G01X1335953D02*
X1337291D01*
G01X1328079D02*
X1329417D01*
G01X1325609Y520999D02*
X1324013D01*
G01X1329550D02*
X1327955D01*
G01X1333483D02*
X1331887D01*
G01X1337424D02*
X1335829D01*
G01X1341357D02*
X1339761D01*
G01X1345298D02*
X1343703D01*
G01X1349231D02*
X1347635D01*
G01X1353172D02*
X1351577D01*
G01X1357105D02*
X1355510D01*
G01X1361046D02*
X1359451D01*
G01X1364979D02*
X1363384D01*
G01X1368920D02*
X1367325D01*
G01X1372853D02*
X1371258D01*
G01X1376794D02*
X1375199D01*
G01X1380727D02*
X1379132D01*
G01X1384668D02*
X1383073D01*
G01X1388601D02*
X1387006D01*
G01X1325913Y520890D02*
X1323709D01*
G01X1329850D02*
X1327646D01*
G01X1333787D02*
X1331583D01*
G01X1337724D02*
X1335520D01*
G01X1341661D02*
X1339457D01*
G01X1345598D02*
X1343394D01*
G01X1349535D02*
X1347331D01*
G01X1353472D02*
X1351268D01*
G01X1357409D02*
X1355205D01*
G01X1361346D02*
X1359142D01*
G01X1365283D02*
X1363079D01*
G01X1369220D02*
X1367016D01*
G01X1373157D02*
X1370953D01*
G01X1377094D02*
X1374890D01*
G01X1381031D02*
X1378827D01*
G01X1384968D02*
X1382764D01*
G01X1388906D02*
X1386701D01*
G01X1325680Y520239D02*
X1323942D01*
G01X1329622D02*
X1327883D01*
G01X1333554D02*
X1331816D01*
G01X1337496D02*
X1335757D01*
G01X1341428D02*
X1339690D01*
G01X1345370D02*
X1343631D01*
G01X1349302D02*
X1347564D01*
G01X1353244D02*
X1351505D01*
G01X1357176D02*
X1355438D01*
G01X1361118D02*
X1359379D01*
G01X1365051D02*
X1363312D01*
G01X1368992D02*
X1367253D01*
G01X1372925D02*
X1371186D01*
G01X1376866D02*
X1375127D01*
G01X1380799D02*
X1379060D01*
G01X1384740D02*
X1383001D01*
G01X1388673D02*
X1386934D01*
G01X1387008Y520037D02*
X1388598D01*
G01X1383076D02*
X1384666D01*
G01X1379134D02*
X1380724D01*
G01X1375202D02*
X1376792D01*
G01X1371260D02*
X1372850D01*
G01X1367328D02*
X1368918D01*
G01X1363386D02*
X1364976D01*
G01X1359454D02*
X1361044D01*
G01X1355512D02*
X1357102D01*
G01X1351579D02*
X1353170D01*
G01X1347638D02*
X1349228D01*
G01X1343705D02*
X1345296D01*
G01X1339764D02*
X1341354D01*
G01X1335831D02*
X1337422D01*
G01X1331890D02*
X1333480D01*
G01X1327957D02*
X1329548D01*
G01X1324016D02*
X1325606D01*
G01X1386955Y520013D02*
X1388651D01*
G01X1383023D02*
X1384719D01*
G01X1379081D02*
X1380777D01*
G01X1375149D02*
X1376845D01*
G01X1371207D02*
X1372903D01*
G01X1367275D02*
X1368971D01*
G01X1363333D02*
X1365029D01*
G01X1359401D02*
X1361097D01*
G01X1355459D02*
X1357155D01*
G01X1351527D02*
X1353223D01*
G01X1347585D02*
X1349281D01*
G01X1343653D02*
X1345349D01*
G01X1339711D02*
X1341407D01*
G01X1335779D02*
X1337475D01*
G01X1331837D02*
X1333533D01*
G01X1327905D02*
X1329601D01*
G01X1323963D02*
X1325659D01*
G01X1325666Y519945D02*
X1323956D01*
G01X1329608D02*
X1327898D01*
G01X1333540D02*
X1331830D01*
G01X1337482D02*
X1335772D01*
G01X1341414D02*
X1339704D01*
G01X1345356D02*
X1343646D01*
G01X1349288D02*
X1347578D01*
G01X1353230D02*
X1351520D01*
G01X1357162D02*
X1355452D01*
G01X1361104D02*
X1359394D01*
G01X1365036D02*
X1363326D01*
G01X1368978D02*
X1367268D01*
G01X1372910D02*
X1371200D01*
G01X1376852D02*
X1375142D01*
G01X1380784D02*
X1379074D01*
G01X1384726D02*
X1383016D01*
G01X1388658D02*
X1386948D01*
G01X1386929Y519353D02*
X1388677D01*
G01X1382997D02*
X1384745D01*
G01X1379055D02*
X1380803D01*
G01X1375123D02*
X1376871D01*
G01X1371181D02*
X1372929D01*
G01X1367249D02*
X1368997D01*
G01X1363307D02*
X1365055D01*
G01X1359375D02*
X1361123D01*
G01X1355433D02*
X1357181D01*
G01X1351501D02*
X1353249D01*
G01X1347559D02*
X1349307D01*
G01X1343627D02*
X1345375D01*
G01X1339685D02*
X1341433D01*
G01X1335753D02*
X1337501D01*
G01X1331811D02*
X1333559D01*
G01X1327879D02*
X1329627D01*
G01X1323937D02*
X1325685D01*
G01X1325657Y519051D02*
X1323965D01*
G01X1329598D02*
X1327907D01*
G01X1333531D02*
X1331839D01*
G01X1337472D02*
X1335781D01*
G01X1341405D02*
X1339713D01*
G01X1345346D02*
X1343655D01*
G01X1349279D02*
X1347587D01*
G01X1353220D02*
X1351529D01*
G01X1357153D02*
X1355461D01*
G01X1361094D02*
X1359403D01*
G01X1365027D02*
X1363335D01*
G01X1368969D02*
X1367277D01*
G01X1372901D02*
X1371209D01*
G01X1376843D02*
X1375151D01*
G01X1380775D02*
X1379083D01*
G01X1384717D02*
X1383025D01*
G01X1388649D02*
X1386957D01*
G01X1325666Y518961D02*
X1323956D01*
G01X1329608D02*
X1327898D01*
G01X1333540D02*
X1331830D01*
G01X1337482D02*
X1335772D01*
G01X1341414D02*
X1339704D01*
G01X1345356D02*
X1343646D01*
G01X1349288D02*
X1347578D01*
G01X1353230D02*
X1351520D01*
G01X1357162D02*
X1355452D01*
G01X1361104D02*
X1359394D01*
G01X1365036D02*
X1363326D01*
G01X1368978D02*
X1367268D01*
G01X1372910D02*
X1371200D01*
G01X1376852D02*
X1375142D01*
G01X1380784D02*
X1379074D01*
G01X1384726D02*
X1383016D01*
G01X1388658D02*
X1386948D01*
G01X1386701Y518635D02*
X1388906D01*
G01X1382764D02*
X1384968D01*
G01X1378827D02*
X1381031D01*
G01X1374890D02*
X1377094D01*
G01X1370953D02*
X1373157D01*
G01X1367016D02*
X1369220D01*
G01X1363079D02*
X1365283D01*
G01X1359142D02*
X1361346D01*
G01X1355205D02*
X1357409D01*
G01X1351268D02*
X1353472D01*
G01X1347331D02*
X1349535D01*
G01X1343394D02*
X1345598D01*
G01X1339457D02*
X1341661D01*
G01X1335520D02*
X1337724D01*
G01X1331583D02*
X1333787D01*
G01X1327646D02*
X1329850D01*
G01X1323709D02*
X1325913D01*
G01X1386701Y518468D02*
X1388906D01*
G01X1382764D02*
X1384968D01*
G01X1378827D02*
X1381031D01*
G01X1374890D02*
X1377094D01*
G01X1370953D02*
X1373157D01*
G01X1367016D02*
X1369220D01*
G01X1363079D02*
X1365283D01*
G01X1359142D02*
X1361346D01*
G01X1355205D02*
X1357409D01*
G01X1351268D02*
X1353472D01*
G01X1347331D02*
X1349535D01*
G01X1343394D02*
X1345598D01*
G01X1339457D02*
X1341661D01*
G01X1335520D02*
X1337724D01*
G01X1331583D02*
X1333787D01*
G01X1327646D02*
X1329850D01*
G01X1323709D02*
X1325913D01*
G01Y515910D02*
X1323709D01*
G01X1329850D02*
X1327646D01*
G01X1333787D02*
X1331583D01*
G01X1337724D02*
X1335520D01*
G01X1341661D02*
X1339457D01*
G01X1345598D02*
X1343394D01*
G01X1349535D02*
X1347331D01*
G01X1353472D02*
X1351268D01*
G01X1357409D02*
X1355205D01*
G01X1361346D02*
X1359142D01*
G01X1365283D02*
X1363079D01*
G01X1369220D02*
X1367016D01*
G01X1373157D02*
X1370953D01*
G01X1377094D02*
X1374890D01*
G01X1381031D02*
X1378827D01*
G01X1384968D02*
X1382764D01*
G01X1388906D02*
X1386701D01*
G01X1325913Y515743D02*
X1323709D01*
G01X1329850D02*
X1327646D01*
G01X1333787D02*
X1331583D01*
G01X1337724D02*
X1335520D01*
G01X1341661D02*
X1339457D01*
G01X1345598D02*
X1343394D01*
G01X1349535D02*
X1347331D01*
G01X1353472D02*
X1351268D01*
G01X1357409D02*
X1355205D01*
G01X1361346D02*
X1359142D01*
G01X1365283D02*
X1363079D01*
G01X1369220D02*
X1367016D01*
G01X1373157D02*
X1370953D01*
G01X1377094D02*
X1374890D01*
G01X1381031D02*
X1378827D01*
G01X1384968D02*
X1382764D01*
G01X1388906D02*
X1386701D01*
G01X1386948Y515417D02*
X1388658D01*
G01X1383006D02*
X1384717D01*
G01X1379074D02*
X1380784D01*
G01X1375132D02*
X1376843D01*
G01X1371200D02*
X1372910D01*
G01X1367258D02*
X1368969D01*
G01X1363326D02*
X1365036D01*
G01X1359384D02*
X1361094D01*
G01X1355452D02*
X1357162D01*
G01X1351510D02*
X1353220D01*
G01X1347578D02*
X1349288D01*
G01X1343636D02*
X1345346D01*
G01X1339704D02*
X1341414D01*
G01X1335762D02*
X1337472D01*
G01X1331830D02*
X1333540D01*
G01X1327888D02*
X1329598D01*
G01X1323956D02*
X1325666D01*
G01X1386957Y515327D02*
X1388649D01*
G01X1383016D02*
X1384707D01*
G01X1379083D02*
X1380775D01*
G01X1375142D02*
X1376833D01*
G01X1371209D02*
X1372901D01*
G01X1367268D02*
X1368959D01*
G01X1363335D02*
X1365027D01*
G01X1359394D02*
X1361085D01*
G01X1355461D02*
X1357153D01*
G01X1351520D02*
X1353211D01*
G01X1347587D02*
X1349279D01*
G01X1343646D02*
X1345337D01*
G01X1339713D02*
X1341405D01*
G01X1335772D02*
X1337463D01*
G01X1331839D02*
X1333531D01*
G01X1327898D02*
X1329589D01*
G01X1323965D02*
X1325657D01*
G01X1325685Y515025D02*
X1323937D01*
G01X1329618D02*
X1327869D01*
G01X1333559D02*
X1331811D01*
G01X1337492D02*
X1335743D01*
G01X1341433D02*
X1339685D01*
G01X1345366D02*
X1343617D01*
G01X1349307D02*
X1347559D01*
G01X1353240D02*
X1351491D01*
G01X1357181D02*
X1355433D01*
G01X1361114D02*
X1359365D01*
G01X1365055D02*
X1363307D01*
G01X1368988D02*
X1367239D01*
G01X1372929D02*
X1371181D01*
G01X1376862D02*
X1375113D01*
G01X1380803D02*
X1379055D01*
G01X1384736D02*
X1382987D01*
G01X1388677D02*
X1386929D01*
G01X1386948Y514433D02*
X1388658D01*
G01X1383006D02*
X1384717D01*
G01X1379074D02*
X1380784D01*
G01X1375132D02*
X1376843D01*
G01X1371200D02*
X1372910D01*
G01X1367258D02*
X1368969D01*
G01X1363326D02*
X1365036D01*
G01X1359384D02*
X1361094D01*
G01X1355452D02*
X1357162D01*
G01X1351510D02*
X1353220D01*
G01X1347578D02*
X1349288D01*
G01X1343636D02*
X1345346D01*
G01X1339704D02*
X1341414D01*
G01X1335762D02*
X1337472D01*
G01X1331830D02*
X1333540D01*
G01X1327888D02*
X1329598D01*
G01X1323956D02*
X1325666D01*
G01X1325659Y514365D02*
X1323963D01*
G01X1329591D02*
X1327895D01*
G01X1333533D02*
X1331837D01*
G01X1337465D02*
X1335769D01*
G01X1341407D02*
X1339711D01*
G01X1345339D02*
X1343643D01*
G01X1349281D02*
X1347585D01*
G01X1353213D02*
X1351517D01*
G01X1357155D02*
X1355459D01*
G01X1361087D02*
X1359391D01*
G01X1365029D02*
X1363333D01*
G01X1368962D02*
X1367265D01*
G01X1372903D02*
X1371207D01*
G01X1376836D02*
X1375139D01*
G01X1380777D02*
X1379081D01*
G01X1384710D02*
X1383013D01*
G01X1388651D02*
X1386955D01*
G01X1325606Y514341D02*
X1324016D01*
G01X1329539D02*
X1327948D01*
G01X1333480D02*
X1331890D01*
G01X1337413D02*
X1335822D01*
G01X1341354D02*
X1339764D01*
G01X1345287D02*
X1343696D01*
G01X1349228D02*
X1347638D01*
G01X1353161D02*
X1351570D01*
G01X1357102D02*
X1355512D01*
G01X1361035D02*
X1359444D01*
G01X1364976D02*
X1363386D01*
G01X1368909D02*
X1367318D01*
G01X1372850D02*
X1371260D01*
G01X1376783D02*
X1375192D01*
G01X1380724D02*
X1379134D01*
G01X1384657D02*
X1383066D01*
G01X1388598D02*
X1387008D01*
G01X1386934Y514139D02*
X1388673D01*
G01X1382992D02*
X1384731D01*
G01X1379060D02*
X1380799D01*
G01X1375118D02*
X1376857D01*
G01X1371186D02*
X1372925D01*
G01X1367244D02*
X1368983D01*
G01X1363312D02*
X1365051D01*
G01X1359370D02*
X1361109D01*
G01X1355438D02*
X1357176D01*
G01X1351496D02*
X1353235D01*
G01X1347564D02*
X1349302D01*
G01X1343622D02*
X1345361D01*
G01X1339690D02*
X1341428D01*
G01X1335748D02*
X1337487D01*
G01X1331816D02*
X1333554D01*
G01X1327874D02*
X1329613D01*
G01X1323942D02*
X1325680D01*
G01X1386701Y513488D02*
X1388906D01*
G01X1382764D02*
X1384968D01*
G01X1378827D02*
X1381031D01*
G01X1374890D02*
X1377094D01*
G01X1370953D02*
X1373157D01*
G01X1367016D02*
X1369220D01*
G01X1363079D02*
X1365283D01*
G01X1359142D02*
X1361346D01*
G01X1355205D02*
X1357409D01*
G01X1351268D02*
X1353472D01*
G01X1347331D02*
X1349535D01*
G01X1343394D02*
X1345598D01*
G01X1339457D02*
X1341661D01*
G01X1335520D02*
X1337724D01*
G01X1331583D02*
X1333787D01*
G01X1327646D02*
X1329850D01*
G01X1323709D02*
X1325913D01*
G01X1387006Y513379D02*
X1388601D01*
G01X1383064D02*
X1384659D01*
G01X1379132D02*
X1380727D01*
G01X1375190D02*
X1376785D01*
G01X1371258D02*
X1372853D01*
G01X1367316D02*
X1368911D01*
G01X1363384D02*
X1364979D01*
G01X1359442D02*
X1361037D01*
G01X1355510D02*
X1357105D01*
G01X1351568D02*
X1353163D01*
G01X1347635D02*
X1349231D01*
G01X1343694D02*
X1345289D01*
G01X1339761D02*
X1341357D01*
G01X1335820D02*
X1337415D01*
G01X1331887D02*
X1333483D01*
G01X1327946D02*
X1329541D01*
G01X1324013D02*
X1325609D01*
G01X1329417Y512760D02*
X1328079D01*
G01X1337291D02*
X1335953D01*
G01X1345165D02*
X1343827D01*
G01X1353039D02*
X1351701D01*
G01X1360913D02*
X1359575D01*
G01X1368787D02*
X1367449D01*
G01X1376661D02*
X1375323D01*
G01X1384535D02*
X1383197D01*
G01X1329417Y511776D02*
X1328079D01*
G01X1337291D02*
X1335953D01*
G01X1345165D02*
X1343827D01*
G01X1353039D02*
X1351701D01*
G01X1360913D02*
X1359575D01*
G01X1368787D02*
X1367449D01*
G01X1376661D02*
X1375323D01*
G01X1384535D02*
X1383197D01*
G01X1383039Y511677D02*
X1384693D01*
G01X1375165D02*
X1376819D01*
G01X1367291D02*
X1368945D01*
G01X1359417D02*
X1361071D01*
G01X1351543D02*
X1353197D01*
G01X1343669D02*
X1345323D01*
G01X1335795D02*
X1337449D01*
G01X1327921D02*
X1329575D01*
G01Y511185D02*
X1327921D01*
G01X1337449D02*
X1335795D01*
G01X1345323D02*
X1343669D01*
G01X1353197D02*
X1351543D01*
G01X1361071D02*
X1359417D01*
G01X1368945D02*
X1367291D01*
G01X1376819D02*
X1375165D01*
G01X1384693D02*
X1383039D01*
G01X1378030Y547622D02*
X1379506Y547873D01*
G01X1378030Y548879D02*
X1379260Y549130D01*
G01X1387284Y509984D02*
X1387275Y509937D01*
G01X1383343Y509984D02*
X1383333Y509937D01*
G01X1384390Y524394D02*
X1384399Y524441D01*
G01X1379401Y509937D02*
X1379410Y509984D01*
G01X1380457Y524441D02*
X1380448Y524394D01*
G01X1375469Y509984D02*
X1375459Y509937D01*
G01X1376515Y524394D02*
X1376525Y524441D01*
G01X1371527Y509937D02*
X1371536Y509984D01*
G01X1372583Y524441D02*
X1372574Y524394D01*
G01X1382213Y551140D02*
X1382459Y552397D01*
G01X1380982Y551140D02*
X1381228Y552648D01*
G01X1384659Y513379D02*
X1384710Y514365D01*
G01X1384707Y515327D02*
X1384657Y514341D01*
G01X1383025Y519051D02*
X1383076Y520037D01*
G01X1383073Y520999D02*
X1383023Y520013D01*
G01X1380727Y513379D02*
X1380777Y514365D01*
G01X1380775Y515327D02*
X1380724Y514341D01*
G01X1379083Y519051D02*
X1379134Y520037D01*
G01X1379132Y520999D02*
X1379081Y520013D01*
G01X1376785Y513379D02*
X1376836Y514365D01*
G01X1376833Y515327D02*
X1376783Y514341D01*
G01X1375151Y519051D02*
X1375202Y520037D01*
G01X1375199Y520999D02*
X1375149Y520013D01*
G01X1372853Y513379D02*
X1372903Y514365D01*
G01X1372901Y515327D02*
X1372850Y514341D01*
G01X1371209Y519051D02*
X1371260Y520037D01*
G01X1371258Y520999D02*
X1371207Y520013D01*
G01X1368911Y513379D02*
X1368962Y514365D01*
G01X1368959Y515327D02*
X1368909Y514341D01*
G01X1367277Y519051D02*
X1367328Y520037D01*
G01X1367325Y520999D02*
X1367275Y520013D01*
G01X1364979Y513379D02*
X1365029Y514365D01*
G01X1365027Y515327D02*
X1364976Y514341D01*
G01X1363335Y519051D02*
X1363386Y520037D01*
G01X1363384Y520999D02*
X1363333Y520013D01*
G01X1361037Y513379D02*
X1361087Y514365D01*
G01X1361085Y515327D02*
X1361035Y514341D01*
G01X1382856Y508231D02*
X1382992Y514139D01*
G01X1382987Y515025D02*
X1382851Y509117D01*
G01X1380803Y519353D02*
X1380940Y525261D01*
G01X1380935Y526147D02*
X1380799Y520239D01*
G01X1378924Y508231D02*
X1379060Y514139D01*
G01X1379055Y515025D02*
X1378919Y509117D01*
G01X1376871Y519353D02*
X1377007Y525261D01*
G01X1377002Y526147D02*
X1376866Y520239D01*
G01X1374982Y508231D02*
X1375118Y514139D01*
G01X1375113Y515025D02*
X1374977Y509117D01*
G01X1372929Y519353D02*
X1373066Y525261D01*
G01X1373061Y526147D02*
X1372925Y520239D01*
G01X1371049Y508231D02*
X1371186Y514139D01*
G01X1371181Y515025D02*
X1371045Y509117D01*
G01X1368997Y519353D02*
X1369133Y525261D01*
G01X1369128Y526147D02*
X1368992Y520239D01*
G01X1367108Y508231D02*
X1367244Y514139D01*
G01X1367239Y515025D02*
X1367103Y509117D01*
G01X1365055Y519353D02*
X1365192Y525261D01*
G01X1365187Y526147D02*
X1365051Y520239D01*
G01X1363175Y508231D02*
X1363312Y514139D01*
G01X1363307Y515025D02*
X1363171Y509117D01*
G01X1361123Y519353D02*
X1361259Y525261D01*
G01X1361254Y526147D02*
X1361118Y520239D01*
G01X1359234Y508231D02*
X1359370Y514139D01*
G01X1359365Y515025D02*
X1359229Y509117D01*
G01X1380425Y509984D02*
X1380412Y509010D01*
G01X1379433Y524394D02*
X1379446Y525368D01*
G01X1376483Y509984D02*
X1376470Y509010D01*
G01X1375501Y524394D02*
X1375514Y525368D01*
G01X1372551Y509984D02*
X1372538Y509010D01*
G01X1371559Y524394D02*
X1371572Y525368D01*
G01X1368609Y509984D02*
X1368596Y509010D01*
G01X1367627Y524394D02*
X1367640Y525368D01*
G01X1364677Y509984D02*
X1364664Y509010D01*
G01X1363685Y524394D02*
X1363698Y525368D01*
G01X1360735Y509984D02*
X1360722Y509010D01*
G01X1359753Y524394D02*
X1359766Y525368D01*
G01X1381346Y523862D02*
Y528035D01*
G01Y506343D02*
Y510516D01*
G01X1381312Y508823D02*
Y507839D01*
G01X1381307Y508823D02*
Y507839D01*
G01Y526539D02*
Y525555D01*
G01X1381110Y509984D02*
Y503902D01*
G01Y530476D02*
Y524394D01*
G01X1381031Y507839D02*
Y526539D01*
G01X1380953Y508825D02*
Y507840D01*
G01Y526538D02*
Y525553D01*
G01X1380756Y525555D02*
Y530396D01*
G01Y503982D02*
Y508823D01*
G01X1380677Y524760D02*
Y525751D01*
G01Y508627D02*
Y509618D01*
G01X1380598Y504965D02*
Y503902D01*
G01Y530476D02*
Y529413D01*
G01X1380323Y503902D02*
Y504886D01*
G01Y530476D02*
Y529492D01*
G01X1379535Y504886D02*
Y503902D01*
G01Y530476D02*
Y529492D01*
G01X1379260Y504965D02*
Y503902D01*
G01Y530476D02*
Y529413D01*
G01X1379181Y509618D02*
Y508627D01*
G01Y525751D02*
Y524760D01*
G01X1379102Y525555D02*
Y530396D01*
G01Y503982D02*
Y508823D01*
G01X1378906Y507840D02*
Y508825D01*
G01Y525553D02*
Y526538D01*
G01X1378827Y526539D02*
Y507839D01*
G01X1378748Y509984D02*
Y503902D01*
G01Y530476D02*
Y524394D01*
G01X1378551Y508823D02*
Y507839D01*
G01Y526539D02*
Y525555D01*
G01X1378547Y526539D02*
Y525555D01*
G01X1378512Y510516D02*
Y506343D01*
G01Y528035D02*
Y523862D01*
G01X1377409D02*
Y528035D01*
G01Y506343D02*
Y510516D01*
G01X1377375Y526539D02*
Y525555D01*
G01X1377370Y508823D02*
Y507839D01*
G01X1377365Y508823D02*
Y507839D01*
G01X1377173Y509984D02*
Y503902D01*
G01Y530476D02*
Y524394D01*
G01X1377094Y507839D02*
Y526539D01*
G01X1377020Y526538D02*
Y525553D01*
G01X1377011Y508825D02*
Y507840D01*
G01X1376819Y521698D02*
Y526539D01*
G01Y507839D02*
Y512680D01*
G01X1376745Y524760D02*
Y525751D01*
G01X1376735Y508627D02*
Y509618D01*
G01X1376661Y512760D02*
Y511696D01*
G01Y522681D02*
Y521618D01*
G01X1376386D02*
Y522602D01*
G01Y512760D02*
Y511776D01*
G01X1375598Y521618D02*
Y522602D01*
G01Y512760D02*
Y511776D01*
G01X1375323Y512760D02*
Y511696D01*
G01Y522682D02*
Y521618D01*
G01X1375249Y525751D02*
Y524760D01*
G01X1375239Y509618D02*
Y508627D01*
G01X1375165Y521698D02*
Y526539D01*
G01Y507839D02*
Y512680D01*
G01X1374973Y525553D02*
Y526538D01*
G01X1374964Y507840D02*
Y508825D01*
G01X1374890Y526539D02*
Y507839D01*
G01X1374811Y509984D02*
Y503902D01*
G01Y530476D02*
Y524394D01*
G01X1374619Y526539D02*
Y525555D01*
G01X1374614Y526539D02*
Y525555D01*
G01X1374610Y508823D02*
Y507839D01*
G01X1374575Y510516D02*
Y506343D01*
G01Y528035D02*
Y523862D01*
G01X1373472D02*
Y528035D01*
G01Y506343D02*
Y510516D01*
G01X1373438Y508823D02*
Y507839D01*
G01X1373433Y508823D02*
Y507839D01*
G01Y526539D02*
Y525555D01*
G01X1373236Y509984D02*
Y503902D01*
G01Y530476D02*
Y524394D01*
G01X1373157Y507839D02*
Y526539D01*
G01X1373079Y508825D02*
Y507840D01*
G01Y526538D02*
Y525553D01*
G01X1372882Y525555D02*
Y530396D01*
G01Y503982D02*
Y508823D01*
G01X1372803Y524760D02*
Y525751D01*
G01Y508627D02*
Y509618D01*
G01X1372724Y504965D02*
Y503902D01*
G01Y530476D02*
Y529413D01*
G01X1372449Y503902D02*
Y504886D01*
G01Y530476D02*
Y529492D01*
G01X1371661Y504886D02*
Y503902D01*
G01Y530476D02*
Y529492D01*
G01X1371632Y559433D02*
Y547622D01*
G01X1371386Y504965D02*
Y503902D01*
G01Y530476D02*
Y529413D01*
G01X1371307Y509618D02*
Y508627D01*
G01Y525751D02*
Y524760D01*
G01X1371228Y525555D02*
Y530396D01*
G01Y503982D02*
Y508823D01*
G01X1371031Y507840D02*
Y508825D01*
G01Y525553D02*
Y526538D01*
G01X1370953Y526539D02*
Y507839D01*
G01X1370874Y509984D02*
Y503902D01*
G01Y530476D02*
Y524394D01*
G01X1370677Y508823D02*
Y507839D01*
G01Y526539D02*
Y525555D01*
G01X1370672Y526539D02*
Y525555D01*
G01X1370638Y510516D02*
Y506343D01*
G01Y528035D02*
Y523862D01*
G01X1370156Y547622D02*
Y557423D01*
G01X1369535Y523862D02*
Y528035D01*
G01Y506343D02*
Y510516D01*
G01X1369501Y526539D02*
Y525555D01*
G01X1369496Y508823D02*
Y507839D01*
G01X1369491Y508823D02*
Y507839D01*
G01X1369299Y509984D02*
Y503902D01*
G01Y530476D02*
Y524394D01*
G01X1369220Y507839D02*
Y526539D01*
G01X1369146Y526538D02*
Y525553D01*
G01X1369137Y508825D02*
Y507840D01*
G01X1368945Y521698D02*
Y526539D01*
G01Y507839D02*
Y512680D01*
G01X1368871Y524760D02*
Y525751D01*
G01X1368861Y508627D02*
Y509618D01*
G01X1368787Y512760D02*
Y511696D01*
G01Y522681D02*
Y521618D01*
G01X1368512D02*
Y522602D01*
G01Y512760D02*
Y511776D01*
G01X1367724Y521618D02*
Y522602D01*
G01Y512760D02*
Y511776D01*
G01X1367449Y512760D02*
Y511696D01*
G01Y522682D02*
Y521618D01*
G01X1367375Y525751D02*
Y524760D01*
G01X1367365Y509618D02*
Y508627D01*
G01X1367291Y521698D02*
Y526539D01*
G01Y507839D02*
Y512680D01*
G01X1367099Y525553D02*
Y526538D01*
G01X1367090Y507840D02*
Y508825D01*
G01X1367016Y526539D02*
Y507839D01*
G01X1366937Y509984D02*
Y503902D01*
G01Y530476D02*
Y524394D01*
G01X1366745Y526539D02*
Y525555D01*
G01X1366740Y526539D02*
Y525555D01*
G01X1366735Y508823D02*
Y507839D01*
G01X1366701Y510516D02*
Y506343D01*
G01Y528035D02*
Y523862D01*
G01X1365598D02*
Y528035D01*
G01Y506343D02*
Y510516D01*
G01X1365564Y508823D02*
Y507839D01*
G01X1365559Y508823D02*
Y507839D01*
G01Y526539D02*
Y525555D01*
G01X1365362Y509984D02*
Y503902D01*
G01Y530476D02*
Y524394D01*
G01X1365283Y507839D02*
Y526539D01*
G01X1365205Y508825D02*
Y507840D01*
G01Y526538D02*
Y525553D01*
G01X1365008Y525555D02*
Y530396D01*
G01Y503982D02*
Y508823D01*
G01X1364929Y524760D02*
Y525751D01*
G01Y508627D02*
Y509618D01*
G01X1364850Y504965D02*
Y503902D01*
G01Y530476D02*
Y529413D01*
G01X1364575Y504886D02*
Y503902D01*
G01Y530476D02*
Y529492D01*
G01X1363787D02*
Y530476D01*
G01Y504886D02*
Y503902D01*
G01X1363512Y504965D02*
Y503902D01*
G01Y530476D02*
Y529413D01*
G01X1363433Y509618D02*
Y508627D01*
G01Y525751D02*
Y524760D01*
G01X1363354Y525555D02*
Y530396D01*
G01Y503982D02*
Y508823D01*
G01X1363157Y525553D02*
Y526538D01*
G01Y507840D02*
Y508825D01*
G01X1363079Y526539D02*
Y507839D01*
G01X1363000Y509984D02*
Y503902D01*
G01Y530476D02*
Y524394D01*
G01X1362803Y508823D02*
Y507839D01*
G01Y526539D02*
Y525555D01*
G01X1362798Y526539D02*
Y525555D01*
G01X1362764Y510516D02*
Y506343D01*
G01Y528035D02*
Y523862D01*
G01X1361661D02*
Y528035D01*
G01Y506343D02*
Y510516D01*
G01X1361627Y526539D02*
Y525555D01*
G01X1361622Y508823D02*
Y507839D01*
G01X1361617Y508823D02*
Y507839D01*
G01X1361425Y509984D02*
Y503902D01*
G01Y530476D02*
Y524394D01*
G01X1361346Y507839D02*
Y526539D01*
G01X1361272Y526538D02*
Y525553D01*
G01X1361263Y508825D02*
Y507840D01*
G01X1361071Y521698D02*
Y526539D01*
G01Y507839D02*
Y512680D01*
G01X1360997Y524760D02*
Y525751D01*
G01X1360987Y508627D02*
Y509618D01*
G01X1360913Y512760D02*
Y511696D01*
G01Y522681D02*
Y521618D01*
G01X1360638Y512760D02*
Y511776D01*
G01Y522602D02*
Y521618D01*
G01X1359850Y512760D02*
Y511776D01*
G01Y522602D02*
Y521618D01*
G01X1359575Y512760D02*
Y511696D01*
G01Y522682D02*
Y521618D01*
G01Y559433D02*
Y547622D01*
G01X1359501Y525751D02*
Y524760D01*
G01X1359491Y509618D02*
Y508627D01*
G01X1359417Y521698D02*
Y526539D01*
G01Y507839D02*
Y512680D01*
G01X1359225Y525553D02*
Y526538D01*
G01X1359216Y507840D02*
Y508825D01*
G01X1359142Y526539D02*
Y507839D01*
G01X1359063Y509984D02*
Y503902D01*
G01Y530476D02*
Y524394D01*
G01X1358871Y526539D02*
Y525555D01*
G01X1358866Y526539D02*
Y525555D01*
G01X1358861Y508823D02*
Y507839D01*
G01X1358827Y510516D02*
Y506343D01*
G01Y528035D02*
Y523862D01*
G01X1358098Y547622D02*
Y553151D01*
G01X1357724Y523862D02*
Y528035D01*
G01Y506343D02*
Y510516D01*
G01X1357690Y508823D02*
Y507839D01*
G01X1357685Y508823D02*
Y507839D01*
G01Y526539D02*
Y525555D01*
G01X1380412Y525368D02*
X1380425Y524394D01*
G01X1379446Y509010D02*
X1379433Y509984D01*
G01X1376479Y525368D02*
X1376493Y524394D01*
G01X1375505Y509010D02*
X1375492Y509984D01*
G01X1372538Y525368D02*
X1372551Y524394D01*
G01X1371572Y509010D02*
X1371559Y509984D01*
G01X1368605Y525368D02*
X1368619Y524394D01*
G01X1367631Y509010D02*
X1367618Y509984D01*
G01X1364664Y525368D02*
X1364677Y524394D01*
G01X1363698Y509010D02*
X1363685Y509984D01*
G01X1360731Y525368D02*
X1360745Y524394D01*
G01X1359757Y509010D02*
X1359744Y509984D01*
G01X1356790Y525368D02*
X1356803Y524394D01*
G01X1380940Y509117D02*
X1380803Y515025D01*
G01X1380799Y514139D02*
X1380935Y508231D01*
G01X1379060Y520239D02*
X1378924Y526147D01*
G01X1378919Y525261D02*
X1379055Y519353D01*
G01X1376998Y509117D02*
X1376862Y515025D01*
G01X1376857Y514139D02*
X1376993Y508231D01*
G01X1375127Y520239D02*
X1374991Y526147D01*
G01X1374986Y525261D02*
X1375123Y519353D01*
G01X1373066Y509117D02*
X1372929Y515025D01*
G01X1372925Y514139D02*
X1373061Y508231D01*
G01X1371186Y520239D02*
X1371049Y526147D01*
G01X1371045Y525261D02*
X1371181Y519353D01*
G01X1369124Y509117D02*
X1368988Y515025D01*
G01X1368983Y514139D02*
X1369119Y508231D01*
G01X1367253Y520239D02*
X1367117Y526147D01*
G01X1367112Y525261D02*
X1367249Y519353D01*
G01X1365192Y509117D02*
X1365055Y515025D01*
G01X1365051Y514139D02*
X1365187Y508231D01*
G01X1363312Y520239D02*
X1363175Y526147D01*
G01X1363171Y525261D02*
X1363307Y519353D01*
G01X1361250Y509117D02*
X1361114Y515025D01*
G01X1361109Y514139D02*
X1361245Y508231D01*
G01X1359379Y520239D02*
X1359243Y526147D01*
G01X1359238Y525261D02*
X1359375Y519353D01*
G01X1357317Y509117D02*
X1357181Y515025D01*
G01X1357176Y514139D02*
X1357313Y508231D01*
G01X1379134Y514341D02*
X1379083Y515327D01*
G01X1379081Y514365D02*
X1379132Y513379D01*
G01X1376845Y520013D02*
X1376794Y520999D01*
G01X1376792Y520037D02*
X1376843Y519051D01*
G01X1375192Y514341D02*
X1375142Y515327D01*
G01X1375139Y514365D02*
X1375190Y513379D01*
G01X1372903Y520013D02*
X1372853Y520999D01*
G01X1372850Y520037D02*
X1372901Y519051D01*
G01X1371260Y514341D02*
X1371209Y515327D01*
G01X1371207Y514365D02*
X1371258Y513379D01*
G01X1368971Y520013D02*
X1368920Y520999D01*
G01X1368918Y520037D02*
X1368969Y519051D01*
G01X1367318Y514341D02*
X1367268Y515327D01*
G01X1367265Y514365D02*
X1367316Y513379D01*
G01X1365029Y520013D02*
X1364979Y520999D01*
G01X1364976Y520037D02*
X1365027Y519051D01*
G01X1363386Y514341D02*
X1363335Y515327D01*
G01X1363333Y514365D02*
X1363384Y513379D01*
G01X1361097Y520013D02*
X1361046Y520999D01*
G01X1361044Y520037D02*
X1361094Y519051D01*
G01X1359444Y514341D02*
X1359394Y515327D01*
G01X1359391Y514365D02*
X1359442Y513379D01*
G01X1357155Y520013D02*
X1357105Y520999D01*
G01X1357102Y520037D02*
X1357153Y519051D01*
G01X1355512Y514341D02*
X1355461Y515327D01*
G01X1355459Y514365D02*
X1355510Y513379D01*
G01X1343972Y524441D02*
X1343982Y524394D01*
G01X1345020Y509937D02*
X1345010Y509984D01*
G01X1340031Y524441D02*
X1340040Y524394D01*
G01X1341087Y509937D02*
X1341078Y509984D01*
G01X1336098Y524441D02*
X1336108Y524394D01*
G01X1337146Y509937D02*
X1337136Y509984D01*
G01X1332157Y524441D02*
X1332166Y524394D01*
G01X1333213Y509937D02*
X1333204Y509984D01*
G01X1328224Y524441D02*
X1328234Y524394D01*
G01X1329272Y509937D02*
X1329262Y509984D01*
G01X1324283Y524441D02*
X1324292Y524394D01*
G01X1325339Y509937D02*
X1325330Y509984D01*
G01X1333213Y509937D02*
X1333435Y509615D01*
G01X1333422Y508640D02*
X1333168Y509010D01*
G01X1329272Y509937D02*
X1329493Y509615D01*
G01X1329480Y508640D02*
X1329226Y509010D01*
G01X1325339Y509937D02*
X1325561Y509615D01*
G01X1325548Y508640D02*
X1325294Y509010D01*
G01X1321398Y509937D02*
X1321619Y509615D01*
G01X1321606Y508640D02*
X1321352Y509010D01*
G01X1325572Y510571D02*
X1324050D01*
G01X1329504D02*
X1327983D01*
G01X1333446D02*
X1331924D01*
G01X1337378D02*
X1335857D01*
G01X1341320D02*
X1339798D01*
G01X1345252D02*
X1343731D01*
G01X1349194D02*
X1347672D01*
G01X1353126D02*
X1351605D01*
G01X1357068D02*
X1355546D01*
G01X1361000D02*
X1359479D01*
G01X1364942D02*
X1363420D01*
G01X1368874D02*
X1367353D01*
G01X1372816D02*
X1371294D01*
G01X1376748D02*
X1375227D01*
G01X1380690D02*
X1379168D01*
G01X1384622D02*
X1383101D01*
G01X1388564D02*
X1387042D01*
G01X1325583Y510552D02*
X1324039D01*
G01X1329515D02*
X1327972D01*
G01X1333457D02*
X1331913D01*
G01X1337389D02*
X1335846D01*
G01X1341331D02*
X1339787D01*
G01X1345263D02*
X1343720D01*
G01X1349205D02*
X1347661D01*
G01X1353137D02*
X1351594D01*
G01X1357079D02*
X1355535D01*
G01X1361011D02*
X1359468D01*
G01X1364953D02*
X1363409D01*
G01X1368885D02*
X1367342D01*
G01X1372827D02*
X1371283D01*
G01X1376759D02*
X1375216D01*
G01X1380701D02*
X1379157D01*
G01X1384633D02*
X1383090D01*
G01X1388575D02*
X1387031D01*
G01X1322291Y510516D02*
X1321976D01*
G01X1323709D02*
X1323394D01*
G01X1326228D02*
X1325913D01*
G01X1327646D02*
X1327331D01*
G01X1330165D02*
X1329850D01*
G01X1331583D02*
X1331268D01*
G01X1334102D02*
X1333787D01*
G01X1335520D02*
X1335205D01*
G01X1338039D02*
X1337724D01*
G01X1339457D02*
X1339142D01*
G01X1341976D02*
X1341661D01*
G01X1343394D02*
X1343079D01*
G01X1345913D02*
X1345598D01*
G01X1347331D02*
X1347016D01*
G01X1349850D02*
X1349535D01*
G01X1351268D02*
X1350953D01*
G01X1353787D02*
X1353472D01*
G01X1355205D02*
X1354890D01*
G01X1357724D02*
X1357409D01*
G01X1359142D02*
X1358827D01*
G01X1361661D02*
X1361346D01*
G01X1363079D02*
X1362764D01*
G01X1365598D02*
X1365283D01*
G01X1367016D02*
X1366701D01*
G01X1369535D02*
X1369220D01*
G01X1370953D02*
X1370638D01*
G01X1373472D02*
X1373157D01*
G01X1374890D02*
X1374575D01*
G01X1377409D02*
X1377094D01*
G01X1378827D02*
X1378512D01*
G01X1381346D02*
X1381031D01*
G01X1382764D02*
X1382449D01*
G01X1385283D02*
X1384968D01*
G01X1386701D02*
X1386386D01*
G01X1325992Y509984D02*
X1323630D01*
G01X1329929D02*
X1327567D01*
G01X1333866D02*
X1331504D01*
G01X1337803D02*
X1335441D01*
G01X1341740D02*
X1339378D01*
G01X1345677D02*
X1343315D01*
G01X1349614D02*
X1347252D01*
G01X1353551D02*
X1351189D01*
G01X1357488D02*
X1355126D01*
G01X1361425D02*
X1359063D01*
G01X1365362D02*
X1363000D01*
G01X1369299D02*
X1366937D01*
G01X1373236D02*
X1370874D01*
G01X1377173D02*
X1374811D01*
G01X1381110D02*
X1378748D01*
G01X1385047D02*
X1382685D01*
G01X1388984D02*
X1386622D01*
G01X1321398Y509937D02*
X1320341D01*
G01X1325339D02*
X1324283D01*
G01X1329272D02*
X1328215D01*
G01X1333213D02*
X1332157D01*
G01X1337146D02*
X1336089D01*
G01X1341087D02*
X1340031D01*
G01X1345020D02*
X1343963D01*
G01X1348961D02*
X1347905D01*
G01X1352894D02*
X1351837D01*
G01X1356835D02*
X1355779D01*
G01X1360768D02*
X1359711D01*
G01X1364709D02*
X1363653D01*
G01X1368642D02*
X1367585D01*
G01X1372583D02*
X1371527D01*
G01X1376516D02*
X1375459D01*
G01X1380457D02*
X1379401D01*
G01X1384390D02*
X1383333D01*
G01X1388331D02*
X1387275D01*
G01X1387055Y509615D02*
X1388551D01*
G01X1383113D02*
X1384610D01*
G01X1379181D02*
X1380677D01*
G01X1375239D02*
X1376736D01*
G01X1371307D02*
X1372803D01*
G01X1367365D02*
X1368862D01*
G01X1363433D02*
X1364929D01*
G01X1359491D02*
X1360988D01*
G01X1355559D02*
X1357055D01*
G01X1351617D02*
X1353114D01*
G01X1347685D02*
X1349181D01*
G01X1343743D02*
X1345240D01*
G01X1339811D02*
X1341307D01*
G01X1335869D02*
X1337366D01*
G01X1331937D02*
X1333433D01*
G01X1327995D02*
X1329492D01*
G01X1324063D02*
X1325559D01*
G01X1387053Y509606D02*
X1388553D01*
G01X1383112D02*
X1384611D01*
G01X1379179D02*
X1380679D01*
G01X1375238D02*
X1376737D01*
G01X1371305D02*
X1372805D01*
G01X1367364D02*
X1368863D01*
G01X1363431D02*
X1364931D01*
G01X1359490D02*
X1360989D01*
G01X1355557D02*
X1357057D01*
G01X1351616D02*
X1353115D01*
G01X1347683D02*
X1349183D01*
G01X1343742D02*
X1345241D01*
G01X1339809D02*
X1341309D01*
G01X1335868D02*
X1337367D01*
G01X1331935D02*
X1333435D01*
G01X1327994D02*
X1329493D01*
G01X1324061D02*
X1325561D01*
G01X1329575Y509413D02*
X1327921D01*
G01X1337449D02*
X1335795D01*
G01X1345323D02*
X1343669D01*
G01X1353197D02*
X1351543D01*
G01X1361071D02*
X1359417D01*
G01X1368945D02*
X1367291D01*
G01X1376819D02*
X1375165D01*
G01X1384693D02*
X1383039D01*
G01X1386793Y509117D02*
X1388814D01*
G01X1382851D02*
X1384872D01*
G01X1378919D02*
X1380940D01*
G01X1374977D02*
X1376998D01*
G01X1371045D02*
X1373066D01*
G01X1367103D02*
X1369124D01*
G01X1363171D02*
X1365192D01*
G01X1359229D02*
X1361250D01*
G01X1355297D02*
X1357317D01*
G01X1351355D02*
X1353376D01*
G01X1347423D02*
X1349443D01*
G01X1343481D02*
X1345502D01*
G01X1339549D02*
X1341569D01*
G01X1335607D02*
X1337628D01*
G01X1331675D02*
X1333695D01*
G01X1327733D02*
X1329754D01*
G01X1323801D02*
X1325821D01*
G01X1384968Y509020D02*
X1385283D01*
G01X1377094D02*
X1377409D01*
G01X1369220D02*
X1369535D01*
G01X1365283D02*
X1365598D01*
G01X1361346D02*
X1361661D01*
G01X1357409D02*
X1357724D01*
G01X1353472D02*
X1353787D01*
G01X1349535D02*
X1349850D01*
G01X1345598D02*
X1345913D01*
G01X1341661D02*
X1341976D01*
G01X1337724D02*
X1338039D01*
G01X1333787D02*
X1334102D01*
G01X1329850D02*
X1330165D01*
G01X1325913D02*
X1326228D01*
G01X1321976D02*
X1322291D01*
G01X1323709D02*
X1323394D01*
G01X1327646D02*
X1327331D01*
G01X1331583D02*
X1331268D01*
G01X1335520D02*
X1335205D01*
G01X1339457D02*
X1339142D01*
G01X1343394D02*
X1343079D01*
G01X1347331D02*
X1347016D01*
G01X1351268D02*
X1350953D01*
G01X1355205D02*
X1354890D01*
G01X1359142D02*
X1358827D01*
G01X1363079D02*
X1362764D01*
G01X1367016D02*
X1366701D01*
G01X1370953D02*
X1370638D01*
G01X1373472D02*
X1373157D01*
G01X1374890D02*
X1374575D01*
G01X1378827D02*
X1378512D01*
G01X1381346D02*
X1381031D01*
G01X1382764D02*
X1382449D01*
G01X1386701D02*
X1386386D01*
G01X1387320Y509010D02*
X1388286D01*
G01X1383379D02*
X1384344D01*
G01X1379446D02*
X1380412D01*
G01X1375505D02*
X1376470D01*
G01X1371572D02*
X1372538D01*
G01X1367631D02*
X1368596D01*
G01X1363698D02*
X1364664D01*
G01X1359757D02*
X1360722D01*
G01X1355824D02*
X1356790D01*
G01X1351883D02*
X1352848D01*
G01X1347950D02*
X1348916D01*
G01X1344009D02*
X1344974D01*
G01X1340076D02*
X1341042D01*
G01X1336135D02*
X1337100D01*
G01X1332202D02*
X1333168D01*
G01X1328261D02*
X1329226D01*
G01X1324328D02*
X1325294D01*
G01X1320387D02*
X1321352D01*
G01X1383039Y508921D02*
X1384693D01*
G01X1375165D02*
X1376819D01*
G01X1367291D02*
X1368945D01*
G01X1359417D02*
X1361071D01*
G01X1351543D02*
X1353197D01*
G01X1343669D02*
X1345323D01*
G01X1335795D02*
X1337449D01*
G01X1327921D02*
X1329575D01*
G01X1386386Y508823D02*
X1389220D01*
G01X1382449D02*
X1385283D01*
G01X1378512D02*
X1381346D01*
G01X1374575D02*
X1377409D01*
G01X1370638D02*
X1373472D01*
G01X1366701D02*
X1369535D01*
G01X1362764D02*
X1365598D01*
G01X1358827D02*
X1361661D01*
G01X1354890D02*
X1357724D01*
G01X1350953D02*
X1353787D01*
G01X1347016D02*
X1349850D01*
G01X1343079D02*
X1345913D01*
G01X1339142D02*
X1341976D01*
G01X1335205D02*
X1338039D01*
G01X1331268D02*
X1334102D01*
G01X1327331D02*
X1330165D01*
G01X1323394D02*
X1326228D01*
G01X1386386Y508665D02*
X1386976D01*
G01X1384693D02*
X1385283D01*
G01X1382449D02*
X1383039D01*
G01X1380756D02*
X1381346D01*
G01X1378512D02*
X1379102D01*
G01X1376819D02*
X1377409D01*
G01X1374575D02*
X1375165D01*
G01X1372882D02*
X1373472D01*
G01X1370638D02*
X1371228D01*
G01X1368945D02*
X1369535D01*
G01X1366701D02*
X1367291D01*
G01X1365008D02*
X1365598D01*
G01X1362764D02*
X1363354D01*
G01X1361071D02*
X1361661D01*
G01X1358827D02*
X1359417D01*
G01X1357134D02*
X1357724D01*
G01X1354890D02*
X1355480D01*
G01X1353197D02*
X1353787D01*
G01X1350953D02*
X1351543D01*
G01X1349260D02*
X1349850D01*
G01X1347016D02*
X1347606D01*
G01X1345323D02*
X1345913D01*
G01X1343079D02*
X1343669D01*
G01X1341386D02*
X1341976D01*
G01X1339142D02*
X1339732D01*
G01X1337449D02*
X1338039D01*
G01X1335205D02*
X1335795D01*
G01X1333512D02*
X1334102D01*
G01X1331268D02*
X1331858D01*
G01X1329575D02*
X1330165D01*
G01X1327331D02*
X1327921D01*
G01X1325638D02*
X1326228D01*
G01X1323394D02*
X1323984D01*
G01X1321701D02*
X1322291D01*
G01X1325548Y508640D02*
X1324075D01*
G01X1329480D02*
X1328007D01*
G01X1333422D02*
X1331949D01*
G01X1337354D02*
X1335881D01*
G01X1341296D02*
X1339823D01*
G01X1345228D02*
X1343755D01*
G01X1349170D02*
X1347697D01*
G01X1353102D02*
X1351629D01*
G01X1357044D02*
X1355571D01*
G01X1360976D02*
X1359503D01*
G01X1364918D02*
X1363445D01*
G01X1368850D02*
X1367377D01*
G01X1372792D02*
X1371319D01*
G01X1376724D02*
X1375251D01*
G01X1380666D02*
X1379193D01*
G01X1384598D02*
X1383125D01*
G01X1388540D02*
X1387067D01*
G01X1387053Y508621D02*
X1388553D01*
G01X1383112D02*
X1384611D01*
G01X1379179D02*
X1380679D01*
G01X1375238D02*
X1376737D01*
G01X1371305D02*
X1372805D01*
G01X1367364D02*
X1368863D01*
G01X1363431D02*
X1364931D01*
G01X1359490D02*
X1360989D01*
G01X1355557D02*
X1357057D01*
G01X1351616D02*
X1353115D01*
G01X1347683D02*
X1349183D01*
G01X1343742D02*
X1345241D01*
G01X1339809D02*
X1341309D01*
G01X1335868D02*
X1337367D01*
G01X1331935D02*
X1333435D01*
G01X1327994D02*
X1329493D01*
G01X1324061D02*
X1325561D01*
G01X1325817Y508231D02*
X1323805D01*
G01X1329749D02*
X1327738D01*
G01X1333691D02*
X1331679D01*
G01X1337623D02*
X1335612D01*
G01X1341565D02*
X1339553D01*
G01X1345497D02*
X1343486D01*
G01X1349439D02*
X1347427D01*
G01X1353371D02*
X1351360D01*
G01X1357313D02*
X1355301D01*
G01X1361245D02*
X1359234D01*
G01X1365187D02*
X1363175D01*
G01X1369119D02*
X1367108D01*
G01X1373061D02*
X1371049D01*
G01X1376993D02*
X1374982D01*
G01X1380935D02*
X1378924D01*
G01X1384867D02*
X1382856D01*
G01X1388809D02*
X1386798D01*
G01X1322291Y507996D02*
X1321701D01*
G01X1323984D02*
X1323394D01*
G01X1326228D02*
X1325638D01*
G01X1327921D02*
X1327331D01*
G01X1330165D02*
X1329575D01*
G01X1331858D02*
X1331268D01*
G01X1334102D02*
X1333512D01*
G01X1335795D02*
X1335205D01*
G01X1338039D02*
X1337449D01*
G01X1339732D02*
X1339142D01*
G01X1341976D02*
X1341386D01*
G01X1343669D02*
X1343079D01*
G01X1345913D02*
X1345323D01*
G01X1347606D02*
X1347016D01*
G01X1349850D02*
X1349260D01*
G01X1351543D02*
X1350953D01*
G01X1353787D02*
X1353197D01*
G01X1355480D02*
X1354890D01*
G01X1357724D02*
X1357134D01*
G01X1359417D02*
X1358827D01*
G01X1361661D02*
X1361071D01*
G01X1363354D02*
X1362764D01*
G01X1365598D02*
X1365008D01*
G01X1367291D02*
X1366701D01*
G01X1369535D02*
X1368945D01*
G01X1371228D02*
X1370638D01*
G01X1373472D02*
X1372882D01*
G01X1375165D02*
X1374575D01*
G01X1377409D02*
X1376819D01*
G01X1379102D02*
X1378512D01*
G01X1381346D02*
X1380756D01*
G01X1383039D02*
X1382449D01*
G01X1385283D02*
X1384693D01*
G01X1386976D02*
X1386386D01*
G01X1326228Y507839D02*
X1323394D01*
G01X1330165D02*
X1327331D01*
G01X1334102D02*
X1331268D01*
G01X1338039D02*
X1335205D01*
G01X1341976D02*
X1339142D01*
G01X1345913D02*
X1343079D01*
G01X1349850D02*
X1347016D01*
G01X1353787D02*
X1350953D01*
G01X1357724D02*
X1354890D01*
G01X1361661D02*
X1358827D01*
G01X1365598D02*
X1362764D01*
G01X1369535D02*
X1366701D01*
G01X1373472D02*
X1370638D01*
G01X1377409D02*
X1374575D01*
G01X1381346D02*
X1378512D01*
G01X1385283D02*
X1382449D01*
G01X1389220D02*
X1386386D01*
G01X1325638Y507740D02*
X1323984D01*
G01X1333512D02*
X1331858D01*
G01X1341386D02*
X1339732D01*
G01X1349260D02*
X1347606D01*
G01X1357134D02*
X1355480D01*
G01X1365008D02*
X1363354D01*
G01X1372882D02*
X1371228D01*
G01X1380756D02*
X1379102D01*
G01X1388630D02*
X1386976D01*
G01Y507248D02*
X1388630D01*
G01X1379102D02*
X1380756D01*
G01X1371228D02*
X1372882D01*
G01X1363354D02*
X1365008D01*
G01X1355480D02*
X1357134D01*
G01X1347606D02*
X1349260D01*
G01X1339732D02*
X1341386D01*
G01X1331858D02*
X1333512D01*
G01X1323984D02*
X1325638D01*
G01X1386386Y506343D02*
X1389220D01*
G01X1382449D02*
X1385283D01*
G01X1378512D02*
X1381346D01*
G01X1374575D02*
X1377409D01*
G01X1370638D02*
X1373472D01*
G01X1366701D02*
X1369535D01*
G01X1362764D02*
X1365598D01*
G01X1358827D02*
X1361661D01*
G01X1354890D02*
X1357724D01*
G01X1350953D02*
X1353787D01*
G01X1347016D02*
X1349850D01*
G01X1343079D02*
X1345913D01*
G01X1339142D02*
X1341976D01*
G01X1335205D02*
X1338039D01*
G01X1331268D02*
X1334102D01*
G01X1327331D02*
X1330165D01*
G01X1323394D02*
X1326228D01*
G01X1386976Y505476D02*
X1388630D01*
G01X1379102D02*
X1380756D01*
G01X1371228D02*
X1372882D01*
G01X1363354D02*
X1365008D01*
G01X1355480D02*
X1357134D01*
G01X1347606D02*
X1349260D01*
G01X1339732D02*
X1341386D01*
G01X1331858D02*
X1333512D01*
G01X1323984D02*
X1325638D01*
G01X1378748Y505083D02*
X1381110D01*
G01X1374811D02*
X1377173D01*
G01X1370874D02*
X1373236D01*
G01X1366937D02*
X1369299D01*
G01X1325992D02*
X1323630D01*
G01X1329929D02*
X1327567D01*
G01X1333866D02*
X1331504D01*
G01X1337803D02*
X1335441D01*
G01X1341740D02*
X1339378D01*
G01X1345677D02*
X1343315D01*
G01X1349614D02*
X1347252D01*
G01X1353551D02*
X1351189D01*
G01X1357488D02*
X1355126D01*
G01X1361425D02*
X1359063D01*
G01X1365362D02*
X1363000D01*
G01X1385047D02*
X1382685D01*
G01X1388984D02*
X1386622D01*
G01X1325638Y504984D02*
X1323984D01*
G01X1333512D02*
X1331858D01*
G01X1341386D02*
X1339732D01*
G01X1349260D02*
X1347606D01*
G01X1357134D02*
X1355480D01*
G01X1365008D02*
X1363354D01*
G01X1372882D02*
X1371228D01*
G01X1380756D02*
X1379102D01*
G01X1388630D02*
X1386976D01*
G01X1325480Y504886D02*
X1324142D01*
G01X1333354D02*
X1332016D01*
G01X1341228D02*
X1339890D01*
G01X1349102D02*
X1347764D01*
G01X1356976D02*
X1355638D01*
G01X1364850D02*
X1363512D01*
G01X1372724D02*
X1371386D01*
G01X1380598D02*
X1379260D01*
G01X1388472D02*
X1387134D01*
G01X1386622Y503902D02*
X1388984D01*
G01X1382685D02*
X1385047D01*
G01X1378748D02*
X1381110D01*
G01X1374811D02*
X1377173D01*
G01X1370874D02*
X1373236D01*
G01X1366937D02*
X1369299D01*
G01X1363000D02*
X1365362D01*
G01X1359063D02*
X1361425D01*
G01X1355126D02*
X1357488D01*
G01X1351189D02*
X1353551D01*
G01X1347252D02*
X1349614D01*
G01X1343315D02*
X1345677D01*
G01X1339378D02*
X1341740D01*
G01X1335441D02*
X1337803D01*
G01X1331504D02*
X1333866D01*
G01X1327567D02*
X1329929D01*
G01X1323630D02*
X1325992D01*
G01X1387067Y508640D02*
X1387320Y509010D01*
G01X1387054Y509615D02*
X1387275Y509937D01*
G01X1383125Y508640D02*
X1383379Y509010D01*
G01X1383112Y509615D02*
X1383333Y509937D01*
G01X1379193Y508640D02*
X1379446Y509010D01*
G01X1379401Y509937D02*
X1379181Y509618D01*
G01X1375251Y508640D02*
X1375505Y509010D01*
G01X1375238Y509615D02*
X1375459Y509937D01*
G01X1384620Y524763D02*
X1384399Y524441D01*
G01X1381474Y549381D02*
X1381967Y550386D01*
G01D02*
X1382213Y551140D01*
G01X1367595Y509984D02*
X1367585Y509937D01*
G01X1368641Y524394D02*
X1368651Y524441D01*
G01X1363662Y509984D02*
X1363653Y509937D01*
G01X1364700Y524394D02*
X1364709Y524441D01*
G01X1359721Y509984D02*
X1359711Y509937D01*
G01X1360767Y524394D02*
X1360777Y524441D01*
G01X1355788Y509984D02*
X1355779Y509937D01*
G01X1356826Y524394D02*
X1356835Y524441D01*
G01X1351847Y509984D02*
X1351837Y509937D01*
G01X1352893Y524394D02*
X1352903Y524441D01*
G01X1347914Y509984D02*
X1347905Y509937D01*
G01X1348952Y524394D02*
X1348961Y524441D01*
G01X1359403Y519051D02*
X1359454Y520037D01*
G01X1359451Y520999D02*
X1359401Y520013D01*
G01X1357105Y513379D02*
X1357155Y514365D01*
G01X1357153Y515327D02*
X1357102Y514341D01*
G01X1355461Y519051D02*
X1355512Y520037D01*
G01X1355510Y520999D02*
X1355459Y520013D01*
G01X1353163Y513379D02*
X1353213Y514365D01*
G01X1353211Y515327D02*
X1353161Y514341D01*
G01X1351529Y519051D02*
X1351579Y520037D01*
G01X1351577Y520999D02*
X1351527Y520013D01*
G01X1349231Y513379D02*
X1349281Y514365D01*
G01X1349279Y515327D02*
X1349228Y514341D01*
G01X1347587Y519051D02*
X1347638Y520037D01*
G01X1347635Y520999D02*
X1347585Y520013D01*
G01X1345289Y513379D02*
X1345339Y514365D01*
G01X1345337Y515327D02*
X1345287Y514341D01*
G01X1343655Y519051D02*
X1343705Y520037D01*
G01X1343703Y520999D02*
X1343653Y520013D01*
G01X1341357Y513379D02*
X1341407Y514365D01*
G01X1341405Y515327D02*
X1341354Y514341D01*
G01X1339713Y519051D02*
X1339764Y520037D01*
G01X1339761Y520999D02*
X1339711Y520013D01*
G01X1337415Y513379D02*
X1337465Y514365D01*
G01X1337463Y515327D02*
X1337413Y514341D01*
G01X1357181Y519353D02*
X1357317Y525261D01*
G01X1357313Y526147D02*
X1357176Y520239D01*
G01X1355301Y508231D02*
X1355438Y514139D01*
G01X1355433Y515025D02*
X1355297Y509117D01*
G01X1353249Y519353D02*
X1353385Y525261D01*
G01X1353380Y526147D02*
X1353244Y520239D01*
G01X1351360Y508231D02*
X1351496Y514139D01*
G01X1351491Y515025D02*
X1351355Y509117D01*
G01X1349307Y519353D02*
X1349443Y525261D01*
G01X1349439Y526147D02*
X1349302Y520239D01*
G01X1347427Y508231D02*
X1347564Y514139D01*
G01X1347559Y515025D02*
X1347423Y509117D01*
G01X1345375Y519353D02*
X1345511Y525261D01*
G01X1345506Y526147D02*
X1345370Y520239D01*
G01X1343486Y508231D02*
X1343622Y514139D01*
G01X1343617Y515025D02*
X1343481Y509117D01*
G01X1341433Y519353D02*
X1341569Y525261D01*
G01X1341565Y526147D02*
X1341428Y520239D01*
G01X1339553Y508231D02*
X1339690Y514139D01*
G01X1339685Y515025D02*
X1339549Y509117D01*
G01X1337501Y519353D02*
X1337637Y525261D01*
G01X1337632Y526147D02*
X1337496Y520239D01*
G01X1335612Y508231D02*
X1335748Y514139D01*
G01X1335743Y515025D02*
X1335607Y509117D01*
G01X1356803Y509984D02*
X1356790Y509010D01*
G01X1355811Y524394D02*
X1355824Y525368D01*
G01X1352861Y509984D02*
X1352848Y509010D01*
G01X1351879Y524394D02*
X1351892Y525368D01*
G01X1348929Y509984D02*
X1348916Y509010D01*
G01X1347937Y524394D02*
X1347950Y525368D01*
G01X1344987Y509984D02*
X1344974Y509010D01*
G01X1344005Y524394D02*
X1344018Y525368D01*
G01X1341055Y509984D02*
X1341042Y509010D01*
G01X1340063Y524394D02*
X1340076Y525368D01*
G01X1337113Y509984D02*
X1337100Y509010D01*
G01X1336131Y524394D02*
X1336144Y525368D01*
G01X1357488Y509984D02*
Y503902D01*
G01Y530476D02*
Y524394D01*
G01X1357409Y507839D02*
Y526539D01*
G01X1357331Y508825D02*
Y507840D01*
G01Y526538D02*
Y525553D01*
G01X1357134Y525555D02*
Y530396D01*
G01Y503982D02*
Y508823D01*
G01X1357055Y524760D02*
Y525751D01*
G01Y508627D02*
Y509618D01*
G01X1356976Y504965D02*
Y503902D01*
G01Y530476D02*
Y529413D01*
G01X1356701Y504886D02*
Y503902D01*
G01Y530476D02*
Y529492D01*
G01X1355913D02*
Y530476D01*
G01Y504886D02*
Y503902D01*
G01X1355638Y504965D02*
Y503902D01*
G01Y530476D02*
Y529413D01*
G01X1355559Y509618D02*
Y508627D01*
G01Y525751D02*
Y524760D01*
G01X1355480Y525555D02*
Y530396D01*
G01Y503982D02*
Y508823D01*
G01X1355283Y525553D02*
Y526538D01*
G01Y507840D02*
Y508825D01*
G01X1355205Y526539D02*
Y507839D01*
G01X1355126Y509984D02*
Y503902D01*
G01Y530476D02*
Y524394D01*
G01X1354929Y508823D02*
Y507839D01*
G01Y526539D02*
Y525555D01*
G01X1354924Y526539D02*
Y525555D01*
G01X1354890Y510516D02*
Y506343D01*
G01Y528035D02*
Y523862D01*
G01X1353787D02*
Y528035D01*
G01Y506343D02*
Y510516D01*
G01X1353753Y526539D02*
Y525555D01*
G01X1353748Y508823D02*
Y507839D01*
G01X1353743Y508823D02*
Y507839D01*
G01X1353551Y509984D02*
Y503902D01*
G01Y530476D02*
Y524394D01*
G01X1353472Y507839D02*
Y526539D01*
G01X1353398Y526538D02*
Y525553D01*
G01X1353389Y508825D02*
Y507840D01*
G01X1353197Y521698D02*
Y526539D01*
G01Y507839D02*
Y512680D01*
G01X1353123Y524760D02*
Y525751D01*
G01X1353113Y508627D02*
Y509618D01*
G01X1353039Y512760D02*
Y511696D01*
G01Y522681D02*
Y521618D01*
G01X1352764D02*
Y522602D01*
G01Y512760D02*
Y511776D01*
G01X1351976Y521618D02*
Y522602D01*
G01Y511776D02*
Y512760D01*
G01X1351701D02*
Y511696D01*
G01Y522682D02*
Y521618D01*
G01X1351627Y525751D02*
Y524760D01*
G01X1351617Y509618D02*
Y508627D01*
G01X1351543Y521698D02*
Y526539D01*
G01Y507839D02*
Y512680D01*
G01X1351351Y525553D02*
Y526538D01*
G01X1351342Y507840D02*
Y508825D01*
G01X1351268Y526539D02*
Y507839D01*
G01X1351209Y553151D02*
Y547622D01*
G01X1351189Y509984D02*
Y503902D01*
G01Y530476D02*
Y524394D01*
G01X1350997Y526539D02*
Y525555D01*
G01X1350992Y526539D02*
Y525555D01*
G01X1350987Y508823D02*
Y507839D01*
G01X1350953Y510516D02*
Y506343D01*
G01Y528035D02*
Y523862D01*
G01X1349850D02*
Y528035D01*
G01Y506343D02*
Y510516D01*
G01X1349816Y508823D02*
Y507839D01*
G01X1349811Y508823D02*
Y507839D01*
G01Y526539D02*
Y525555D01*
G01X1349732Y547622D02*
Y559433D01*
G01X1349614Y509984D02*
Y503902D01*
G01Y530476D02*
Y524394D01*
G01X1349535Y507839D02*
Y526539D01*
G01X1349457Y508825D02*
Y507840D01*
G01Y526538D02*
Y525553D01*
G01X1349260Y525555D02*
Y530396D01*
G01Y503982D02*
Y508823D01*
G01X1349181Y524760D02*
Y525751D01*
G01Y508627D02*
Y509618D01*
G01X1349102Y504965D02*
Y503902D01*
G01Y530476D02*
Y529413D01*
G01X1348827Y504886D02*
Y503902D01*
G01Y530476D02*
Y529492D01*
G01X1348039D02*
Y530476D01*
G01Y504886D02*
Y503902D01*
G01X1347764Y504965D02*
Y503902D01*
G01Y530476D02*
Y529413D01*
G01X1347685Y509618D02*
Y508627D01*
G01Y525751D02*
Y524760D01*
G01X1347606Y525555D02*
Y530396D01*
G01Y503982D02*
Y508823D01*
G01X1347409Y525553D02*
Y526538D01*
G01Y507840D02*
Y508825D01*
G01X1347331Y526539D02*
Y507839D01*
G01X1347252Y509984D02*
Y503902D01*
G01Y530476D02*
Y524394D01*
G01X1347055Y508823D02*
Y507839D01*
G01Y526539D02*
Y525555D01*
G01X1347050Y526539D02*
Y525555D01*
G01X1347016Y510516D02*
Y506343D01*
G01Y528035D02*
Y523862D01*
G01X1345913D02*
Y528035D01*
G01Y506343D02*
Y510516D01*
G01X1345879Y526539D02*
Y525555D01*
G01X1345874Y508823D02*
Y507839D01*
G01X1345869Y508823D02*
Y507839D01*
G01X1345677Y509984D02*
Y503902D01*
G01Y530476D02*
Y524394D01*
G01X1345598Y507839D02*
Y526539D01*
G01X1345524Y526538D02*
Y525553D01*
G01X1345515Y508825D02*
Y507840D01*
G01X1345323Y521698D02*
Y526539D01*
G01Y507839D02*
Y512680D01*
G01X1345249Y524760D02*
Y525751D01*
G01X1345239Y508627D02*
Y509618D01*
G01X1345165Y512760D02*
Y511696D01*
G01Y522681D02*
Y521618D01*
G01X1344890D02*
Y522602D01*
G01Y512760D02*
Y511776D01*
G01X1344102Y521618D02*
Y522602D01*
G01Y511776D02*
Y512760D01*
G01X1343827D02*
Y511696D01*
G01Y522682D02*
Y521618D01*
G01X1343753Y525751D02*
Y524760D01*
G01X1343743Y509618D02*
Y508627D01*
G01X1343669Y521698D02*
Y526539D01*
G01Y507839D02*
Y512680D01*
G01X1343477Y525553D02*
Y526538D01*
G01X1343468Y507840D02*
Y508825D01*
G01X1343394Y526539D02*
Y507839D01*
G01X1343315Y509984D02*
Y503902D01*
G01Y530476D02*
Y524394D01*
G01X1343123Y526539D02*
Y525555D01*
G01X1343118Y526539D02*
Y525555D01*
G01X1343113Y508823D02*
Y507839D01*
G01X1343079Y510516D02*
Y506343D01*
G01Y528035D02*
Y523862D01*
G01X1341976D02*
Y528035D01*
G01Y506343D02*
Y510516D01*
G01X1341942Y508823D02*
Y507839D01*
G01X1341937Y508823D02*
Y507839D01*
G01Y526539D02*
Y525555D01*
G01X1341740Y509984D02*
Y503902D01*
G01Y530476D02*
Y524394D01*
G01X1341661Y507839D02*
Y526539D01*
G01X1341583Y508825D02*
Y507840D01*
G01Y526538D02*
Y525553D01*
G01X1341386Y525555D02*
Y530396D01*
G01Y503982D02*
Y508823D01*
G01X1341307Y524760D02*
Y525751D01*
G01Y508627D02*
Y509618D01*
G01X1341228Y504965D02*
Y503902D01*
G01Y530476D02*
Y529413D01*
G01X1340953Y504886D02*
Y503902D01*
G01Y530476D02*
Y529492D01*
G01X1340165D02*
Y530476D01*
G01Y504886D02*
Y503902D01*
G01X1339890Y504965D02*
Y503902D01*
G01Y530476D02*
Y529413D01*
G01X1339811Y509618D02*
Y508627D01*
G01Y525751D02*
Y524760D01*
G01X1339732Y525555D02*
Y530396D01*
G01Y503982D02*
Y508823D01*
G01X1339535Y507840D02*
Y508825D01*
G01Y525553D02*
Y526538D01*
G01X1339457Y526539D02*
Y507839D01*
G01X1339378Y509984D02*
Y503902D01*
G01Y530476D02*
Y524394D01*
G01X1339181Y508823D02*
Y507839D01*
G01Y526539D02*
Y525555D01*
G01X1339176Y526539D02*
Y525555D01*
G01X1339142Y510516D02*
Y506343D01*
G01Y528035D02*
Y523862D01*
G01X1338039D02*
Y528035D01*
G01Y506343D02*
Y510516D01*
G01X1338005Y526539D02*
Y525555D01*
G01X1338000Y508823D02*
Y507839D01*
G01X1337995Y508823D02*
Y507839D01*
G01X1337803Y509984D02*
Y503902D01*
G01Y530476D02*
Y524394D01*
G01X1337724Y507839D02*
Y526539D01*
G01X1337650Y526538D02*
Y525553D01*
G01X1337641Y508825D02*
Y507840D01*
G01X1337449Y521698D02*
Y526539D01*
G01Y507839D02*
Y512680D01*
G01X1337375Y524760D02*
Y525751D01*
G01X1337365Y508627D02*
Y509618D01*
G01X1337291Y512760D02*
Y511696D01*
G01Y522681D02*
Y521618D01*
G01X1337016Y512760D02*
Y511776D01*
G01Y522602D02*
Y521618D01*
G01X1336228Y512760D02*
Y511776D01*
G01Y522602D02*
Y521618D01*
G01X1335953Y512760D02*
Y511696D01*
G01Y522682D02*
Y521618D01*
G01X1335879Y525751D02*
Y524760D01*
G01X1335869Y509618D02*
Y508627D01*
G01X1335795Y521698D02*
Y526539D01*
G01Y507839D02*
Y512680D01*
G01X1335603Y525553D02*
Y526538D01*
G01X1335594Y507840D02*
Y508825D01*
G01X1335520Y526539D02*
Y507839D01*
G01X1335441Y509984D02*
Y503902D01*
G01Y530476D02*
Y524394D01*
G01X1335249Y526539D02*
Y525555D01*
G01X1335244Y526539D02*
Y525555D01*
G01X1335239Y508823D02*
Y507839D01*
G01X1335205Y510516D02*
Y506343D01*
G01Y528035D02*
Y523862D01*
G01X1334102D02*
Y528035D01*
G01Y506343D02*
Y510516D01*
G01X1334068Y508823D02*
Y507839D01*
G01X1334063Y508823D02*
Y507839D01*
G01Y526539D02*
Y525555D01*
G01X1333866Y509984D02*
Y503902D01*
G01Y530476D02*
Y524394D01*
G01X1333787Y507839D02*
Y526539D01*
G01X1333709Y508825D02*
Y507840D01*
G01Y526538D02*
Y525553D01*
G01X1333512Y525555D02*
Y530396D01*
G01Y503982D02*
Y508823D01*
G01X1333433Y524760D02*
Y525751D01*
G01Y508627D02*
Y509618D01*
G01X1333354Y504965D02*
Y503902D01*
G01Y530476D02*
Y529413D01*
G01X1355824Y509010D02*
X1355811Y509984D01*
G01X1352857Y525368D02*
X1352871Y524394D01*
G01X1351883Y509010D02*
X1351870Y509984D01*
G01X1348916Y525368D02*
X1348929Y524394D01*
G01X1347950Y509010D02*
X1347937Y509984D01*
G01X1344983Y525368D02*
X1344997Y524394D01*
G01X1344009Y509010D02*
X1343996Y509984D01*
G01X1341042Y525368D02*
X1341055Y524394D01*
G01X1340076Y509010D02*
X1340063Y509984D01*
G01X1337109Y525368D02*
X1337123Y524394D01*
G01X1336135Y509010D02*
X1336122Y509984D01*
G01X1333168Y525368D02*
X1333181Y524394D01*
G01X1355438Y520239D02*
X1355301Y526147D01*
G01X1355297Y525261D02*
X1355433Y519353D01*
G01X1353376Y509117D02*
X1353240Y515025D01*
G01X1353235Y514139D02*
X1353371Y508231D01*
G01X1351505Y520239D02*
X1351369Y526147D01*
G01X1351364Y525261D02*
X1351501Y519353D01*
G01X1349443Y509117D02*
X1349307Y515025D01*
G01X1349302Y514139D02*
X1349439Y508231D01*
G01X1347564Y520239D02*
X1347427Y526147D01*
G01X1347423Y525261D02*
X1347559Y519353D01*
G01X1345502Y509117D02*
X1345366Y515025D01*
G01X1345361Y514139D02*
X1345497Y508231D01*
G01X1343631Y520239D02*
X1343495Y526147D01*
G01X1343490Y525261D02*
X1343627Y519353D01*
G01X1341569Y509117D02*
X1341433Y515025D01*
G01X1341428Y514139D02*
X1341565Y508231D01*
G01X1339690Y520239D02*
X1339553Y526147D01*
G01X1339549Y525261D02*
X1339685Y519353D01*
G01X1337628Y509117D02*
X1337492Y515025D01*
G01X1337487Y514139D02*
X1337623Y508231D01*
G01X1335757Y520239D02*
X1335621Y526147D01*
G01X1335616Y525261D02*
X1335753Y519353D01*
G01X1333695Y509117D02*
X1333559Y515025D01*
G01X1333554Y514139D02*
X1333691Y508231D01*
G01X1331816Y520239D02*
X1331679Y526147D01*
G01X1331675Y525261D02*
X1331811Y519353D01*
G01X1353223Y520013D02*
X1353172Y520999D01*
G01X1353170Y520037D02*
X1353220Y519051D01*
G01X1351570Y514341D02*
X1351520Y515327D01*
G01X1351517Y514365D02*
X1351568Y513379D01*
G01X1349281Y520013D02*
X1349231Y520999D01*
G01X1349228Y520037D02*
X1349279Y519051D01*
G01X1347638Y514341D02*
X1347587Y515327D01*
G01X1347585Y514365D02*
X1347635Y513379D01*
G01X1345349Y520013D02*
X1345298Y520999D01*
G01X1345296Y520037D02*
X1345346Y519051D01*
G01X1343696Y514341D02*
X1343646Y515327D01*
G01X1343643Y514365D02*
X1343694Y513379D01*
G01X1341407Y520013D02*
X1341357Y520999D01*
G01X1341354Y520037D02*
X1341405Y519051D01*
G01X1339764Y514341D02*
X1339713Y515327D01*
G01X1339711Y514365D02*
X1339761Y513379D01*
G01X1337475Y520013D02*
X1337424Y520999D01*
G01X1337422Y520037D02*
X1337472Y519051D01*
G01X1335822Y514341D02*
X1335772Y515327D01*
G01X1335769Y514365D02*
X1335820Y513379D01*
G01X1333533Y520013D02*
X1333483Y520999D01*
G01X1333480Y520037D02*
X1333531Y519051D01*
G01X1331890Y514341D02*
X1331839Y515327D01*
G01X1331837Y514365D02*
X1331887Y513379D01*
G01X1320350Y524441D02*
X1320360Y524394D01*
G01X1321398Y509937D02*
X1321388Y509984D01*
G01X1384607Y525738D02*
X1384353Y525368D01*
G01X1371319Y508640D02*
X1371572Y509010D01*
G01X1371527Y509937D02*
X1371307Y509618D01*
G01X1380457Y524441D02*
X1380677Y524760D01*
G01X1380666Y525738D02*
X1380412Y525368D01*
G01X1367377Y508640D02*
X1367631Y509010D01*
G01X1367364Y509615D02*
X1367585Y509937D01*
G01X1376746Y524763D02*
X1376525Y524441D01*
G01X1376733Y525738D02*
X1376479Y525368D01*
G01X1363445Y508640D02*
X1363698Y509010D01*
G01X1363431Y509615D02*
X1363653Y509937D01*
G01X1372583Y524441D02*
X1372803Y524760D01*
G01X1372792Y525738D02*
X1372538Y525368D01*
G01X1359503Y508640D02*
X1359757Y509010D01*
G01X1359490Y509615D02*
X1359711Y509937D01*
G01X1368872Y524763D02*
X1368651Y524441D01*
G01X1368859Y525738D02*
X1368605Y525368D01*
G01X1355571Y508640D02*
X1355824Y509010D01*
G01X1355557Y509615D02*
X1355779Y509937D01*
G01X1364931Y524763D02*
X1364709Y524441D01*
G01X1364918Y525738D02*
X1364664Y525368D01*
G01X1351629Y508640D02*
X1351883Y509010D01*
G01X1351616Y509615D02*
X1351837Y509937D01*
G01X1360998Y524763D02*
X1360777Y524441D01*
G01X1360985Y525738D02*
X1360731Y525368D01*
G01X1347697Y508640D02*
X1347950Y509010D01*
G01X1347683Y509615D02*
X1347905Y509937D01*
G01X1357057Y524763D02*
X1356835Y524441D01*
G01X1357044Y525738D02*
X1356790Y525368D01*
G01X1343755Y508640D02*
X1344009Y509010D01*
G01X1379998Y549632D02*
X1380982Y551140D01*
G01X1343973Y509984D02*
X1343963Y509937D01*
G01X1345019Y524394D02*
X1345029Y524441D01*
G01X1340040Y509984D02*
X1340031Y509937D01*
G01X1341078Y524394D02*
X1341087Y524441D01*
G01X1336099Y509984D02*
X1336089Y509937D01*
G01X1337145Y524394D02*
X1337155Y524441D01*
G01X1332166Y509984D02*
X1332157Y509937D01*
G01X1333204Y524394D02*
X1333213Y524441D01*
G01X1328225Y509984D02*
X1328215Y509937D01*
G01X1329271Y524394D02*
X1329281Y524441D01*
G01X1324292Y509984D02*
X1324283Y509937D01*
G01X1325330Y524394D02*
X1325339Y524441D01*
G01X1320351Y509984D02*
X1320341Y509937D01*
G01X1335781Y519051D02*
X1335831Y520037D01*
G01X1335829Y520999D02*
X1335779Y520013D01*
G01X1333483Y513379D02*
X1333533Y514365D01*
G01X1333531Y515327D02*
X1333480Y514341D01*
G01X1331839Y519051D02*
X1331890Y520037D01*
G01X1331887Y520999D02*
X1331837Y520013D01*
G01X1329541Y513379D02*
X1329591Y514365D01*
G01X1329589Y515327D02*
X1329539Y514341D01*
G01X1327907Y519051D02*
X1327957Y520037D01*
G01X1327955Y520999D02*
X1327905Y520013D01*
G01X1325609Y513379D02*
X1325659Y514365D01*
G01X1325657Y515327D02*
X1325606Y514341D01*
G01X1323965Y519051D02*
X1324016Y520037D01*
G01X1324013Y520999D02*
X1323963Y520013D01*
G01X1321667Y513379D02*
X1321717Y514365D01*
G01X1321715Y515327D02*
X1321665Y514341D01*
G01X1333559Y519353D02*
X1333695Y525261D01*
G01X1333691Y526147D02*
X1333554Y520239D01*
G01X1331679Y508231D02*
X1331816Y514139D01*
G01X1331811Y515025D02*
X1331675Y509117D01*
G01X1329627Y519353D02*
X1329763Y525261D01*
G01X1329758Y526147D02*
X1329622Y520239D01*
G01X1327738Y508231D02*
X1327874Y514139D01*
G01X1327869Y515025D02*
X1327733Y509117D01*
G01X1325685Y519353D02*
X1325821Y525261D01*
G01X1325817Y526147D02*
X1325680Y520239D01*
G01X1323805Y508231D02*
X1323942Y514139D01*
G01X1323937Y515025D02*
X1323801Y509117D01*
G01X1321753Y519353D02*
X1321889Y525261D01*
G01X1321884Y526147D02*
X1321748Y520239D01*
G01X1333181Y509984D02*
X1333168Y509010D01*
G01X1332189Y524394D02*
X1332202Y525368D01*
G01X1329239Y509984D02*
X1329226Y509010D01*
G01X1328257Y524394D02*
X1328270Y525368D01*
G01X1325307Y509984D02*
X1325294Y509010D01*
G01X1324315Y524394D02*
X1324328Y525368D01*
G01X1321365Y509984D02*
X1321352Y509010D01*
G01X1320383Y524394D02*
X1320396Y525368D01*
G01X1333079Y504886D02*
Y503902D01*
G01Y530476D02*
Y529492D01*
G01X1332291D02*
Y530476D01*
G01Y504886D02*
Y503902D01*
G01X1332016Y504965D02*
Y503902D01*
G01Y530476D02*
Y529413D01*
G01X1331937Y509618D02*
Y508627D01*
G01Y525751D02*
Y524760D01*
G01X1331858Y525555D02*
Y530396D01*
G01Y503982D02*
Y508823D01*
G01X1331661Y507840D02*
Y508825D01*
G01Y525553D02*
Y526538D01*
G01X1331583Y526539D02*
Y507839D01*
G01X1331504Y509984D02*
Y503902D01*
G01Y530476D02*
Y524394D01*
G01X1331307Y508823D02*
Y507839D01*
G01Y526539D02*
Y525555D01*
G01X1331302Y526539D02*
Y525555D01*
G01X1331268Y510516D02*
Y506343D01*
G01Y528035D02*
Y523862D01*
G01X1330165D02*
Y528035D01*
G01Y506343D02*
Y510516D01*
G01X1330131Y526539D02*
Y525555D01*
G01X1330126Y508823D02*
Y507839D01*
G01X1330121Y508823D02*
Y507839D01*
G01X1329929Y509984D02*
Y503902D01*
G01Y530476D02*
Y524394D01*
G01X1329850Y507839D02*
Y526539D01*
G01X1329776Y526538D02*
Y525553D01*
G01X1329767Y508825D02*
Y507840D01*
G01X1329575Y521698D02*
Y526539D01*
G01Y507839D02*
Y512680D01*
G01X1329501Y524760D02*
Y525751D01*
G01X1329491Y508627D02*
Y509618D01*
G01X1329417Y512760D02*
Y511696D01*
G01Y522681D02*
Y521618D01*
G01X1329142Y512760D02*
Y511776D01*
G01Y522602D02*
Y521618D01*
G01X1328354Y512760D02*
Y511776D01*
G01Y522602D02*
Y521618D01*
G01X1328079Y512760D02*
Y511696D01*
G01Y522682D02*
Y521618D01*
G01X1328005Y525751D02*
Y524760D01*
G01X1327995Y509618D02*
Y508627D01*
G01X1327921Y521698D02*
Y526539D01*
G01Y507839D02*
Y512680D01*
G01X1327729Y525553D02*
Y526538D01*
G01X1327720Y507840D02*
Y508825D01*
G01X1327646Y526539D02*
Y507839D01*
G01X1327567Y509984D02*
Y503902D01*
G01Y530476D02*
Y524394D01*
G01X1327375Y526539D02*
Y525555D01*
G01X1327370Y526539D02*
Y525555D01*
G01X1327365Y508823D02*
Y507839D01*
G01X1327331Y510516D02*
Y506343D01*
G01Y528035D02*
Y523862D01*
G01X1326228D02*
Y528035D01*
G01Y506343D02*
Y510516D01*
G01X1326194Y508823D02*
Y507839D01*
G01X1326189Y508823D02*
Y507839D01*
G01Y526539D02*
Y525555D01*
G01X1325992Y509984D02*
Y503902D01*
G01Y530476D02*
Y524394D01*
G01X1325913Y507839D02*
Y526539D01*
G01X1325835Y508825D02*
Y507840D01*
G01Y526538D02*
Y525553D01*
G01X1325638Y525555D02*
Y530396D01*
G01Y503982D02*
Y508823D01*
G01X1325559Y524760D02*
Y525751D01*
G01Y508627D02*
Y509618D01*
G01X1325480Y504965D02*
Y503902D01*
G01Y530476D02*
Y529413D01*
G01X1325205Y504886D02*
Y503902D01*
G01Y530476D02*
Y529492D01*
G01X1324417D02*
Y530476D01*
G01Y504886D02*
Y503902D01*
G01X1324142Y504965D02*
Y503902D01*
G01Y530476D02*
Y529413D01*
G01X1324063Y509618D02*
Y508627D01*
G01Y525751D02*
Y524760D01*
G01X1323984Y525555D02*
Y530396D01*
G01Y503982D02*
Y508823D01*
G01X1323787Y507840D02*
Y508825D01*
G01Y525553D02*
Y526538D01*
G01X1323709Y526539D02*
Y507839D01*
G01X1323630Y509984D02*
Y503902D01*
G01Y530476D02*
Y524394D01*
G01X1323433Y508823D02*
Y507839D01*
G01Y526539D02*
Y525555D01*
G01X1323428Y526539D02*
Y525555D01*
G01X1323394Y510516D02*
Y506343D01*
G01Y528035D02*
Y523862D01*
G01X1322291D02*
Y528035D01*
G01Y506343D02*
Y510516D01*
G01X1322257Y526539D02*
Y525555D01*
G01X1322252Y508823D02*
Y507839D01*
G01X1322247Y508823D02*
Y507839D01*
G01X1322055Y509984D02*
Y503902D01*
G01Y530476D02*
Y524394D01*
G01X1321976Y507839D02*
Y526539D01*
G01X1321902Y526538D02*
Y525553D01*
G01X1321893Y508825D02*
Y507840D01*
G01X1321701Y521698D02*
Y526539D01*
G01Y507839D02*
Y512680D01*
G01X1321627Y524760D02*
Y525751D01*
G01X1321617Y508627D02*
Y509618D01*
G01X1321543Y512760D02*
Y511696D01*
G01Y522681D02*
Y521618D01*
G01X1321268D02*
Y522602D01*
G01Y512760D02*
Y511776D01*
G01X1320480Y521618D02*
Y522602D01*
G01Y511776D02*
Y512760D01*
G01X1332202Y509010D02*
X1332189Y509984D01*
G01X1329235Y525368D02*
X1329249Y524394D01*
G01X1328261Y509010D02*
X1328248Y509984D01*
G01X1325294Y525368D02*
X1325307Y524394D01*
G01X1324328Y509010D02*
X1324315Y509984D01*
G01X1321361Y525368D02*
X1321374Y524394D01*
G01X1320387Y509010D02*
X1320374Y509984D01*
G01X1329754Y509117D02*
X1329618Y515025D01*
G01X1329613Y514139D02*
X1329749Y508231D01*
G01X1327883Y520239D02*
X1327747Y526147D01*
G01X1327742Y525261D02*
X1327879Y519353D01*
G01X1325821Y509117D02*
X1325685Y515025D01*
G01X1325680Y514139D02*
X1325817Y508231D01*
G01X1323942Y520239D02*
X1323805Y526147D01*
G01X1323801Y525261D02*
X1323937Y519353D01*
G01X1321880Y509117D02*
X1321744Y515025D01*
G01X1321739Y514139D02*
X1321875Y508231D01*
G01X1329601Y520013D02*
X1329550Y520999D01*
G01X1329548Y520037D02*
X1329598Y519051D01*
G01X1327948Y514341D02*
X1327898Y515327D01*
G01X1327895Y514365D02*
X1327946Y513379D01*
G01X1325659Y520013D02*
X1325609Y520999D01*
G01X1325606Y520037D02*
X1325657Y519051D01*
G01X1324016Y514341D02*
X1323965Y515327D01*
G01X1323963Y514365D02*
X1324013Y513379D01*
G01X1321727Y520013D02*
X1321676Y520999D01*
G01X1321674Y520037D02*
X1321724Y519051D01*
G01X1380736Y548627D02*
X1381474Y549381D01*
G01X1343742Y509615D02*
X1343963Y509937D01*
G01X1353124Y524763D02*
X1352903Y524441D01*
G01X1353111Y525738D02*
X1352857Y525368D01*
G01X1339823Y508640D02*
X1340076Y509010D01*
G01X1339809Y509615D02*
X1340031Y509937D01*
G01X1349183Y524763D02*
X1348961Y524441D01*
G01X1349170Y525738D02*
X1348916Y525368D01*
G01X1335881Y508640D02*
X1336135Y509010D01*
G01X1335868Y509615D02*
X1336089Y509937D01*
G01X1345250Y524763D02*
X1345029Y524441D01*
G01X1345237Y525738D02*
X1344983Y525368D01*
G01X1331949Y508640D02*
X1332202Y509010D01*
G01X1331935Y509615D02*
X1332157Y509937D01*
G01X1341309Y524763D02*
X1341087Y524441D01*
G01X1341296Y525738D02*
X1341042Y525368D01*
G01X1328007Y508640D02*
X1328261Y509010D01*
G01X1327994Y509615D02*
X1328215Y509937D01*
G01X1337376Y524763D02*
X1337155Y524441D01*
G01X1337363Y525738D02*
X1337109Y525368D01*
G01X1324075Y508640D02*
X1324328Y509010D01*
G01X1324061Y509615D02*
X1324283Y509937D01*
G01X1333435Y524763D02*
X1333213Y524441D01*
G01X1333422Y525738D02*
X1333168Y525368D01*
G01X1329502Y524763D02*
X1329281Y524441D01*
G01X1329489Y525738D02*
X1329235Y525368D01*
G01X1325561Y524763D02*
X1325339Y524441D01*
G01X1366711Y551894D02*
X1366218Y551140D01*
G01X1321397Y524394D02*
X1321407Y524441D01*
G01X1379506Y547873D02*
X1380736Y548627D01*
G01X1379260Y549130D02*
X1379998Y549632D01*
G01X1325548Y525738D02*
X1325294Y525368D01*
G01X1321628Y524763D02*
X1321407Y524441D01*
G01X1321615Y525738D02*
X1321361Y525368D01*
G01X1382213Y555915D02*
X1381967Y556669D01*
G01D02*
X1381474Y557674D01*
G01X1380982Y555915D02*
X1379998Y557423D01*
G01X1366218Y556166D02*
X1366711Y555412D01*
G01X1381474Y557674D02*
X1380736Y558428D01*
G01X1379998Y557423D02*
X1379260Y557925D01*
G01X1380736Y558428D02*
X1379506Y559182D01*
G01X1387872Y554407D02*
X1387380Y554658D01*
G01X1363266Y553653D02*
X1366711Y551894D01*
G01X1379260Y557925D02*
X1378030Y558177D01*
G01X1379506Y559182D02*
X1378030Y559433D01*
G01X1372055Y577012D02*
X1391740D01*
G01X1348433D02*
X1368118D01*
G01X1324811D02*
X1344496D01*
G01X1381228Y554407D02*
X1380982Y555915D01*
G01X1382459Y554658D02*
X1382213Y555915D01*
G01X1370156Y559433D02*
X1371632D01*
G01X1358098D02*
X1359575D01*
G01X1349732D02*
X1351209D01*
G01X1386888Y555664D02*
X1387872D01*
G01X1384427D02*
X1385657D01*
G01X1351209Y554658D02*
X1358098D01*
G01X1387380D02*
X1386888D01*
G01X1358098Y553151D02*
X1351209D01*
G01X1378030Y559433D02*
X1376553Y559182D01*
G01X1378030Y558177D02*
X1376799Y557925D01*
G01X1385657Y555664D02*
Y554910D01*
G01X1382459Y552397D02*
Y554658D01*
G01X1375077Y555915D02*
X1374831Y554407D01*
G01X1381228Y552648D02*
Y554407D01*
G01X1375205Y582524D02*
Y577012D01*
G01X1374831Y554407D02*
Y552648D01*
G01X1373600Y554658D02*
Y552397D01*
G01X1372055Y582524D02*
Y577012D01*
G01X1368679Y555664D02*
Y557674D01*
G01X1368118Y582524D02*
Y577012D01*
G01X1364968Y582524D02*
Y577012D01*
G01X1358098Y554658D02*
Y559433D01*
G01X1374093Y556669D02*
X1373846Y555915D01*
G01D02*
X1373600Y554658D01*
G01X1351583Y582524D02*
Y577012D01*
G01X1351209Y559433D02*
Y554658D01*
G01X1348433Y582524D02*
Y577012D01*
G01X1344496Y582524D02*
Y577012D01*
G01X1341346Y582524D02*
Y577012D01*
G01X1376061Y557423D02*
X1375077Y555915D01*
G01X1374585Y557674D02*
X1374093Y556669D01*
G01X1327961Y582524D02*
Y577012D01*
G01X1324811Y582524D02*
Y577012D01*
G01X1320874Y582524D02*
Y577012D01*
G01X1386150Y554407D02*
X1385657Y553905D01*
G01Y554910D02*
X1386150Y555412D01*
G01X1375323Y558428D02*
X1374585Y557674D01*
G01X1370156Y557423D02*
X1368679Y555664D01*
G01Y557674D02*
X1370156Y559433D01*
G01X1376799Y557925D02*
X1376061Y557423D01*
G01X1386888Y554658D02*
X1386150Y554407D01*
G01Y555412D02*
X1386888Y555664D01*
G01X1366711Y555412D02*
X1363266Y553653D01*
G01X1361543D02*
X1366218Y556166D01*
G01X1376553Y559182D02*
X1375323Y558428D01*
G01X1309812Y605754D02*
X1309811Y605751D01*
G01X1309812Y605756D02*
Y605754D01*
G01X1309813Y605757D02*
X1309812Y605756D01*
G01X1317686Y605754D02*
X1317685Y605751D01*
G01X1317686Y605756D02*
Y605754D01*
G01X1317687Y605757D02*
X1317686Y605756D01*
G01X1308314Y588624D02*
X1308315Y588627D01*
G01X1308314Y588622D02*
Y588624D01*
G01X1308313Y588621D02*
X1308314Y588622D01*
G01X1316188Y588624D02*
X1316189Y588627D01*
G01X1316188Y588622D02*
Y588624D01*
G01X1316187Y588621D02*
X1316188Y588622D01*
G01X1317686Y604768D02*
X1317685Y604763D01*
G01X1317686Y604771D02*
Y604768D01*
G01X1317687Y604772D02*
X1317686Y604771D01*
G01X1316188Y589610D02*
X1316189Y589615D01*
G01X1316188Y589607D02*
Y589610D01*
G01X1316187Y589606D02*
X1316188Y589607D01*
G01X1308305Y588770D02*
X1308313Y588621D01*
G01X1308298Y589184D02*
X1308305Y588770D01*
G01X1308293Y589804D02*
X1308298Y589184D01*
G01X1308291Y590552D02*
X1308293Y589804D01*
G01X1308309Y604698D02*
X1308313Y604772D01*
G01X1308306Y604491D02*
X1308309Y604698D01*
G01X1308303Y604181D02*
X1308306Y604491D01*
G01X1308302Y603807D02*
X1308303Y604181D01*
G01X1308293Y604573D02*
X1308291Y603826D01*
G01X1308298Y605193D02*
X1308293Y604573D01*
G01X1308305Y605608D02*
X1308298Y605193D01*
G01X1308313Y605757D02*
X1308305Y605608D01*
G01X1309833Y589804D02*
X1309835Y590552D01*
G01X1309828Y589184D02*
X1309833Y589804D01*
G01X1309821Y588770D02*
X1309828Y589184D01*
G01X1309813Y588621D02*
X1309821Y588770D01*
G01X1316167Y604573D02*
X1316165Y603826D01*
G01X1316172Y605193D02*
X1316167Y604573D01*
G01X1316179Y605608D02*
X1316172Y605193D01*
G01X1316187Y605757D02*
X1316179Y605608D01*
G01X1316177Y604178D02*
X1316176Y603807D01*
G01X1316180Y604491D02*
X1316177Y604178D01*
G01X1316183Y604699D02*
X1316180Y604491D01*
G01X1316187Y604772D02*
X1316183Y604699D01*
G01X1308314Y589607D02*
X1308313Y589606D01*
G01X1308314Y589610D02*
Y589607D01*
G01X1308315Y589617D02*
X1308314Y589610D01*
G01X1309812Y604771D02*
X1309813Y604772D01*
G01X1309812Y604768D02*
Y604771D01*
G01X1309811Y604761D02*
X1309812Y604768D01*
G01X1308048Y588965D02*
X1308053Y589117D01*
G01X1308044Y588867D02*
X1308048Y588965D01*
G01X1308039Y588825D02*
X1308044Y588867D01*
G01X1310078Y605413D02*
X1310073Y605261D01*
G01X1310082Y605511D02*
X1310078Y605413D01*
G01X1310087Y605553D02*
X1310082Y605511D01*
G01X1311981Y588965D02*
X1311985Y589117D01*
G01X1311976Y588867D02*
X1311981Y588965D01*
G01X1311972Y588825D02*
X1311976Y588867D01*
G01X1314019Y605413D02*
X1314015Y605261D01*
G01X1314024Y605511D02*
X1314019Y605413D01*
G01X1314028Y605553D02*
X1314024Y605511D01*
G01X1315922Y588965D02*
X1315927Y589117D01*
G01X1315918Y588867D02*
X1315922Y588965D01*
G01X1315913Y588825D02*
X1315918Y588867D01*
G01X1317952Y605413D02*
X1317947Y605261D01*
G01X1317956Y605511D02*
X1317952Y605413D01*
G01X1317961Y605553D02*
X1317956Y605511D01*
G01X1319855Y588965D02*
X1319859Y589117D01*
G01X1319850Y588867D02*
X1319855Y588965D01*
G01X1319846Y588825D02*
X1319850Y588867D01*
G01X1310074Y606353D02*
X1310069Y606147D01*
G01X1310080Y606485D02*
X1310074Y606353D01*
G01X1310087Y606538D02*
X1310080Y606485D01*
G01X1308052Y588025D02*
X1308057Y588231D01*
G01X1308046Y587893D02*
X1308052Y588025D01*
G01X1308039Y587840D02*
X1308046Y587893D01*
G01X1314016Y606353D02*
X1314010Y606147D01*
G01X1314022Y606485D02*
X1314016Y606353D01*
G01X1314028Y606538D02*
X1314022Y606485D01*
G01X1311984Y588025D02*
X1311990Y588231D01*
G01X1311978Y587893D02*
X1311984Y588025D01*
G01X1311972Y587840D02*
X1311978Y587893D01*
G01X1317948Y606353D02*
X1317943Y606147D01*
G01X1317954Y606485D02*
X1317948Y606353D01*
G01X1317961Y606538D02*
X1317954Y606485D01*
G01X1315926Y588025D02*
X1315931Y588231D01*
G01X1315920Y587893D02*
X1315926Y588025D01*
G01X1315913Y587840D02*
X1315920Y587893D01*
G01X1319858Y588025D02*
X1319864Y588231D01*
G01X1319852Y587893D02*
X1319858Y588025D01*
G01X1319846Y587840D02*
X1319852Y587893D01*
G01X1312245Y604209D02*
X1312244Y603807D01*
G01X1312248Y604537D02*
X1312245Y604209D01*
G01X1312252Y604733D02*
X1312248Y604537D01*
G01X1312256Y604763D02*
X1312252Y604733D01*
G01X1313755Y590169D02*
X1313756Y590571D01*
G01X1313752Y589841D02*
X1313755Y590169D01*
G01X1313748Y589645D02*
X1313752Y589841D01*
G01X1313744Y589615D02*
X1313748Y589645D01*
G01X1320119Y604209D02*
X1320118Y603807D01*
G01X1320122Y604537D02*
X1320119Y604209D01*
G01X1320126Y604733D02*
X1320122Y604537D01*
G01X1320130Y604763D02*
X1320126Y604733D01*
G01X1316188Y604771D02*
X1316187Y604772D01*
G01X1316188Y604768D02*
Y604771D01*
G01X1316189Y604763D02*
X1316188Y604768D01*
G01X1317686Y589607D02*
X1317687Y589606D01*
G01X1317686Y589610D02*
Y589607D01*
G01X1317685Y589615D02*
X1317686Y589610D01*
G01X1308303Y590197D02*
X1308302Y590571D01*
G01X1308306Y589887D02*
X1308303Y590197D01*
G01X1308309Y589680D02*
X1308306Y589887D01*
G01X1308313Y589606D02*
X1308309Y589680D01*
G01X1309823Y604181D02*
X1309824Y603807D01*
G01X1309820Y604491D02*
X1309823Y604181D01*
G01X1309817Y604698D02*
X1309820Y604491D01*
G01X1309813Y604772D02*
X1309817Y604698D01*
G01X1308046Y606485D02*
X1308039Y606538D01*
G01X1308052Y606353D02*
X1308046Y606485D01*
G01X1308057Y606147D02*
X1308052Y606353D01*
G01X1310080Y587893D02*
X1310087Y587840D01*
G01X1310074Y588025D02*
X1310080Y587893D01*
G01X1310069Y588231D02*
X1310074Y588025D01*
G01X1311987Y606485D02*
X1311981Y606538D01*
G01X1311993Y606353D02*
X1311987Y606485D01*
G01X1311999Y606147D02*
X1311993Y606353D01*
G01X1314013Y587893D02*
X1314019Y587840D01*
G01X1314007Y588025D02*
X1314013Y587893D01*
G01X1314001Y588231D02*
X1314007Y588025D01*
G01X1315920Y606485D02*
X1315913Y606538D01*
G01X1315926Y606353D02*
X1315920Y606485D01*
G01X1315931Y606147D02*
X1315926Y606353D01*
G01X1317954Y587893D02*
X1317961Y587840D01*
G01X1317948Y588025D02*
X1317954Y587893D01*
G01X1317943Y588231D02*
X1317948Y588025D01*
G01X1319861Y606485D02*
X1319855Y606538D01*
G01X1319867Y606353D02*
X1319861Y606485D01*
G01X1319873Y606147D02*
X1319867Y606353D01*
G01X1308044Y605511D02*
X1308039Y605553D01*
G01X1308048Y605413D02*
X1308044Y605511D01*
G01X1308053Y605261D02*
X1308048Y605413D01*
G01X1310082Y588867D02*
X1310087Y588825D01*
G01X1310078Y588965D02*
X1310082Y588867D01*
G01X1310073Y589117D02*
X1310078Y588965D01*
G01X1311986Y605511D02*
X1311981Y605553D01*
G01X1311990Y605413D02*
X1311986Y605511D01*
G01X1311994Y605261D02*
X1311990Y605413D01*
G01X1314014Y588867D02*
X1314019Y588825D01*
G01X1314010Y588965D02*
X1314014Y588867D01*
G01X1314006Y589117D02*
X1314010Y588965D01*
G01X1315918Y605511D02*
X1315913Y605553D01*
G01X1315922Y605413D02*
X1315918Y605511D01*
G01X1315927Y605261D02*
X1315922Y605413D01*
G01X1317956Y588867D02*
X1317961Y588825D01*
G01X1317952Y588965D02*
X1317956Y588867D01*
G01X1317947Y589117D02*
X1317952Y588965D01*
G01X1319860Y605511D02*
X1319855Y605553D01*
G01X1319864Y605413D02*
X1319860Y605511D01*
G01X1319868Y605261D02*
X1319864Y605413D01*
G01X1312243Y589645D02*
X1312247Y589615D01*
G01X1312238Y589841D02*
X1312243Y589645D01*
G01X1312236Y590169D02*
X1312238Y589841D01*
G01X1312235Y590571D02*
X1312236Y590169D01*
G01X1313757Y604733D02*
X1313753Y604763D01*
G01X1313762Y604537D02*
X1313757Y604733D01*
G01X1313764Y604209D02*
X1313762Y604537D01*
G01X1313765Y603807D02*
X1313764Y604209D01*
G01X1320117Y589645D02*
X1320121Y589615D01*
G01X1320112Y589841D02*
X1320117Y589645D01*
G01X1320110Y590169D02*
X1320112Y589841D01*
G01X1320109Y590571D02*
X1320110Y590169D01*
G01X1309821Y605608D02*
X1309813Y605757D01*
G01X1309828Y605193D02*
X1309821Y605608D01*
G01X1309833Y604573D02*
X1309828Y605193D01*
G01X1309835Y603826D02*
X1309833Y604573D01*
G01X1316179Y588770D02*
X1316187Y588621D01*
G01X1316172Y589184D02*
X1316179Y588770D01*
G01X1316167Y589804D02*
X1316172Y589184D01*
G01X1316165Y590552D02*
X1316167Y589804D01*
G01X1316183Y589679D02*
X1316187Y589606D01*
G01X1316180Y589887D02*
X1316183Y589679D01*
G01X1316177Y590200D02*
X1316180Y589887D01*
G01X1316176Y590571D02*
X1316177Y590200D01*
G01X1317691Y604699D02*
X1317687Y604772D01*
G01X1317694Y604491D02*
X1317691Y604699D01*
G01X1317697Y604178D02*
X1317694Y604491D01*
G01X1317698Y603807D02*
X1317697Y604178D01*
G01X1317695Y605608D02*
X1317687Y605757D01*
G01X1317702Y605193D02*
X1317695Y605608D01*
G01X1317707Y604573D02*
X1317702Y605193D01*
G01X1317709Y603826D02*
X1317707Y604573D01*
G01X1309817Y589680D02*
X1309813Y589606D01*
G01X1309820Y589887D02*
X1309817Y589680D01*
G01X1309823Y590197D02*
X1309820Y589887D01*
G01X1309824Y590571D02*
X1309823Y590197D01*
G01X1317707Y589804D02*
X1317709Y590552D01*
G01X1317702Y589184D02*
X1317707Y589804D01*
G01X1317695Y588770D02*
X1317702Y589184D01*
G01X1317687Y588621D02*
X1317695Y588770D01*
G01X1317697Y590200D02*
X1317698Y590571D01*
G01X1317694Y589887D02*
X1317697Y590200D01*
G01X1317691Y589679D02*
X1317694Y589887D01*
G01X1317687Y589606D02*
X1317691Y589679D01*
G01X1309812Y588622D02*
X1309813Y588621D01*
G01X1309812Y588624D02*
Y588622D01*
G01X1309811Y588627D02*
X1309812Y588624D01*
G01X1308314Y605756D02*
X1308313Y605757D01*
G01X1308314Y605754D02*
Y605756D01*
G01X1308315Y605751D02*
X1308314Y605754D01*
G01X1317686Y588622D02*
X1317687Y588621D01*
G01X1317686Y588624D02*
Y588622D01*
G01X1317685Y588627D02*
X1317686Y588624D01*
G01X1316188Y605756D02*
X1316187Y605757D01*
G01X1316188Y605754D02*
Y605756D01*
G01X1316189Y605751D02*
X1316188Y605754D01*
G01X1309812Y589610D02*
X1309811Y589617D01*
G01X1309812Y589607D02*
Y589610D01*
G01X1309813Y589606D02*
X1309812Y589607D01*
G01X1308314Y604768D02*
X1308315Y604761D01*
G01X1308314Y604771D02*
Y604768D01*
G01X1308313Y604772D02*
X1308314Y604771D01*
G01X1319816Y588823D02*
X1319801D01*
G01X1319831Y588824D02*
X1319816Y588823D01*
G01X1319846Y588825D02*
X1319831Y588824D01*
G01X1315883Y588823D02*
X1315868D01*
G01X1315898Y588824D02*
X1315883Y588823D01*
G01X1315913Y588825D02*
X1315898Y588824D01*
G01X1311942Y588823D02*
X1311927D01*
G01X1311957Y588824D02*
X1311942Y588823D01*
G01X1311972Y588825D02*
X1311957Y588824D01*
G01X1308009Y588823D02*
X1307994D01*
G01X1308024Y588824D02*
X1308009Y588823D01*
G01X1308039Y588825D02*
X1308024Y588824D01*
G01X1317991Y605555D02*
X1318006D01*
G01X1317976Y605554D02*
X1317991Y605555D01*
G01X1317961Y605553D02*
X1317976Y605554D01*
G01X1310117Y605555D02*
X1310132D01*
G01X1310102Y605554D02*
X1310117Y605555D01*
G01X1310087Y605553D02*
X1310102Y605554D01*
G01X1319816Y587839D02*
X1319801D01*
G01X1319831D02*
X1319816D01*
G01X1319846Y587840D02*
X1319831Y587839D01*
G01X1315883D02*
X1315868D01*
G01X1315898D02*
X1315883D01*
G01X1315913Y587840D02*
X1315898Y587839D01*
G01X1311942D02*
X1311927D01*
G01X1311957D02*
X1311942D01*
G01X1311972Y587840D02*
X1311957Y587839D01*
G01X1317991Y606539D02*
X1318006D01*
G01X1317976D02*
X1317991D01*
G01X1317961Y606538D02*
X1317976Y606539D01*
G01X1314058D02*
X1314073D01*
G01X1314043D02*
X1314058D01*
G01X1314028Y606538D02*
X1314043Y606539D01*
G01X1310102Y587839D02*
X1310087Y587840D01*
G01X1310117Y587839D02*
X1310102D01*
G01X1310132D02*
X1310117D01*
G01X1314034D02*
X1314019Y587840D01*
G01X1314049Y587839D02*
X1314034D01*
G01X1314064D02*
X1314049D01*
G01X1317976D02*
X1317961Y587840D01*
G01X1317991Y587839D02*
X1317976D01*
G01X1318006D02*
X1317991D01*
G01X1308024Y606539D02*
X1308039Y606538D01*
G01X1308009Y606539D02*
X1308024D01*
G01X1307994D02*
X1308009D01*
G01X1311966D02*
X1311981Y606538D01*
G01X1311951Y606539D02*
X1311966D01*
G01X1311936D02*
X1311951D01*
G01X1315898D02*
X1315913Y606538D01*
G01X1315883Y606539D02*
X1315898D01*
G01X1315868D02*
X1315883D01*
G01X1319840D02*
X1319855Y606538D01*
G01X1319825Y606539D02*
X1319840D01*
G01X1319810D02*
X1319825D01*
G01X1310102Y588824D02*
X1310087Y588825D01*
G01X1310117Y588823D02*
X1310102Y588824D01*
G01X1310132Y588823D02*
X1310117D01*
G01X1314034Y588824D02*
X1314019Y588825D01*
G01X1314049Y588823D02*
X1314034Y588824D01*
G01X1314064Y588823D02*
X1314049D01*
G01X1317976Y588824D02*
X1317961Y588825D01*
G01X1317991Y588823D02*
X1317976Y588824D01*
G01X1318006Y588823D02*
X1317991D01*
G01X1308024Y605554D02*
X1308039Y605553D01*
G01X1308009Y605555D02*
X1308024Y605554D01*
G01X1307994Y605555D02*
X1308009D01*
G01X1311966Y605554D02*
X1311981Y605553D01*
G01X1311951Y605555D02*
X1311966Y605554D01*
G01X1311936Y605555D02*
X1311951D01*
G01X1315898Y605554D02*
X1315913Y605553D01*
G01X1315883Y605555D02*
X1315898Y605554D01*
G01X1315868Y605555D02*
X1315883D01*
G01X1319840Y605554D02*
X1319855Y605553D01*
G01X1319825Y605555D02*
X1319840Y605554D01*
G01X1319810Y605555D02*
X1319825D01*
G01X1310244Y610476D02*
X1307882D01*
G01X1314181D02*
X1311819D01*
G01X1318118D02*
X1315756D01*
G01X1322055D02*
X1319693D01*
G01X1309732Y609492D02*
X1308394D01*
G01X1317606D02*
X1316268D01*
G01X1316110Y609394D02*
X1317764D01*
G01X1308236D02*
X1309890D01*
G01X1310244Y609295D02*
X1307882D01*
G01X1314181D02*
X1311819D01*
G01X1318118D02*
X1315756D01*
G01X1322055D02*
X1319693D01*
G01X1309890Y608902D02*
X1308236D01*
G01X1317764D02*
X1316110D01*
G01X1314417Y608035D02*
X1311583D01*
G01X1318354D02*
X1315520D01*
G01X1322291D02*
X1319457D01*
G01X1309890Y607130D02*
X1308236D01*
G01X1317764D02*
X1316110D01*
G01Y606638D02*
X1317764D01*
G01X1308236D02*
X1309890D01*
G01X1314417Y606539D02*
X1311583D01*
G01X1318354D02*
X1315520D01*
G01X1322291D02*
X1319457D01*
G01Y606382D02*
X1320047D01*
G01X1317764D02*
X1318354D01*
G01X1315520D02*
X1316110D01*
G01X1313827D02*
X1314417D01*
G01X1311583D02*
X1312173D01*
G01X1309890D02*
X1310480D01*
G01X1319873Y606147D02*
X1321884D01*
G01X1315931D02*
X1317943D01*
G01X1311999D02*
X1314010D01*
G01X1308057D02*
X1310069D01*
G01X1309813Y605757D02*
X1308313D01*
G01X1313754D02*
X1312255D01*
G01X1317687D02*
X1316187D01*
G01X1321628D02*
X1320129D01*
G01X1320142Y605738D02*
X1321615D01*
G01X1316201D02*
X1317674D01*
G01X1312268D02*
X1313741D01*
G01X1308326D02*
X1309799D01*
G01X1310480Y605713D02*
X1309890D01*
G01X1312173D02*
X1311583D01*
G01X1314417D02*
X1313827D01*
G01X1316110D02*
X1315520D01*
G01X1318354D02*
X1317764D01*
G01X1320047D02*
X1319457D01*
G01Y605555D02*
X1322291D01*
G01X1315520D02*
X1318354D01*
G01X1311583D02*
X1314417D01*
G01X1313827Y605457D02*
X1312173D01*
G01X1321701D02*
X1320047D01*
G01X1309546Y605368D02*
X1308580D01*
G01X1313487D02*
X1312522D01*
G01X1317420D02*
X1316454D01*
G01X1319457Y605358D02*
X1319772D01*
G01X1315520D02*
X1315835D01*
G01X1311583D02*
X1311898D01*
G01X1310480D02*
X1310165D01*
G01X1314417D02*
X1314102D01*
G01X1318354D02*
X1318039D01*
G01X1310073Y605261D02*
X1308053D01*
G01X1314015D02*
X1311994D01*
G01X1317947D02*
X1315927D01*
G01X1321889D02*
X1319868D01*
G01X1320047Y604965D02*
X1321701D01*
G01X1312173D02*
X1313827D01*
G01X1309813Y604772D02*
X1308313D01*
G01X1313754D02*
X1312255D01*
G01X1317687D02*
X1316187D01*
G01X1321628D02*
X1320129D01*
G01X1309811Y604763D02*
X1308315D01*
G01X1313753D02*
X1312256D01*
G01X1317685D02*
X1316189D01*
G01X1321627D02*
X1320130D01*
G01X1316409Y604441D02*
X1317465D01*
G01X1312476D02*
X1313533D01*
G01X1308535D02*
X1309591D01*
G01X1307882Y604394D02*
X1310244D01*
G01X1314181D02*
X1311819D01*
G01X1318118D02*
X1315756D01*
G01X1322055D02*
X1319693D01*
G01X1319457Y603862D02*
X1319772D01*
G01X1318039D02*
X1318354D01*
G01X1315520D02*
X1315835D01*
G01X1314102D02*
X1314417D01*
G01X1311583D02*
X1311898D01*
G01X1310165D02*
X1310480D01*
G01X1320107Y603826D02*
X1321650D01*
G01X1316165D02*
X1317709D01*
G01X1312233D02*
X1313776D01*
G01X1308291D02*
X1309835D01*
G01X1320118Y603807D02*
X1321639D01*
G01X1316176D02*
X1317698D01*
G01X1312244D02*
X1313765D01*
G01X1308302D02*
X1309824D01*
G01X1320047Y603193D02*
X1321701D01*
G01X1312173D02*
X1313827D01*
G01Y602701D02*
X1312173D01*
G01X1321701D02*
X1320047D01*
G01X1313669Y602602D02*
X1312331D01*
G01X1321543D02*
X1320205D01*
G01Y601618D02*
X1321543D01*
G01X1312331D02*
X1313669D01*
G01X1309861Y600999D02*
X1308265D01*
G01X1313802D02*
X1312207D01*
G01X1317735D02*
X1316139D01*
G01X1321676D02*
X1320081D01*
G01X1310165Y600890D02*
X1307961D01*
G01X1314102D02*
X1311898D01*
G01X1318039D02*
X1315835D01*
G01X1321976D02*
X1319772D01*
G01X1309932Y600239D02*
X1308194D01*
G01X1313874D02*
X1312135D01*
G01X1317806D02*
X1316068D01*
G01X1321748D02*
X1320009D01*
G01X1320083Y600037D02*
X1321674D01*
G01X1316142D02*
X1317732D01*
G01X1312209D02*
X1313800D01*
G01X1308268D02*
X1309858D01*
G01X1320031Y600013D02*
X1321727D01*
G01X1316089D02*
X1317785D01*
G01X1312157D02*
X1313853D01*
G01X1308215D02*
X1309911D01*
G01X1309918Y599945D02*
X1308208D01*
G01X1313860D02*
X1312150D01*
G01X1317792D02*
X1316082D01*
G01X1321734D02*
X1320024D01*
G01X1320004Y599353D02*
X1321753D01*
G01X1316063D02*
X1317811D01*
G01X1312130D02*
X1313879D01*
G01X1308189D02*
X1309937D01*
G01X1309909Y599051D02*
X1308217D01*
G01X1313850D02*
X1312159D01*
G01X1317783D02*
X1316091D01*
G01X1321724D02*
X1320033D01*
G01X1309918Y598961D02*
X1308208D01*
G01X1313860D02*
X1312150D01*
G01X1317792D02*
X1316082D01*
G01X1321734D02*
X1320024D01*
G01X1319772Y598635D02*
X1321976D01*
G01X1315835D02*
X1318039D01*
G01X1311898D02*
X1314102D01*
G01X1307961D02*
X1310165D01*
G01X1319772Y598468D02*
X1321976D01*
G01X1315835D02*
X1318039D01*
G01X1311898D02*
X1314102D01*
G01X1307961D02*
X1310165D01*
G01Y595910D02*
X1307961D01*
G01X1314102D02*
X1311898D01*
G01X1318039D02*
X1315835D01*
G01X1321976D02*
X1319772D01*
G01X1310165Y595743D02*
X1307961D01*
G01X1314102D02*
X1311898D01*
G01X1318039D02*
X1315835D01*
G01X1321976D02*
X1319772D01*
G01X1320014Y595417D02*
X1321724D01*
G01X1316082D02*
X1317792D01*
G01X1312140D02*
X1313850D01*
G01X1308208D02*
X1309918D01*
G01X1320024Y595327D02*
X1321715D01*
G01X1316091D02*
X1317783D01*
G01X1312150D02*
X1313841D01*
G01X1308217D02*
X1309909D01*
G01X1309937Y595025D02*
X1308189D01*
G01X1313870D02*
X1312121D01*
G01X1317811D02*
X1316063D01*
G01X1321744D02*
X1319995D01*
G01X1320014Y594433D02*
X1321724D01*
G01X1316082D02*
X1317792D01*
G01X1312140D02*
X1313850D01*
G01X1308208D02*
X1309918D01*
G01X1309911Y594365D02*
X1308215D01*
G01X1313843D02*
X1312147D01*
G01X1317785D02*
X1316089D01*
G01X1321717D02*
X1320021D01*
G01X1309858Y594341D02*
X1308268D01*
G01X1313791D02*
X1312200D01*
G01X1317732D02*
X1316142D01*
G01X1321665D02*
X1320074D01*
G01X1320000Y594139D02*
X1321739D01*
G01X1316068D02*
X1317806D01*
G01X1312126D02*
X1313865D01*
G01X1308194D02*
X1309932D01*
G01X1319772Y593488D02*
X1321976D01*
G01X1315835D02*
X1318039D01*
G01X1311898D02*
X1314102D01*
G01X1307961D02*
X1310165D01*
G01X1320072Y593379D02*
X1321667D01*
G01X1316139D02*
X1317735D01*
G01X1312198D02*
X1313793D01*
G01X1308265D02*
X1309861D01*
G01X1313669Y592760D02*
X1312331D01*
G01X1321543D02*
X1320205D01*
G01X1313669Y591776D02*
X1312331D01*
G01X1321543D02*
X1320205D01*
G01X1320047Y591677D02*
X1321701D01*
G01X1312173D02*
X1313827D01*
G01Y591185D02*
X1312173D01*
G01X1321701D02*
X1320047D01*
G01X1309824Y590571D02*
X1308302D01*
G01X1313756D02*
X1312235D01*
G01X1317698D02*
X1316176D01*
G01X1321630D02*
X1320109D01*
G01X1309835Y590552D02*
X1308291D01*
G01X1313767D02*
X1312224D01*
G01X1317709D02*
X1316165D01*
G01X1321641D02*
X1320098D01*
G01X1310480Y590516D02*
X1310165D01*
G01X1311898D02*
X1311583D01*
G01X1314417D02*
X1314102D01*
G01X1315835D02*
X1315520D01*
G01X1319772D02*
X1319457D01*
G01X1318354D02*
X1318039D01*
G01X1310244Y589984D02*
X1307882D01*
G01X1314181D02*
X1311819D01*
G01X1318118D02*
X1315756D01*
G01X1322055D02*
X1319693D01*
G01X1309591Y589937D02*
X1308535D01*
G01X1313524D02*
X1312467D01*
G01X1317465D02*
X1316409D01*
G01X1320121Y589615D02*
X1321618D01*
G01X1316189D02*
X1317685D01*
G01X1312247D02*
X1313744D01*
G01X1308315D02*
X1309811D01*
G01X1320120Y589606D02*
X1321619D01*
G01X1316187D02*
X1317687D01*
G01X1312246D02*
X1313745D01*
G01X1308313D02*
X1309813D01*
G01X1313827Y589413D02*
X1312173D01*
G01X1321701D02*
X1320047D01*
G01X1319859Y589117D02*
X1321880D01*
G01X1315927D02*
X1317947D01*
G01X1311985D02*
X1314006D01*
G01X1308053D02*
X1310073D01*
G01X1318039Y589020D02*
X1318354D01*
G01X1314102D02*
X1314417D01*
G01X1310480D02*
X1310165D01*
G01X1311898D02*
X1311583D01*
G01X1315835D02*
X1315520D01*
G01X1319772D02*
X1319457D01*
G01X1316454Y589010D02*
X1317420D01*
G01X1312513D02*
X1313478D01*
G01X1308580D02*
X1309546D01*
G01X1320047Y588921D02*
X1321701D01*
G01X1312173D02*
X1313827D01*
G01X1319457Y588823D02*
X1322291D01*
G01X1315520D02*
X1318354D01*
G01X1311583D02*
X1314417D01*
G01X1319457Y588665D02*
X1320047D01*
G01X1317764D02*
X1318354D01*
G01X1315520D02*
X1316110D01*
G01X1313827D02*
X1314417D01*
G01X1311583D02*
X1312173D01*
G01X1309890D02*
X1310480D01*
G01X1309799Y588640D02*
X1308326D01*
G01X1313732D02*
X1312259D01*
G01X1317674D02*
X1316201D01*
G01X1321606D02*
X1320133D01*
G01X1320120Y588621D02*
X1321619D01*
G01X1316187D02*
X1317687D01*
G01X1312246D02*
X1313745D01*
G01X1308313D02*
X1309813D01*
G01X1310069Y588231D02*
X1308057D01*
G01X1314001D02*
X1311990D01*
G01X1317943D02*
X1315931D01*
G01X1321875D02*
X1319864D01*
G01X1310480Y587996D02*
X1309890D01*
G01X1312173D02*
X1311583D01*
G01X1314417D02*
X1313827D01*
G01X1316110D02*
X1315520D01*
G01X1318354D02*
X1317764D01*
G01X1320047D02*
X1319457D01*
G01X1314417Y587839D02*
X1311583D01*
G01X1318354D02*
X1315520D01*
G01X1322291D02*
X1319457D01*
G01X1309890Y587740D02*
X1308236D01*
G01X1317764D02*
X1316110D01*
G01Y587248D02*
X1317764D01*
G01X1308236D02*
X1309890D01*
G01X1319457Y586343D02*
X1322291D01*
G01X1315520D02*
X1318354D01*
G01X1311583D02*
X1314417D01*
G01X1316110Y585476D02*
X1317764D01*
G01X1308236D02*
X1309890D01*
G01X1307882Y585083D02*
X1310244D01*
G01X1314181D02*
X1311819D01*
G01X1318118D02*
X1315756D01*
G01X1322055D02*
X1319693D01*
G01X1309890Y584984D02*
X1308236D01*
G01X1317764D02*
X1316110D01*
G01X1309732Y584886D02*
X1308394D01*
G01X1317606D02*
X1316268D01*
G01X1319693Y583902D02*
X1322055D01*
G01X1315756D02*
X1318118D01*
G01X1311819D02*
X1314181D01*
G01X1307882D02*
X1310244D01*
G01X1320142Y605738D02*
X1320396Y605368D01*
G01X1320350Y604441D02*
X1320129Y604763D01*
G01X1316201Y605738D02*
X1316454Y605368D01*
G01X1316409Y604441D02*
X1316187Y604763D01*
G01X1312268Y605738D02*
X1312522Y605368D01*
G01X1312476Y604441D02*
X1312255Y604763D01*
G01X1308580Y605368D02*
X1308326Y605738D01*
G01X1308315Y604760D02*
X1308535Y604441D01*
G01X1317465Y589937D02*
X1317687Y589615D01*
G01X1317674Y588640D02*
X1317420Y589010D01*
G01X1313524Y589937D02*
X1313745Y589615D01*
G01X1313732Y588640D02*
X1313478Y589010D01*
G01X1309811Y589618D02*
X1309591Y589937D01*
G01X1309546Y589010D02*
X1309799Y588640D01*
G01X1316409Y604441D02*
X1316418Y604394D01*
G01X1317465Y589937D02*
X1317456Y589984D01*
G01X1312476Y604441D02*
X1312486Y604394D01*
G01X1313524Y589937D02*
X1313514Y589984D01*
G01X1308544Y604394D02*
X1308535Y604441D01*
G01X1309582Y589984D02*
X1309591Y589937D01*
G01X1320033Y599051D02*
X1320083Y600037D01*
G01X1320081Y600999D02*
X1320031Y600013D01*
G01X1317735Y593379D02*
X1317785Y594365D01*
G01X1317783Y595327D02*
X1317732Y594341D01*
G01X1316091Y599051D02*
X1316142Y600037D01*
G01X1316139Y600999D02*
X1316089Y600013D01*
G01X1319864Y588231D02*
X1320000Y594139D01*
G01X1319995Y595025D02*
X1319859Y589117D01*
G01X1317811Y599353D02*
X1317947Y605261D01*
G01X1317943Y606147D02*
X1317806Y600239D01*
G01X1315931Y588231D02*
X1316068Y594139D01*
G01X1316063Y595025D02*
X1315927Y589117D01*
G01X1313879Y599353D02*
X1314015Y605261D01*
G01X1314010Y606147D02*
X1313874Y600239D01*
G01X1311990Y588231D02*
X1312126Y594139D01*
G01X1312121Y595025D02*
X1311985Y589117D01*
G01X1317433Y589984D02*
X1317420Y589010D01*
G01X1316441Y604394D02*
X1316454Y605368D01*
G01X1313491Y589984D02*
X1313478Y589010D01*
G01X1312509Y604394D02*
X1312522Y605368D01*
G01X1320205Y592760D02*
Y591696D01*
G01Y602682D02*
Y601618D01*
G01X1320131Y605751D02*
Y604760D01*
G01X1320121Y589618D02*
Y588627D01*
G01X1320047Y601698D02*
Y606539D01*
G01Y587839D02*
Y592680D01*
G01X1319855Y605553D02*
Y606538D01*
G01X1319846Y587840D02*
Y588825D01*
G01X1319772Y606539D02*
Y587839D01*
G01X1319693Y589984D02*
Y583902D01*
G01Y610476D02*
Y604394D01*
G01X1319501Y606539D02*
Y605555D01*
G01X1319496Y606539D02*
Y605555D01*
G01X1319491Y588823D02*
Y587839D01*
G01X1319457Y590516D02*
Y586343D01*
G01Y608035D02*
Y603862D01*
G01X1318354D02*
Y608035D01*
G01Y586343D02*
Y590516D01*
G01X1318320Y588823D02*
Y587839D01*
G01X1318315Y588823D02*
Y587839D01*
G01Y606539D02*
Y605555D01*
G01X1318118Y589984D02*
Y583902D01*
G01Y610476D02*
Y604394D01*
G01X1318039Y587839D02*
Y606539D01*
G01X1317961Y588825D02*
Y587840D01*
G01Y606538D02*
Y605553D01*
G01X1317764Y605555D02*
Y610396D01*
G01Y583982D02*
Y588823D01*
G01X1317685Y604760D02*
Y605751D01*
G01Y588627D02*
Y589618D01*
G01X1317606Y584965D02*
Y583902D01*
G01Y610476D02*
Y609413D01*
G01X1317331Y584886D02*
Y583902D01*
G01Y610476D02*
Y609492D01*
G01X1316543D02*
Y610476D01*
G01Y584886D02*
Y583902D01*
G01X1316268Y584965D02*
Y583902D01*
G01Y610476D02*
Y609413D01*
G01X1316189Y589618D02*
Y588627D01*
G01Y605751D02*
Y604760D01*
G01X1316110Y605555D02*
Y610396D01*
G01Y583982D02*
Y588823D01*
G01X1315913Y587840D02*
Y588825D01*
G01Y605553D02*
Y606538D01*
G01X1315835Y606539D02*
Y587839D01*
G01X1315756Y589984D02*
Y583902D01*
G01Y610476D02*
Y604394D01*
G01X1315559Y588823D02*
Y587839D01*
G01Y606539D02*
Y605555D01*
G01X1315554Y606539D02*
Y605555D01*
G01X1315520Y590516D02*
Y586343D01*
G01Y608035D02*
Y603862D01*
G01X1314417D02*
Y608035D01*
G01Y586343D02*
Y590516D01*
G01X1314383Y606539D02*
Y605555D01*
G01X1314378Y588823D02*
Y587839D01*
G01X1314373Y588823D02*
Y587839D01*
G01X1314181Y589984D02*
Y583902D01*
G01Y610476D02*
Y604394D01*
G01X1314102Y587839D02*
Y606539D01*
G01X1314028Y606538D02*
Y605553D01*
G01X1314019Y588825D02*
Y587840D01*
G01X1313827Y601698D02*
Y606539D01*
G01Y587839D02*
Y592680D01*
G01X1313753Y604760D02*
Y605751D01*
G01X1313743Y588627D02*
Y589618D01*
G01X1313669Y592760D02*
Y591696D01*
G01Y602681D02*
Y601618D01*
G01X1313394D02*
Y602602D01*
G01Y592760D02*
Y591776D01*
G01X1312606Y601618D02*
Y602602D01*
G01Y591776D02*
Y592760D01*
G01X1312331D02*
Y591696D01*
G01Y602682D02*
Y601618D01*
G01X1312257Y605751D02*
Y604760D01*
G01X1312247Y589618D02*
Y588627D01*
G01X1312173Y601698D02*
Y606539D01*
G01Y587839D02*
Y592680D01*
G01X1311981Y605553D02*
Y606538D01*
G01X1311972Y587840D02*
Y588825D01*
G01X1311898Y606539D02*
Y587839D01*
G01X1311819Y589984D02*
Y583902D01*
G01Y610476D02*
Y604394D01*
G01X1311627Y606539D02*
Y605555D01*
G01X1311622Y606539D02*
Y605555D01*
G01X1311617Y588823D02*
Y587839D01*
G01X1311583Y590516D02*
Y586343D01*
G01Y608035D02*
Y603862D01*
G01X1310480D02*
Y608035D01*
G01Y586343D02*
Y590516D01*
G01X1310446Y588823D02*
Y587839D01*
G01X1310441Y588823D02*
Y587839D01*
G01Y606539D02*
Y605555D01*
G01X1310244Y589984D02*
Y583902D01*
G01Y610476D02*
Y604394D01*
G01X1310165Y587839D02*
Y606539D01*
G01X1310087Y588825D02*
Y587840D01*
G01Y606538D02*
Y605553D01*
G01X1309890Y605555D02*
Y610396D01*
G01Y583982D02*
Y588823D01*
G01X1309811Y604760D02*
Y605751D01*
G01Y588627D02*
Y589618D01*
G01X1309732Y584965D02*
Y583902D01*
G01Y610476D02*
Y609413D01*
G01X1309457Y583902D02*
Y584886D01*
G01Y610476D02*
Y609492D01*
G01X1308669Y584886D02*
Y583902D01*
G01Y610476D02*
Y609492D01*
G01X1317420Y605368D02*
X1317433Y604394D01*
G01X1316454Y589010D02*
X1316441Y589984D01*
G01X1313487Y605368D02*
X1313500Y604394D01*
G01X1312513Y589010D02*
X1312500Y589984D01*
G01X1309546Y605368D02*
X1309559Y604394D01*
G01X1308580Y589010D02*
X1308567Y589984D01*
G01X1320009Y600239D02*
X1319873Y606147D01*
G01X1319868Y605261D02*
X1320004Y599353D01*
G01X1317947Y589117D02*
X1317811Y595025D01*
G01X1317806Y594139D02*
X1317943Y588231D01*
G01X1316068Y600239D02*
X1315931Y606147D01*
G01X1315927Y605261D02*
X1316063Y599353D01*
G01X1314006Y589117D02*
X1313870Y595025D01*
G01X1313865Y594139D02*
X1314001Y588231D01*
G01X1312135Y600239D02*
X1311999Y606147D01*
G01X1311994Y605261D02*
X1312130Y599353D01*
G01X1310073Y589117D02*
X1309937Y595025D01*
G01X1309932Y594139D02*
X1310069Y588231D01*
G01X1308194Y600239D02*
X1308057Y606147D01*
G01X1308053Y605261D02*
X1308189Y599353D01*
G01X1320074Y594341D02*
X1320024Y595327D01*
G01X1320021Y594365D02*
X1320072Y593379D01*
G01X1317785Y600013D02*
X1317735Y600999D01*
G01X1317732Y600037D02*
X1317783Y599051D01*
G01X1316142Y594341D02*
X1316091Y595327D01*
G01X1316089Y594365D02*
X1316139Y593379D01*
G01X1313853Y600013D02*
X1313802Y600999D01*
G01X1313800Y600037D02*
X1313850Y599051D01*
G01X1312200Y594341D02*
X1312150Y595327D01*
G01X1312147Y594365D02*
X1312198Y593379D01*
G01X1309911Y600013D02*
X1309861Y600999D01*
G01X1309858Y600037D02*
X1309909Y599051D01*
G01X1308268Y594341D02*
X1308217Y595327D01*
G01X1308215Y594365D02*
X1308265Y593379D01*
G01X1316418Y589984D02*
X1316409Y589937D01*
G01X1317456Y604394D02*
X1317465Y604441D01*
G01X1312477Y589984D02*
X1312467Y589937D01*
G01X1313523Y604394D02*
X1313533Y604441D01*
G01X1313793Y593379D02*
X1313843Y594365D01*
G01X1313841Y595327D02*
X1313791Y594341D01*
G01X1312159Y599051D02*
X1312209Y600037D01*
G01X1312207Y600999D02*
X1312157Y600013D01*
G01X1309861Y593379D02*
X1309911Y594365D01*
G01X1309909Y595327D02*
X1309858Y594341D01*
G01X1308217Y599051D02*
X1308268Y600037D01*
G01X1308265Y600999D02*
X1308215Y600013D01*
G01X1309937Y599353D02*
X1310073Y605261D01*
G01X1310069Y606147D02*
X1309932Y600239D01*
G01X1308057Y588231D02*
X1308194Y594139D01*
G01X1308189Y595025D02*
X1308053Y589117D01*
G01X1309559Y589984D02*
X1309546Y589010D01*
G01X1308567Y604394D02*
X1308580Y605368D01*
G01X1308394Y584965D02*
Y583902D01*
G01Y610476D02*
Y609413D01*
G01X1308315Y589618D02*
Y588627D01*
G01Y605751D02*
Y604760D01*
G01X1308236Y605555D02*
Y610396D01*
G01Y583982D02*
Y588823D01*
G01X1308039Y587840D02*
Y588825D01*
G01Y605553D02*
Y606538D01*
G01X1307961Y606539D02*
Y587839D01*
G01X1307882Y589984D02*
Y583902D01*
G01Y610476D02*
Y604394D01*
G01X1308535Y589937D02*
X1308544Y589984D01*
G01X1309591Y604441D02*
X1309582Y604394D01*
G01X1320133Y588640D02*
X1320387Y589010D01*
G01X1320120Y589615D02*
X1320341Y589937D01*
G01X1316201Y588640D02*
X1316454Y589010D01*
G01X1316187Y589615D02*
X1316409Y589937D01*
G01X1312259Y588640D02*
X1312513Y589010D01*
G01X1312246Y589615D02*
X1312467Y589937D01*
G01X1308326Y588640D02*
X1308580Y589010D01*
G01X1308535Y589937D02*
X1308315Y589618D01*
G01X1317687Y604763D02*
X1317465Y604441D01*
G01X1317674Y605738D02*
X1317420Y605368D01*
G01X1313754Y604763D02*
X1313533Y604441D01*
G01X1313741Y605738D02*
X1313487Y605368D01*
G01X1309591Y604441D02*
X1309811Y604760D01*
G01X1309799Y605738D02*
X1309546Y605368D01*
G01X1325560Y605754D02*
X1325559Y605751D01*
G01X1325560Y605756D02*
Y605754D01*
G01X1325561Y605757D02*
X1325560Y605756D01*
G01X1333434Y605754D02*
X1333433Y605751D01*
G01X1333434Y605756D02*
Y605754D01*
G01X1333435Y605757D02*
X1333434Y605756D01*
G01X1324062Y588624D02*
X1324063Y588627D01*
G01X1324062Y588622D02*
Y588624D01*
G01X1324061Y588621D02*
X1324062Y588622D01*
G01X1341308Y605754D02*
X1341307Y605751D01*
G01X1341308Y605756D02*
Y605754D01*
G01X1341309Y605757D02*
X1341308Y605756D01*
G01X1331936Y588624D02*
X1331937Y588627D01*
G01X1331936Y588622D02*
Y588624D01*
G01X1331935Y588621D02*
X1331936Y588622D01*
G01X1349182Y605754D02*
X1349181Y605751D01*
G01X1349182Y605756D02*
Y605754D01*
G01X1349183Y605757D02*
X1349182Y605756D01*
G01X1339810Y588624D02*
X1339811Y588627D01*
G01X1339810Y588622D02*
Y588624D01*
G01X1339809Y588621D02*
X1339810Y588622D01*
G01X1357056Y605754D02*
X1357055Y605751D01*
G01X1357056Y605756D02*
Y605754D01*
G01X1357057Y605757D02*
X1357056Y605756D01*
G01X1347684Y588624D02*
X1347685Y588627D01*
G01X1347684Y588622D02*
Y588624D01*
G01X1347683Y588621D02*
X1347684Y588622D01*
G01X1364930Y605754D02*
X1364929Y605751D01*
G01X1364930Y605756D02*
Y605754D01*
G01X1364931Y605757D02*
X1364930Y605756D01*
G01X1355558Y588624D02*
X1355559Y588627D01*
G01X1355558Y588622D02*
Y588624D01*
G01X1355557Y588621D02*
X1355558Y588622D01*
G01X1325560Y604768D02*
X1325559Y604763D01*
G01X1325560Y604771D02*
Y604768D01*
G01X1325561Y604772D02*
X1325560Y604771D01*
G01X1324062Y589610D02*
X1324063Y589615D01*
G01X1324062Y589607D02*
Y589610D01*
G01X1324061Y589606D02*
X1324062Y589607D01*
G01X1333434Y604768D02*
X1333433Y604763D01*
G01X1333434Y604771D02*
Y604768D01*
G01X1333435Y604772D02*
X1333434Y604771D01*
G01X1331936Y589610D02*
X1331937Y589615D01*
G01X1331936Y589607D02*
Y589610D01*
G01X1331935Y589606D02*
X1331936Y589607D01*
G01X1341308Y604768D02*
X1341307Y604763D01*
G01X1341308Y604771D02*
Y604768D01*
G01X1341309Y604772D02*
X1341308Y604771D01*
G01X1339810Y589610D02*
X1339811Y589615D01*
G01X1339810Y589607D02*
Y589610D01*
G01X1339809Y589606D02*
X1339810Y589607D01*
G01X1349182Y604768D02*
X1349181Y604763D01*
G01X1349182Y604771D02*
Y604768D01*
G01X1349183Y604772D02*
X1349182Y604771D01*
G01X1372804Y605754D02*
X1372803Y605751D01*
G01X1372804Y605756D02*
Y605754D01*
G01X1372805Y605757D02*
X1372804Y605756D01*
G01X1363432Y588624D02*
X1363433Y588627D01*
G01X1363432Y588622D02*
Y588624D01*
G01X1363431Y588621D02*
X1363432Y588622D01*
G01X1380678Y605754D02*
X1380677Y605751D01*
G01X1380678Y605756D02*
Y605754D01*
G01X1380679Y605757D02*
X1380678Y605756D01*
G01X1371307Y588624D02*
Y588627D01*
G01X1371306Y588622D02*
X1371307Y588624D01*
G01X1371305Y588621D02*
X1371306Y588622D01*
G01X1379181Y588624D02*
Y588627D01*
G01X1379180Y588622D02*
X1379181Y588624D01*
G01X1379179Y588621D02*
X1379180Y588622D01*
G01X1387055Y588624D02*
Y588627D01*
G01X1387054Y588622D02*
X1387055Y588624D01*
G01X1387053Y588621D02*
X1387054Y588622D01*
G01X1321893Y605413D02*
X1321889Y605261D01*
G01X1321898Y605511D02*
X1321893Y605413D01*
G01X1321902Y605553D02*
X1321898Y605511D01*
G01X1321890Y606353D02*
X1321884Y606147D01*
G01X1321896Y606485D02*
X1321890Y606353D01*
G01X1321902Y606538D02*
X1321896Y606485D01*
G01X1321629Y590169D02*
X1321630Y590571D01*
G01X1321626Y589841D02*
X1321629Y590169D01*
G01X1321622Y589645D02*
X1321626Y589841D01*
G01X1321618Y589615D02*
X1321622Y589645D01*
G01X1327993Y604209D02*
X1327992Y603807D01*
G01X1327996Y604537D02*
X1327993Y604209D01*
G01X1328000Y604733D02*
X1327996Y604537D01*
G01X1328004Y604763D02*
X1328000Y604733D01*
G01X1347684Y589610D02*
X1347685Y589615D01*
G01X1347684Y589607D02*
Y589610D01*
G01X1347683Y589606D02*
X1347684Y589607D01*
G01X1357056Y604768D02*
X1357055Y604763D01*
G01X1357056Y604771D02*
Y604768D01*
G01X1357057Y604772D02*
X1357056Y604771D01*
G01X1355558Y589610D02*
X1355559Y589615D01*
G01X1355558Y589607D02*
Y589610D01*
G01X1355557Y589606D02*
X1355558Y589607D01*
G01X1364930Y604768D02*
X1364929Y604763D01*
G01X1364930Y604771D02*
Y604768D01*
G01X1364931Y604772D02*
X1364930Y604771D01*
G01X1363432Y589610D02*
X1363433Y589615D01*
G01X1363432Y589607D02*
Y589610D01*
G01X1363431Y589606D02*
X1363432Y589607D01*
G01X1321887Y587893D02*
X1321893Y587840D01*
G01X1321881Y588025D02*
X1321887Y587893D01*
G01X1321875Y588231D02*
X1321881Y588025D01*
G01X1323794Y606485D02*
X1323787Y606538D01*
G01X1323800Y606353D02*
X1323794Y606485D01*
G01X1323805Y606147D02*
X1323800Y606353D01*
G01X1325828Y587893D02*
X1325835Y587840D01*
G01X1325822Y588025D02*
X1325828Y587893D01*
G01X1325817Y588231D02*
X1325822Y588025D01*
G01X1327735Y606485D02*
X1327729Y606538D01*
G01X1327741Y606353D02*
X1327735Y606485D01*
G01X1327747Y606147D02*
X1327741Y606353D01*
G01X1321888Y588867D02*
X1321893Y588825D01*
G01X1321884Y588965D02*
X1321888Y588867D01*
G01X1321880Y589117D02*
X1321884Y588965D01*
G01X1323792Y605511D02*
X1323787Y605553D01*
G01X1323796Y605413D02*
X1323792Y605511D01*
G01X1323801Y605261D02*
X1323796Y605413D01*
G01X1325830Y588867D02*
X1325835Y588825D01*
G01X1325826Y588965D02*
X1325830Y588867D01*
G01X1325821Y589117D02*
X1325826Y588965D01*
G01X1327734Y605511D02*
X1327729Y605553D01*
G01X1327738Y605413D02*
X1327734Y605511D01*
G01X1327742Y605261D02*
X1327738Y605413D01*
G01X1321631Y604733D02*
X1321627Y604763D01*
G01X1321636Y604537D02*
X1321631Y604733D01*
G01X1321638Y604209D02*
X1321636Y604537D01*
G01X1321639Y603807D02*
X1321638Y604209D01*
G01X1327991Y589645D02*
X1327995Y589615D01*
G01X1327986Y589841D02*
X1327991Y589645D01*
G01X1327984Y590169D02*
X1327986Y589841D01*
G01X1327983Y590571D02*
X1327984Y590169D01*
G01X1329506Y604733D02*
X1329501Y604763D01*
G01X1329510Y604537D02*
X1329506Y604733D01*
G01X1329512Y604209D02*
X1329510Y604537D01*
G01X1329513Y603807D02*
X1329512Y604209D01*
G01X1324053Y588770D02*
X1324061Y588621D01*
G01X1324046Y589184D02*
X1324053Y588770D01*
G01X1324041Y589804D02*
X1324046Y589184D01*
G01X1324039Y590552D02*
X1324041Y589804D01*
G01X1324057Y589679D02*
X1324061Y589606D01*
G01X1324054Y589887D02*
X1324057Y589679D01*
G01X1324051Y590200D02*
X1324054Y589887D01*
G01X1324050Y590571D02*
X1324051Y590200D01*
G01X1325565Y604699D02*
X1325561Y604772D01*
G01X1325568Y604491D02*
X1325565Y604699D01*
G01X1325571Y604178D02*
X1325568Y604491D01*
G01X1325572Y603807D02*
X1325571Y604178D01*
G01X1325569Y605608D02*
X1325561Y605757D01*
G01X1325576Y605193D02*
X1325569Y605608D01*
G01X1325581Y604573D02*
X1325576Y605193D01*
G01X1325583Y603826D02*
X1325581Y604573D01*
G01X1331927Y588770D02*
X1331935Y588621D01*
G01X1331920Y589184D02*
X1331927Y588770D01*
G01X1331915Y589804D02*
X1331920Y589184D01*
G01X1331913Y590552D02*
X1331915Y589804D01*
G01X1331931Y589679D02*
X1331935Y589606D01*
G01X1331928Y589887D02*
X1331931Y589679D01*
G01X1331925Y590200D02*
X1331928Y589887D01*
G01X1331924Y590571D02*
X1331925Y590200D01*
G01X1324041Y604573D02*
X1324039Y603826D01*
G01X1324046Y605193D02*
X1324041Y604573D01*
G01X1324053Y605608D02*
X1324046Y605193D01*
G01X1324061Y605757D02*
X1324053Y605608D01*
G01X1325581Y589804D02*
X1325583Y590552D01*
G01X1325576Y589184D02*
X1325581Y589804D01*
G01X1325569Y588770D02*
X1325576Y589184D01*
G01X1325561Y588621D02*
X1325569Y588770D01*
G01X1331915Y604573D02*
X1331913Y603826D01*
G01X1331920Y605193D02*
X1331915Y604573D01*
G01X1331927Y605608D02*
X1331920Y605193D01*
G01X1331935Y605757D02*
X1331927Y605608D01*
G01X1333455Y589804D02*
X1333457Y590552D01*
G01X1333450Y589184D02*
X1333455Y589804D01*
G01X1333443Y588770D02*
X1333450Y589184D01*
G01X1333435Y588621D02*
X1333443Y588770D01*
G01X1339789Y604573D02*
X1339787Y603826D01*
G01X1339794Y605193D02*
X1339789Y604573D01*
G01X1339801Y605608D02*
X1339794Y605193D01*
G01X1339809Y605757D02*
X1339801Y605608D01*
G01X1324051Y604178D02*
X1324050Y603807D01*
G01X1324054Y604491D02*
X1324051Y604178D01*
G01X1324057Y604699D02*
X1324054Y604491D01*
G01X1324061Y604772D02*
X1324057Y604699D01*
G01X1325571Y590200D02*
X1325572Y590571D01*
G01X1325568Y589887D02*
X1325571Y590200D01*
G01X1325565Y589679D02*
X1325568Y589887D01*
G01X1325561Y589606D02*
X1325565Y589679D01*
G01X1331925Y604178D02*
X1331924Y603807D01*
G01X1331928Y604491D02*
X1331925Y604178D01*
G01X1331931Y604699D02*
X1331928Y604491D01*
G01X1331935Y604772D02*
X1331931Y604699D01*
G01X1333445Y590200D02*
X1333446Y590571D01*
G01X1333442Y589887D02*
X1333445Y590200D01*
G01X1333439Y589679D02*
X1333442Y589887D01*
G01X1333435Y589606D02*
X1333439Y589679D01*
G01X1339799Y604178D02*
X1339798Y603807D01*
G01X1339802Y604491D02*
X1339799Y604178D01*
G01X1339805Y604699D02*
X1339802Y604491D01*
G01X1339809Y604772D02*
X1339805Y604699D01*
G01X1323796Y588965D02*
X1323801Y589117D01*
G01X1323792Y588867D02*
X1323796Y588965D01*
G01X1323787Y588825D02*
X1323792Y588867D01*
G01X1325826Y605413D02*
X1325821Y605261D01*
G01X1325830Y605511D02*
X1325826Y605413D01*
G01X1325835Y605553D02*
X1325830Y605511D01*
G01X1327729Y588965D02*
X1327733Y589117D01*
G01X1327724Y588867D02*
X1327729Y588965D01*
G01X1327720Y588825D02*
X1327724Y588867D01*
G01X1329767Y605413D02*
X1329763Y605261D01*
G01X1329772Y605511D02*
X1329767Y605413D01*
G01X1329776Y605553D02*
X1329772Y605511D01*
G01X1331670Y588965D02*
X1331675Y589117D01*
G01X1331666Y588867D02*
X1331670Y588965D01*
G01X1331661Y588825D02*
X1331666Y588867D01*
G01X1333700Y605413D02*
X1333695Y605261D01*
G01X1333704Y605511D02*
X1333700Y605413D01*
G01X1333709Y605553D02*
X1333704Y605511D01*
G01X1335603Y588965D02*
X1335607Y589117D01*
G01X1335598Y588867D02*
X1335603Y588965D01*
G01X1335594Y588825D02*
X1335598Y588867D01*
G01X1337641Y605413D02*
X1337637Y605261D01*
G01X1337646Y605511D02*
X1337641Y605413D01*
G01X1337650Y605553D02*
X1337646Y605511D01*
G01X1339544Y588965D02*
X1339549Y589117D01*
G01X1339540Y588867D02*
X1339544Y588965D01*
G01X1339535Y588825D02*
X1339540Y588867D01*
G01X1341574Y605413D02*
X1341569Y605261D01*
G01X1341578Y605511D02*
X1341574Y605413D01*
G01X1341583Y605553D02*
X1341578Y605511D01*
G01X1343477Y588965D02*
X1343481Y589117D01*
G01X1343472Y588867D02*
X1343477Y588965D01*
G01X1343468Y588825D02*
X1343472Y588867D01*
G01X1345515Y605413D02*
X1345511Y605261D01*
G01X1345520Y605511D02*
X1345515Y605413D01*
G01X1345524Y605553D02*
X1345520Y605511D01*
G01X1325822Y606353D02*
X1325817Y606147D01*
G01X1325828Y606485D02*
X1325822Y606353D01*
G01X1325835Y606538D02*
X1325828Y606485D01*
G01X1323800Y588025D02*
X1323805Y588231D01*
G01X1323794Y587893D02*
X1323800Y588025D01*
G01X1323787Y587840D02*
X1323794Y587893D01*
G01X1329764Y606353D02*
X1329758Y606147D01*
G01X1329770Y606485D02*
X1329764Y606353D01*
G01X1329776Y606538D02*
X1329770Y606485D01*
G01X1327732Y588025D02*
X1327738Y588231D01*
G01X1327726Y587893D02*
X1327732Y588025D01*
G01X1327720Y587840D02*
X1327726Y587893D01*
G01X1333696Y606353D02*
X1333691Y606147D01*
G01X1333702Y606485D02*
X1333696Y606353D01*
G01X1333709Y606538D02*
X1333702Y606485D01*
G01X1331674Y588025D02*
X1331679Y588231D01*
G01X1331668Y587893D02*
X1331674Y588025D01*
G01X1331661Y587840D02*
X1331668Y587893D01*
G01X1337638Y606353D02*
X1337632Y606147D01*
G01X1337644Y606485D02*
X1337638Y606353D01*
G01X1337650Y606538D02*
X1337644Y606485D01*
G01X1335606Y588025D02*
X1335612Y588231D01*
G01X1335600Y587893D02*
X1335606Y588025D01*
G01X1335594Y587840D02*
X1335600Y587893D01*
G01X1341570Y606353D02*
X1341565Y606147D01*
G01X1341576Y606485D02*
X1341570Y606353D01*
G01X1341583Y606538D02*
X1341576Y606485D01*
G01X1339548Y588025D02*
X1339553Y588231D01*
G01X1339542Y587893D02*
X1339548Y588025D01*
G01X1339535Y587840D02*
X1339542Y587893D01*
G01X1345512Y606353D02*
X1345506Y606147D01*
G01X1345518Y606485D02*
X1345512Y606353D01*
G01X1345524Y606538D02*
X1345518Y606485D01*
G01X1343480Y588025D02*
X1343486Y588231D01*
G01X1343474Y587893D02*
X1343480Y588025D01*
G01X1343468Y587840D02*
X1343474Y587893D01*
G01X1349444Y606353D02*
X1349439Y606147D01*
G01X1349451Y606485D02*
X1349444Y606353D01*
G01X1349457Y606538D02*
X1349451Y606485D01*
G01X1347422Y588025D02*
X1347427Y588231D01*
G01X1347416Y587893D02*
X1347422Y588025D01*
G01X1347409Y587840D02*
X1347416Y587893D01*
G01X1329503Y590169D02*
X1329504Y590571D01*
G01X1329500Y589841D02*
X1329503Y590169D01*
G01X1329496Y589645D02*
X1329500Y589841D01*
G01X1329492Y589615D02*
X1329496Y589645D01*
G01X1335867Y604209D02*
X1335866Y603807D01*
G01X1335870Y604537D02*
X1335867Y604209D01*
G01X1335874Y604733D02*
X1335870Y604537D01*
G01X1335878Y604763D02*
X1335874Y604733D01*
G01X1337377Y590169D02*
X1337378Y590571D01*
G01X1337374Y589841D02*
X1337377Y590169D01*
G01X1337370Y589645D02*
X1337374Y589841D01*
G01X1337366Y589615D02*
X1337370Y589645D01*
G01X1343741Y604209D02*
X1343740Y603807D01*
G01X1343744Y604537D02*
X1343741Y604209D01*
G01X1343748Y604733D02*
X1343744Y604537D01*
G01X1343753Y604763D02*
X1343748Y604733D01*
G01X1345251Y590169D02*
X1345252Y590571D01*
G01X1345248Y589841D02*
X1345251Y590169D01*
G01X1345244Y589645D02*
X1345248Y589841D01*
G01X1345240Y589615D02*
X1345244Y589645D01*
G01X1351615Y604209D02*
X1351614Y603807D01*
G01X1351618Y604537D02*
X1351615Y604209D01*
G01X1351622Y604733D02*
X1351618Y604537D01*
G01X1351627Y604763D02*
X1351622Y604733D01*
G01X1353125Y590169D02*
X1353126Y590571D01*
G01X1353122Y589841D02*
X1353125Y590169D01*
G01X1353118Y589645D02*
X1353122Y589841D01*
G01X1353114Y589615D02*
X1353118Y589645D01*
G01X1387054Y589610D02*
X1387055Y589615D01*
G01X1387054Y589607D02*
Y589610D01*
G01X1387053Y589606D02*
X1387054Y589607D01*
G01X1324062Y604771D02*
X1324061Y604772D01*
G01X1324062Y604768D02*
Y604771D01*
G01X1324063Y604763D02*
X1324062Y604768D01*
G01X1325560Y589607D02*
X1325561Y589606D01*
G01X1325560Y589610D02*
Y589607D01*
G01X1325559Y589615D02*
X1325560Y589610D01*
G01X1331936Y604771D02*
X1331935Y604772D01*
G01X1331936Y604768D02*
Y604771D01*
G01X1331937Y604763D02*
X1331936Y604768D01*
G01X1333434Y589607D02*
X1333435Y589606D01*
G01X1333434Y589610D02*
Y589607D01*
G01X1333433Y589615D02*
X1333434Y589610D01*
G01X1339810Y604771D02*
X1339809Y604772D01*
G01X1339810Y604768D02*
Y604771D01*
G01X1339811Y604763D02*
X1339810Y604768D01*
G01X1341308Y589607D02*
X1341309Y589606D01*
G01X1341308Y589610D02*
Y589607D01*
G01X1341307Y589615D02*
X1341308Y589610D01*
G01X1329761Y587893D02*
X1329767Y587840D01*
G01X1329755Y588025D02*
X1329761Y587893D01*
G01X1329749Y588231D02*
X1329755Y588025D01*
G01X1331668Y606485D02*
X1331661Y606538D01*
G01X1331674Y606353D02*
X1331668Y606485D01*
G01X1331679Y606147D02*
X1331674Y606353D01*
G01X1333702Y587893D02*
X1333709Y587840D01*
G01X1333696Y588025D02*
X1333702Y587893D01*
G01X1333691Y588231D02*
X1333696Y588025D01*
G01X1335609Y606485D02*
X1335603Y606538D01*
G01X1335615Y606353D02*
X1335609Y606485D01*
G01X1335621Y606147D02*
X1335615Y606353D01*
G01X1337635Y587893D02*
X1337641Y587840D01*
G01X1337629Y588025D02*
X1337635Y587893D01*
G01X1337623Y588231D02*
X1337629Y588025D01*
G01X1339542Y606485D02*
X1339535Y606538D01*
G01X1339548Y606353D02*
X1339542Y606485D01*
G01X1339553Y606147D02*
X1339548Y606353D01*
G01X1341576Y587893D02*
X1341583Y587840D01*
G01X1341570Y588025D02*
X1341576Y587893D01*
G01X1341565Y588231D02*
X1341570Y588025D01*
G01X1343483Y606485D02*
X1343477Y606538D01*
G01X1343489Y606353D02*
X1343483Y606485D01*
G01X1343495Y606147D02*
X1343489Y606353D01*
G01X1345509Y587893D02*
X1345515Y587840D01*
G01X1345503Y588025D02*
X1345509Y587893D01*
G01X1345497Y588231D02*
X1345503Y588025D01*
G01X1347416Y606485D02*
X1347409Y606538D01*
G01X1347422Y606353D02*
X1347416Y606485D01*
G01X1347427Y606147D02*
X1347422Y606353D01*
G01X1349451Y587893D02*
X1349457Y587840D01*
G01X1349444Y588025D02*
X1349451Y587893D01*
G01X1349439Y588231D02*
X1349444Y588025D01*
G01X1351357Y606485D02*
X1351351Y606538D01*
G01X1351363Y606353D02*
X1351357Y606485D01*
G01X1351369Y606147D02*
X1351363Y606353D01*
G01X1353383Y587893D02*
X1353389Y587840D01*
G01X1353377Y588025D02*
X1353383Y587893D01*
G01X1353371Y588231D02*
X1353377Y588025D01*
G01X1329762Y588867D02*
X1329767Y588825D01*
G01X1329758Y588965D02*
X1329762Y588867D01*
G01X1329754Y589117D02*
X1329758Y588965D01*
G01X1331666Y605511D02*
X1331661Y605553D01*
G01X1331670Y605413D02*
X1331666Y605511D01*
G01X1331675Y605261D02*
X1331670Y605413D01*
G01X1333704Y588867D02*
X1333709Y588825D01*
G01X1333700Y588965D02*
X1333704Y588867D01*
G01X1333695Y589117D02*
X1333700Y588965D01*
G01X1335608Y605511D02*
X1335603Y605553D01*
G01X1335612Y605413D02*
X1335608Y605511D01*
G01X1335616Y605261D02*
X1335612Y605413D01*
G01X1337636Y588867D02*
X1337641Y588825D01*
G01X1337632Y588965D02*
X1337636Y588867D01*
G01X1337628Y589117D02*
X1337632Y588965D01*
G01X1339540Y605511D02*
X1339535Y605553D01*
G01X1339544Y605413D02*
X1339540Y605511D01*
G01X1339549Y605261D02*
X1339544Y605413D01*
G01X1341578Y588867D02*
X1341583Y588825D01*
G01X1341574Y588965D02*
X1341578Y588867D01*
G01X1341569Y589117D02*
X1341574Y588965D01*
G01X1343482Y605511D02*
X1343477Y605553D01*
G01X1343486Y605413D02*
X1343482Y605511D01*
G01X1343490Y605261D02*
X1343486Y605413D01*
G01X1345510Y588867D02*
X1345515Y588825D01*
G01X1345506Y588965D02*
X1345510Y588867D01*
G01X1345502Y589117D02*
X1345506Y588965D01*
G01X1347414Y605511D02*
X1347409Y605553D01*
G01X1347418Y605413D02*
X1347414Y605511D01*
G01X1347423Y605261D02*
X1347418Y605413D01*
G01X1349452Y588867D02*
X1349457Y588825D01*
G01X1349448Y588965D02*
X1349452Y588867D01*
G01X1349443Y589117D02*
X1349448Y588965D01*
G01X1351356Y605511D02*
X1351351Y605553D01*
G01X1351360Y605413D02*
X1351356Y605511D01*
G01X1351364Y605261D02*
X1351360Y605413D01*
G01X1353384Y588867D02*
X1353389Y588825D01*
G01X1353380Y588965D02*
X1353384Y588867D01*
G01X1353376Y589117D02*
X1353380Y588965D01*
G01X1335865Y589645D02*
X1335869Y589615D01*
G01X1335861Y589841D02*
X1335865Y589645D01*
G01X1335858Y590169D02*
X1335861Y589841D01*
G01X1335857Y590571D02*
X1335858Y590169D01*
G01X1337380Y604733D02*
X1337375Y604763D01*
G01X1337384Y604537D02*
X1337380Y604733D01*
G01X1337386Y604209D02*
X1337384Y604537D01*
G01X1337387Y603807D02*
X1337386Y604209D01*
G01X1343739Y589645D02*
X1343743Y589615D01*
G01X1343735Y589841D02*
X1343739Y589645D01*
G01X1343732Y590169D02*
X1343735Y589841D01*
G01X1343731Y590571D02*
X1343732Y590169D01*
G01X1345254Y604733D02*
X1345249Y604763D01*
G01X1345258Y604537D02*
X1345254Y604733D01*
G01X1345260Y604209D02*
X1345258Y604537D01*
G01X1345261Y603807D02*
X1345260Y604209D01*
G01X1351613Y589645D02*
X1351617Y589615D01*
G01X1351609Y589841D02*
X1351613Y589645D01*
G01X1351606Y590169D02*
X1351609Y589841D01*
G01X1351605Y590571D02*
X1351606Y590169D01*
G01X1353128Y604733D02*
X1353123Y604763D01*
G01X1353132Y604537D02*
X1353128Y604733D01*
G01X1353134Y604209D02*
X1353132Y604537D01*
G01X1353135Y603807D02*
X1353134Y604209D01*
G01X1333439Y604699D02*
X1333435Y604772D01*
G01X1333442Y604491D02*
X1333439Y604699D01*
G01X1333445Y604178D02*
X1333442Y604491D01*
G01X1333446Y603807D02*
X1333445Y604178D01*
G01X1333443Y605608D02*
X1333435Y605757D01*
G01X1333450Y605193D02*
X1333443Y605608D01*
G01X1333455Y604573D02*
X1333450Y605193D01*
G01X1333457Y603826D02*
X1333455Y604573D01*
G01X1339801Y588770D02*
X1339809Y588621D01*
G01X1339794Y589184D02*
X1339801Y588770D01*
G01X1339789Y589804D02*
X1339794Y589184D01*
G01X1339787Y590552D02*
X1339789Y589804D01*
G01X1339805Y589679D02*
X1339809Y589606D01*
G01X1339802Y589887D02*
X1339805Y589679D01*
G01X1339799Y590200D02*
X1339802Y589887D01*
G01X1339798Y590571D02*
X1339799Y590200D01*
G01X1341313Y604699D02*
X1341309Y604772D01*
G01X1341316Y604491D02*
X1341313Y604699D01*
G01X1341319Y604178D02*
X1341316Y604491D01*
G01X1341320Y603807D02*
X1341319Y604178D01*
G01X1341317Y605608D02*
X1341309Y605757D01*
G01X1341324Y605193D02*
X1341317Y605608D01*
G01X1341329Y604573D02*
X1341324Y605193D01*
G01X1341331Y603826D02*
X1341329Y604573D01*
G01X1347675Y588770D02*
X1347683Y588621D01*
G01X1347668Y589184D02*
X1347675Y588770D01*
G01X1347663Y589804D02*
X1347668Y589184D01*
G01X1347661Y590552D02*
X1347663Y589804D01*
G01X1347679Y589679D02*
X1347683Y589606D01*
G01X1347676Y589887D02*
X1347679Y589679D01*
G01X1347673Y590200D02*
X1347676Y589887D01*
G01X1347672Y590571D02*
X1347673Y590200D01*
G01X1349187Y604699D02*
X1349183Y604772D01*
G01X1349190Y604491D02*
X1349187Y604699D01*
G01X1349193Y604178D02*
X1349190Y604491D01*
G01X1349194Y603807D02*
X1349193Y604178D01*
G01X1349191Y605608D02*
X1349183Y605757D01*
G01X1349198Y605193D02*
X1349191Y605608D01*
G01X1349203Y604573D02*
X1349198Y605193D01*
G01X1349205Y603826D02*
X1349203Y604573D01*
G01X1355549Y588770D02*
X1355557Y588621D01*
G01X1355542Y589184D02*
X1355549Y588770D01*
G01X1355537Y589804D02*
X1355542Y589184D01*
G01X1355535Y590552D02*
X1355537Y589804D01*
G01X1355553Y589679D02*
X1355557Y589606D01*
G01X1355550Y589887D02*
X1355553Y589679D01*
G01X1355547Y590200D02*
X1355550Y589887D01*
G01X1355546Y590571D02*
X1355547Y590200D01*
G01X1357061Y604699D02*
X1357057Y604772D01*
G01X1357064Y604491D02*
X1357061Y604699D01*
G01X1357067Y604178D02*
X1357064Y604491D01*
G01X1357068Y603807D02*
X1357067Y604178D01*
G01X1357065Y605608D02*
X1357057Y605757D01*
G01X1357072Y605193D02*
X1357065Y605608D01*
G01X1357077Y604573D02*
X1357072Y605193D01*
G01X1357079Y603826D02*
X1357077Y604573D01*
G01X1341329Y589804D02*
X1341331Y590552D01*
G01X1341324Y589184D02*
X1341329Y589804D01*
G01X1341317Y588770D02*
X1341324Y589184D01*
G01X1341309Y588621D02*
X1341317Y588770D01*
G01X1347663Y604573D02*
X1347661Y603826D01*
G01X1347668Y605193D02*
X1347663Y604573D01*
G01X1347675Y605608D02*
X1347668Y605193D01*
G01X1347683Y605757D02*
X1347675Y605608D01*
G01X1349203Y589804D02*
X1349205Y590552D01*
G01X1349198Y589184D02*
X1349203Y589804D01*
G01X1349191Y588770D02*
X1349198Y589184D01*
G01X1349183Y588621D02*
X1349191Y588770D01*
G01X1355537Y604573D02*
X1355535Y603826D01*
G01X1355542Y605193D02*
X1355537Y604573D01*
G01X1355549Y605608D02*
X1355542Y605193D01*
G01X1355557Y605757D02*
X1355549Y605608D01*
G01X1357077Y589804D02*
X1357079Y590552D01*
G01X1357072Y589184D02*
X1357077Y589804D01*
G01X1357065Y588770D02*
X1357072Y589184D01*
G01X1357057Y588621D02*
X1357065Y588770D01*
G01X1363411Y604573D02*
X1363409Y603826D01*
G01X1363416Y605193D02*
X1363411Y604573D01*
G01X1363423Y605608D02*
X1363416Y605193D01*
G01X1363431Y605757D02*
X1363423Y605608D01*
G01X1364951Y589804D02*
X1364953Y590552D01*
G01X1364946Y589184D02*
X1364951Y589804D01*
G01X1364939Y588770D02*
X1364946Y589184D01*
G01X1364931Y588621D02*
X1364939Y588770D01*
G01X1341319Y590200D02*
X1341320Y590571D01*
G01X1341316Y589887D02*
X1341319Y590200D01*
G01X1341313Y589679D02*
X1341316Y589887D01*
G01X1341309Y589606D02*
X1341313Y589679D01*
G01X1347673Y604178D02*
X1347672Y603807D01*
G01X1347676Y604491D02*
X1347673Y604178D01*
G01X1347679Y604699D02*
X1347676Y604491D01*
G01X1347683Y604772D02*
X1347679Y604699D01*
G01X1349193Y590200D02*
X1349194Y590571D01*
G01X1349190Y589887D02*
X1349193Y590200D01*
G01X1349187Y589679D02*
X1349190Y589887D01*
G01X1349183Y589606D02*
X1349187Y589679D01*
G01X1355547Y604178D02*
X1355546Y603807D01*
G01X1355550Y604491D02*
X1355547Y604178D01*
G01X1355553Y604699D02*
X1355550Y604491D01*
G01X1355557Y604772D02*
X1355553Y604699D01*
G01X1357067Y590200D02*
X1357068Y590571D01*
G01X1357064Y589887D02*
X1357067Y590200D01*
G01X1357061Y589679D02*
X1357064Y589887D01*
G01X1357057Y589606D02*
X1357061Y589679D01*
G01X1363421Y604178D02*
X1363420Y603807D01*
G01X1363424Y604491D02*
X1363421Y604178D01*
G01X1363427Y604699D02*
X1363424Y604491D01*
G01X1363431Y604772D02*
X1363427Y604699D01*
G01X1364941Y590200D02*
X1364942Y590571D01*
G01X1364939Y589887D02*
X1364941Y590200D01*
G01X1364935Y589679D02*
X1364939Y589887D01*
G01X1364931Y589606D02*
X1364935Y589679D01*
G01X1347418Y588965D02*
X1347423Y589117D01*
G01X1347414Y588867D02*
X1347418Y588965D01*
G01X1347409Y588825D02*
X1347414Y588867D01*
G01X1349448Y605413D02*
X1349443Y605261D01*
G01X1349452Y605511D02*
X1349448Y605413D01*
G01X1349457Y605553D02*
X1349452Y605511D01*
G01X1351351Y588965D02*
X1351355Y589117D01*
G01X1351346Y588867D02*
X1351351Y588965D01*
G01X1351342Y588825D02*
X1351346Y588867D01*
G01X1353389Y605413D02*
X1353385Y605261D01*
G01X1353394Y605511D02*
X1353389Y605413D01*
G01X1353398Y605553D02*
X1353394Y605511D01*
G01X1355292Y588965D02*
X1355297Y589117D01*
G01X1355288Y588867D02*
X1355292Y588965D01*
G01X1355283Y588825D02*
X1355288Y588867D01*
G01X1357322Y605413D02*
X1357317Y605261D01*
G01X1357326Y605511D02*
X1357322Y605413D01*
G01X1357331Y605553D02*
X1357326Y605511D01*
G01X1359225Y588965D02*
X1359229Y589117D01*
G01X1359220Y588867D02*
X1359225Y588965D01*
G01X1359216Y588825D02*
X1359220Y588867D01*
G01X1361263Y605413D02*
X1361259Y605261D01*
G01X1361268Y605511D02*
X1361263Y605413D01*
G01X1361272Y605553D02*
X1361268Y605511D01*
G01X1363166Y588965D02*
X1363171Y589117D01*
G01X1363162Y588867D02*
X1363166Y588965D01*
G01X1363157Y588825D02*
X1363162Y588867D01*
G01X1365196Y605413D02*
X1365192Y605261D01*
G01X1365200Y605511D02*
X1365196Y605413D01*
G01X1365205Y605553D02*
X1365200Y605511D01*
G01X1367099Y588965D02*
X1367103Y589117D01*
G01X1367094Y588867D02*
X1367099Y588965D01*
G01X1367090Y588825D02*
X1367094Y588867D01*
G01X1369137Y605413D02*
X1369133Y605261D01*
G01X1369142Y605511D02*
X1369137Y605413D01*
G01X1369146Y605553D02*
X1369142Y605511D01*
G01X1371040Y588965D02*
X1371045Y589117D01*
G01X1371036Y588867D02*
X1371040Y588965D01*
G01X1371031Y588825D02*
X1371036Y588867D01*
G01X1373070Y605413D02*
X1373066Y605261D01*
G01X1373074Y605511D02*
X1373070Y605413D01*
G01X1373079Y605553D02*
X1373074Y605511D01*
G01X1353386Y606353D02*
X1353380Y606147D01*
G01X1353392Y606485D02*
X1353386Y606353D01*
G01X1353398Y606538D02*
X1353392Y606485D01*
G01X1351354Y588025D02*
X1351360Y588231D01*
G01X1351348Y587893D02*
X1351354Y588025D01*
G01X1351342Y587840D02*
X1351348Y587893D01*
G01X1357318Y606353D02*
X1357313Y606147D01*
G01X1357325Y606485D02*
X1357318Y606353D01*
G01X1357331Y606538D02*
X1357325Y606485D01*
G01X1355296Y588025D02*
X1355301Y588231D01*
G01X1355290Y587893D02*
X1355296Y588025D01*
G01X1355283Y587840D02*
X1355290Y587893D01*
G01X1361260Y606353D02*
X1361254Y606147D01*
G01X1361266Y606485D02*
X1361260Y606353D01*
G01X1361272Y606538D02*
X1361266Y606485D01*
G01X1359228Y588025D02*
X1359234Y588231D01*
G01X1359222Y587893D02*
X1359228Y588025D01*
G01X1359216Y587840D02*
X1359222Y587893D01*
G01X1365192Y606353D02*
X1365187Y606147D01*
G01X1365199Y606485D02*
X1365192Y606353D01*
G01X1365205Y606538D02*
X1365199Y606485D01*
G01X1363170Y588025D02*
X1363175Y588231D01*
G01X1363164Y587893D02*
X1363170Y588025D01*
G01X1363157Y587840D02*
X1363164Y587893D01*
G01X1369134Y606353D02*
X1369128Y606147D01*
G01X1369140Y606485D02*
X1369134Y606353D01*
G01X1369146Y606538D02*
X1369140Y606485D01*
G01X1367102Y588025D02*
X1367108Y588231D01*
G01X1367096Y587893D02*
X1367102Y588025D01*
G01X1367090Y587840D02*
X1367096Y587893D01*
G01X1373067Y606353D02*
X1373061Y606147D01*
G01X1373073Y606485D02*
X1373067Y606353D01*
G01X1373079Y606538D02*
X1373073Y606485D01*
G01X1371044Y588025D02*
X1371049Y588231D01*
G01X1371038Y587893D02*
X1371044Y588025D01*
G01X1371031Y587840D02*
X1371038Y587893D01*
G01X1359489Y604209D02*
X1359488Y603807D01*
G01X1359492Y604537D02*
X1359489Y604209D01*
G01X1359496Y604733D02*
X1359492Y604537D01*
G01X1359501Y604763D02*
X1359496Y604733D01*
G01X1360999Y590169D02*
X1361000Y590571D01*
G01X1360996Y589841D02*
X1360999Y590169D01*
G01X1360992Y589645D02*
X1360996Y589841D01*
G01X1360988Y589615D02*
X1360992Y589645D01*
G01X1367363Y604209D02*
X1367362Y603807D01*
G01X1367366Y604537D02*
X1367363Y604209D01*
G01X1367370Y604733D02*
X1367366Y604537D01*
G01X1367375Y604763D02*
X1367370Y604733D01*
G01X1368873Y590169D02*
X1368874Y590571D01*
G01X1368870Y589841D02*
X1368873Y590169D01*
G01X1368866Y589645D02*
X1368870Y589841D01*
G01X1368862Y589615D02*
X1368866Y589645D01*
G01X1375237Y604209D02*
X1375236Y603807D01*
G01X1375240Y604537D02*
X1375237Y604209D01*
G01X1375244Y604733D02*
X1375240Y604537D01*
G01X1375249Y604763D02*
X1375244Y604733D01*
G01X1376747Y590169D02*
X1376748Y590571D01*
G01X1376744Y589841D02*
X1376747Y590169D01*
G01X1376740Y589645D02*
X1376744Y589841D01*
G01X1376736Y589615D02*
X1376740Y589645D01*
G01X1325560Y588622D02*
X1325561Y588621D01*
G01X1325560Y588624D02*
Y588622D01*
G01X1325559Y588627D02*
X1325560Y588624D01*
G01X1324062Y605756D02*
X1324061Y605757D01*
G01X1324062Y605754D02*
Y605756D01*
G01X1324063Y605751D02*
X1324062Y605754D01*
G01X1333434Y588622D02*
X1333435Y588621D01*
G01X1333434Y588624D02*
Y588622D01*
G01X1333433Y588627D02*
X1333434Y588624D01*
G01X1331936Y605756D02*
X1331935Y605757D01*
G01X1331936Y605754D02*
Y605756D01*
G01X1331937Y605751D02*
X1331936Y605754D01*
G01X1347684Y604771D02*
X1347683Y604772D01*
G01X1347684Y604768D02*
Y604771D01*
G01X1347685Y604763D02*
X1347684Y604768D01*
G01X1349182Y589607D02*
X1349183Y589606D01*
G01X1349182Y589610D02*
Y589607D01*
G01X1349181Y589615D02*
X1349182Y589610D01*
G01X1355558Y604771D02*
X1355557Y604772D01*
G01X1355558Y604768D02*
Y604771D01*
G01X1355559Y604763D02*
X1355558Y604768D01*
G01X1357056Y589607D02*
X1357057Y589606D01*
G01X1357056Y589610D02*
Y589607D01*
G01X1357055Y589615D02*
X1357056Y589610D01*
G01X1363432Y604771D02*
X1363431Y604772D01*
G01X1363432Y604768D02*
Y604771D01*
G01X1363433Y604763D02*
X1363432Y604768D01*
G01X1364930Y589607D02*
X1364931Y589606D01*
G01X1364930Y589610D02*
Y589607D01*
G01X1364929Y589615D02*
X1364930Y589610D01*
G01X1371295Y590197D02*
X1371294Y590571D01*
G01X1371298Y589887D02*
X1371295Y590197D01*
G01X1371301Y589680D02*
X1371298Y589887D01*
G01X1371305Y589606D02*
X1371301Y589680D01*
G01X1372815Y604181D02*
X1372816Y603807D01*
G01X1372813Y604491D02*
X1372815Y604181D01*
G01X1372809Y604698D02*
X1372813Y604491D01*
G01X1372805Y604772D02*
X1372809Y604698D01*
G01X1355290Y606485D02*
X1355283Y606538D01*
G01X1355296Y606353D02*
X1355290Y606485D01*
G01X1355301Y606147D02*
X1355296Y606353D01*
G01X1357325Y587893D02*
X1357331Y587840D01*
G01X1357318Y588025D02*
X1357325Y587893D01*
G01X1357313Y588231D02*
X1357318Y588025D01*
G01X1359231Y606485D02*
X1359225Y606538D01*
G01X1359237Y606353D02*
X1359231Y606485D01*
G01X1359243Y606147D02*
X1359237Y606353D01*
G01X1361257Y587893D02*
X1361263Y587840D01*
G01X1361251Y588025D02*
X1361257Y587893D01*
G01X1361245Y588231D02*
X1361251Y588025D01*
G01X1363164Y606485D02*
X1363157Y606538D01*
G01X1363170Y606353D02*
X1363164Y606485D01*
G01X1363175Y606147D02*
X1363170Y606353D01*
G01X1365199Y587893D02*
X1365205Y587840D01*
G01X1365192Y588025D02*
X1365199Y587893D01*
G01X1365187Y588231D02*
X1365192Y588025D01*
G01X1367105Y606485D02*
X1367099Y606538D01*
G01X1367111Y606353D02*
X1367105Y606485D01*
G01X1367117Y606147D02*
X1367111Y606353D01*
G01X1369131Y587893D02*
X1369137Y587840D01*
G01X1369125Y588025D02*
X1369131Y587893D01*
G01X1369119Y588231D02*
X1369125Y588025D01*
G01X1371038Y606485D02*
X1371031Y606538D01*
G01X1371044Y606353D02*
X1371038Y606485D01*
G01X1371049Y606147D02*
X1371044Y606353D01*
G01X1373073Y587893D02*
X1373079Y587840D01*
G01X1373067Y588025D02*
X1373073Y587893D01*
G01X1373061Y588231D02*
X1373067Y588025D01*
G01X1374979Y606485D02*
X1374973Y606538D01*
G01X1374985Y606353D02*
X1374979Y606485D01*
G01X1374991Y606147D02*
X1374985Y606353D01*
G01X1377005Y587893D02*
X1377011Y587840D01*
G01X1376999Y588025D02*
X1377005Y587893D01*
G01X1376993Y588231D02*
X1376999Y588025D01*
G01X1355288Y605511D02*
X1355283Y605553D01*
G01X1355292Y605413D02*
X1355288Y605511D01*
G01X1355297Y605261D02*
X1355292Y605413D01*
G01X1357326Y588867D02*
X1357331Y588825D01*
G01X1357322Y588965D02*
X1357326Y588867D01*
G01X1357317Y589117D02*
X1357322Y588965D01*
G01X1359230Y605511D02*
X1359225Y605553D01*
G01X1359234Y605413D02*
X1359230Y605511D01*
G01X1359238Y605261D02*
X1359234Y605413D01*
G01X1361258Y588867D02*
X1361263Y588825D01*
G01X1361254Y588965D02*
X1361258Y588867D01*
G01X1361250Y589117D02*
X1361254Y588965D01*
G01X1363162Y605511D02*
X1363157Y605553D01*
G01X1363166Y605413D02*
X1363162Y605511D01*
G01X1363171Y605261D02*
X1363166Y605413D01*
G01X1365200Y588867D02*
X1365205Y588825D01*
G01X1365196Y588965D02*
X1365200Y588867D01*
G01X1365192Y589117D02*
X1365196Y588965D01*
G01X1367104Y605511D02*
X1367099Y605553D01*
G01X1367108Y605413D02*
X1367104Y605511D01*
G01X1367112Y605261D02*
X1367108Y605413D01*
G01X1369133Y588867D02*
X1369137Y588825D01*
G01X1369128Y588965D02*
X1369133Y588867D01*
G01X1369124Y589117D02*
X1369128Y588965D01*
G01X1371036Y605511D02*
X1371031Y605553D01*
G01X1371040Y605413D02*
X1371036Y605511D01*
G01X1371045Y605261D02*
X1371040Y605413D01*
G01X1373074Y588867D02*
X1373079Y588825D01*
G01X1373070Y588965D02*
X1373074Y588867D01*
G01X1373066Y589117D02*
X1373070Y588965D01*
G01X1374978Y605511D02*
X1374973Y605553D01*
G01X1374982Y605413D02*
X1374978Y605511D01*
G01X1374986Y605261D02*
X1374982Y605413D01*
G01X1377007Y588867D02*
X1377011Y588825D01*
G01X1377002Y588965D02*
X1377007Y588867D01*
G01X1376998Y589117D02*
X1377002Y588965D01*
G01X1359487Y589645D02*
X1359491Y589615D01*
G01X1359483Y589841D02*
X1359487Y589645D01*
G01X1359480Y590169D02*
X1359483Y589841D01*
G01X1359479Y590571D02*
X1359480Y590169D01*
G01X1361002Y604733D02*
X1360997Y604763D01*
G01X1361006Y604537D02*
X1361002Y604733D01*
G01X1361008Y604209D02*
X1361006Y604537D01*
G01X1361009Y603807D02*
X1361008Y604209D01*
G01X1367361Y589645D02*
X1367365Y589615D01*
G01X1367357Y589841D02*
X1367361Y589645D01*
G01X1367354Y590169D02*
X1367357Y589841D01*
G01X1367353Y590571D02*
X1367354Y590169D01*
G01X1368876Y604733D02*
X1368871Y604763D01*
G01X1368880Y604537D02*
X1368876Y604733D01*
G01X1368882Y604209D02*
X1368880Y604537D01*
G01X1368883Y603807D02*
X1368882Y604209D01*
G01X1375235Y589645D02*
X1375239Y589615D01*
G01X1375231Y589841D02*
X1375235Y589645D01*
G01X1375228Y590169D02*
X1375231Y589841D01*
G01X1375227Y590571D02*
X1375228Y590169D01*
G01X1376750Y604733D02*
X1376745Y604763D01*
G01X1376754Y604537D02*
X1376750Y604733D01*
G01X1376756Y604209D02*
X1376754Y604537D01*
G01X1376758Y603807D02*
X1376756Y604209D01*
G01X1363423Y588770D02*
X1363431Y588621D01*
G01X1363416Y589184D02*
X1363423Y588770D01*
G01X1363411Y589804D02*
X1363416Y589184D01*
G01X1363409Y590552D02*
X1363411Y589804D01*
G01X1363427Y589679D02*
X1363431Y589606D01*
G01X1363424Y589887D02*
X1363427Y589679D01*
G01X1363421Y590200D02*
X1363424Y589887D01*
G01X1363420Y590571D02*
X1363421Y590200D01*
G01X1364935Y604699D02*
X1364931Y604772D01*
G01X1364939Y604491D02*
X1364935Y604699D01*
G01X1364941Y604178D02*
X1364939Y604491D01*
G01X1364942Y603807D02*
X1364941Y604178D01*
G01X1364939Y605608D02*
X1364931Y605757D01*
G01X1364946Y605193D02*
X1364939Y605608D01*
G01X1364951Y604573D02*
X1364946Y605193D01*
G01X1364953Y603826D02*
X1364951Y604573D01*
G01X1371297Y588770D02*
X1371305Y588621D01*
G01X1371290Y589184D02*
X1371297Y588770D01*
G01X1371285Y589804D02*
X1371290Y589184D01*
G01X1371283Y590552D02*
X1371285Y589804D01*
G01X1372813Y605608D02*
X1372805Y605757D01*
G01X1372820Y605193D02*
X1372813Y605608D01*
G01X1372825Y604573D02*
X1372820Y605193D01*
G01X1372827Y603826D02*
X1372825Y604573D01*
G01X1379171Y588770D02*
X1379179Y588621D01*
G01X1379164Y589184D02*
X1379171Y588770D01*
G01X1379159Y589804D02*
X1379164Y589184D01*
G01X1379157Y590552D02*
X1379159Y589804D01*
G01X1380687Y605608D02*
X1380679Y605757D01*
G01X1380694Y605193D02*
X1380687Y605608D01*
G01X1380699Y604573D02*
X1380694Y605193D01*
G01X1380701Y603826D02*
X1380699Y604573D01*
G01X1371301Y604698D02*
X1371305Y604772D01*
G01X1371298Y604491D02*
X1371301Y604698D01*
G01X1371295Y604181D02*
X1371298Y604491D01*
G01X1371294Y603807D02*
X1371295Y604181D01*
G01X1372809Y589680D02*
X1372805Y589606D01*
G01X1372813Y589887D02*
X1372809Y589680D01*
G01X1372815Y590197D02*
X1372813Y589887D01*
G01X1372816Y590571D02*
X1372815Y590197D01*
G01X1379175Y604698D02*
X1379179Y604772D01*
G01X1379172Y604491D02*
X1379175Y604698D01*
G01X1379169Y604181D02*
X1379172Y604491D01*
G01X1379168Y603807D02*
X1379169Y604181D01*
G01X1380683Y589680D02*
X1380679Y589606D01*
G01X1380687Y589887D02*
X1380683Y589680D01*
G01X1380689Y590197D02*
X1380687Y589887D01*
G01X1380690Y590571D02*
X1380689Y590197D01*
G01X1371285Y604573D02*
X1371283Y603826D01*
G01X1371290Y605193D02*
X1371285Y604573D01*
G01X1371297Y605608D02*
X1371290Y605193D01*
G01X1371305Y605757D02*
X1371297Y605608D01*
G01X1372825Y589804D02*
X1372827Y590552D01*
G01X1372820Y589184D02*
X1372825Y589804D01*
G01X1372813Y588770D02*
X1372820Y589184D01*
G01X1372805Y588621D02*
X1372813Y588770D01*
G01X1379159Y604573D02*
X1379157Y603826D01*
G01X1379164Y605193D02*
X1379159Y604573D01*
G01X1379171Y605608D02*
X1379164Y605193D01*
G01X1379179Y605757D02*
X1379171Y605608D01*
G01X1380699Y589804D02*
X1380701Y590552D01*
G01X1380694Y589184D02*
X1380699Y589804D01*
G01X1380687Y588770D02*
X1380694Y589184D01*
G01X1380679Y588621D02*
X1380687Y588770D01*
G01X1387033Y604573D02*
X1387031Y603826D01*
G01X1387038Y605193D02*
X1387033Y604573D01*
G01X1387045Y605608D02*
X1387038Y605193D01*
G01X1387053Y605757D02*
X1387045Y605608D01*
G01X1387043Y604178D02*
X1387042Y603807D01*
G01X1387046Y604491D02*
X1387043Y604178D01*
G01X1387049Y604699D02*
X1387046Y604491D01*
G01X1387053Y604772D02*
X1387049Y604699D01*
G01X1371306Y589607D02*
X1371305Y589606D01*
G01X1371306Y589610D02*
Y589607D01*
G01X1371307Y589617D02*
X1371306Y589610D01*
G01X1372804Y604771D02*
X1372805Y604772D01*
G01X1372804Y604768D02*
Y604771D01*
G01X1372803Y604761D02*
X1372804Y604768D01*
G01X1379180Y589607D02*
X1379179Y589606D01*
G01X1379180Y589610D02*
Y589607D01*
G01X1379181Y589617D02*
X1379180Y589610D01*
G01X1380678Y604771D02*
X1380679Y604772D01*
G01X1380678Y604768D02*
Y604771D01*
G01X1380677Y604761D02*
X1380678Y604768D01*
G01X1374973Y588965D02*
X1374977Y589117D01*
G01X1374968Y588867D02*
X1374973Y588965D01*
G01X1374964Y588825D02*
X1374968Y588867D01*
G01X1377011Y605413D02*
X1377007Y605261D01*
G01X1377016Y605511D02*
X1377011Y605413D01*
G01X1377020Y605553D02*
X1377016Y605511D01*
G01X1378914Y588965D02*
X1378919Y589117D01*
G01X1378910Y588867D02*
X1378914Y588965D01*
G01X1378906Y588825D02*
X1378910Y588867D01*
G01X1380944Y605413D02*
X1380940Y605261D01*
G01X1380948Y605511D02*
X1380944Y605413D01*
G01X1380953Y605553D02*
X1380948Y605511D01*
G01X1382847Y588965D02*
X1382851Y589117D01*
G01X1382842Y588867D02*
X1382847Y588965D01*
G01X1382838Y588825D02*
X1382842Y588867D01*
G01X1384885Y605413D02*
X1384881Y605261D01*
G01X1384890Y605511D02*
X1384885Y605413D01*
G01X1384894Y605553D02*
X1384890Y605511D01*
G01X1386788Y588965D02*
X1386793Y589117D01*
G01X1386784Y588867D02*
X1386788Y588965D01*
G01X1386780Y588825D02*
X1386784Y588867D01*
G01X1377008Y606353D02*
X1377002Y606147D01*
G01X1377014Y606485D02*
X1377008Y606353D01*
G01X1377020Y606538D02*
X1377014Y606485D01*
G01X1374976Y588025D02*
X1374982Y588231D01*
G01X1374970Y587893D02*
X1374976Y588025D01*
G01X1374964Y587840D02*
X1374970Y587893D01*
G01X1380941Y606353D02*
X1380935Y606147D01*
G01X1380947Y606485D02*
X1380941Y606353D01*
G01X1380953Y606538D02*
X1380947Y606485D01*
G01X1378918Y588025D02*
X1378924Y588231D01*
G01X1378912Y587893D02*
X1378918Y588025D01*
G01X1378906Y587840D02*
X1378912Y587893D01*
G01X1384882Y606353D02*
X1384876Y606147D01*
G01X1384888Y606485D02*
X1384882Y606353D01*
G01X1384894Y606538D02*
X1384888Y606485D01*
G01X1382850Y588025D02*
X1382856Y588231D01*
G01X1382844Y587893D02*
X1382850Y588025D01*
G01X1382838Y587840D02*
X1382844Y587893D01*
G01X1386792Y588025D02*
X1386798Y588231D01*
G01X1386786Y587893D02*
X1386792Y588025D01*
G01X1386780Y587840D02*
X1386786Y587893D01*
G01X1383111Y604209D02*
X1383110Y603807D01*
G01X1383114Y604537D02*
X1383111Y604209D01*
G01X1383118Y604733D02*
X1383114Y604537D01*
G01X1383123Y604763D02*
X1383118Y604733D01*
G01X1384621Y590169D02*
X1384622Y590571D01*
G01X1384618Y589841D02*
X1384621Y590169D01*
G01X1384614Y589645D02*
X1384618Y589841D01*
G01X1384610Y589615D02*
X1384614Y589645D01*
G01X1341308Y588622D02*
X1341309Y588621D01*
G01X1341308Y588624D02*
Y588622D01*
G01X1341307Y588627D02*
X1341308Y588624D01*
G01X1339810Y605756D02*
X1339809Y605757D01*
G01X1339810Y605754D02*
Y605756D01*
G01X1339811Y605751D02*
X1339810Y605754D01*
G01X1349182Y588622D02*
X1349183Y588621D01*
G01X1349182Y588624D02*
Y588622D01*
G01X1349181Y588627D02*
X1349182Y588624D01*
G01X1347684Y605756D02*
X1347683Y605757D01*
G01X1347684Y605754D02*
Y605756D01*
G01X1347685Y605751D02*
X1347684Y605754D01*
G01X1357056Y588622D02*
X1357057Y588621D01*
G01X1357056Y588624D02*
Y588622D01*
G01X1357055Y588627D02*
X1357056Y588624D01*
G01X1355558Y605756D02*
X1355557Y605757D01*
G01X1355558Y605754D02*
Y605756D01*
G01X1355559Y605751D02*
X1355558Y605754D01*
G01X1387054Y604771D02*
X1387053Y604772D01*
G01X1387054Y604768D02*
Y604771D01*
G01X1387055Y604763D02*
X1387054Y604768D01*
G01X1379169Y590197D02*
X1379168Y590571D01*
G01X1379172Y589887D02*
X1379169Y590197D01*
G01X1379175Y589680D02*
X1379172Y589887D01*
G01X1379179Y589606D02*
X1379175Y589680D01*
G01X1380689Y604181D02*
X1380690Y603807D01*
G01X1380687Y604491D02*
X1380689Y604181D01*
G01X1380683Y604698D02*
X1380687Y604491D01*
G01X1380679Y604772D02*
X1380683Y604698D01*
G01X1378912Y606485D02*
X1378906Y606538D01*
G01X1378918Y606353D02*
X1378912Y606485D01*
G01X1378924Y606147D02*
X1378918Y606353D01*
G01X1380947Y587893D02*
X1380953Y587840D01*
G01X1380941Y588025D02*
X1380947Y587893D01*
G01X1380935Y588231D02*
X1380941Y588025D01*
G01X1382853Y606485D02*
X1382847Y606538D01*
G01X1382859Y606353D02*
X1382853Y606485D01*
G01X1382865Y606147D02*
X1382859Y606353D01*
G01X1384879Y587893D02*
X1384885Y587840D01*
G01X1384873Y588025D02*
X1384879Y587893D01*
G01X1384867Y588231D02*
X1384873Y588025D01*
G01X1386786Y606485D02*
X1386780Y606538D01*
G01X1386792Y606353D02*
X1386786Y606485D01*
G01X1386798Y606147D02*
X1386792Y606353D01*
G01X1378910Y605511D02*
X1378906Y605553D01*
G01X1378914Y605413D02*
X1378910Y605511D01*
G01X1378919Y605261D02*
X1378914Y605413D01*
G01X1380948Y588867D02*
X1380953Y588825D01*
G01X1380944Y588965D02*
X1380948Y588867D01*
G01X1380940Y589117D02*
X1380944Y588965D01*
G01X1382852Y605511D02*
X1382847Y605553D01*
G01X1382856Y605413D02*
X1382852Y605511D01*
G01X1382860Y605261D02*
X1382856Y605413D01*
G01X1384881Y588867D02*
X1384885Y588825D01*
G01X1384876Y588965D02*
X1384881Y588867D01*
G01X1384872Y589117D02*
X1384876Y588965D01*
G01X1386784Y605511D02*
X1386780Y605553D01*
G01X1386788Y605413D02*
X1386784Y605511D01*
G01X1386793Y605261D02*
X1386788Y605413D01*
G01X1383109Y589645D02*
X1383113Y589615D01*
G01X1383105Y589841D02*
X1383109Y589645D01*
G01X1383102Y590169D02*
X1383105Y589841D01*
G01X1383101Y590571D02*
X1383102Y590169D01*
G01X1384624Y604733D02*
X1384619Y604763D01*
G01X1384628Y604537D02*
X1384624Y604733D01*
G01X1384630Y604209D02*
X1384628Y604537D01*
G01X1384632Y603807D02*
X1384630Y604209D01*
G01X1387045Y588770D02*
X1387053Y588621D01*
G01X1387038Y589184D02*
X1387045Y588770D01*
G01X1387033Y589804D02*
X1387038Y589184D01*
G01X1387031Y590552D02*
X1387033Y589804D01*
G01X1387049Y589679D02*
X1387053Y589606D01*
G01X1387046Y589887D02*
X1387049Y589679D01*
G01X1387043Y590200D02*
X1387046Y589887D01*
G01X1387042Y590571D02*
X1387043Y590200D01*
G01X1364930Y588622D02*
X1364931Y588621D01*
G01X1364930Y588624D02*
Y588622D01*
G01X1364929Y588627D02*
X1364930Y588624D01*
G01X1363432Y605756D02*
X1363431Y605757D01*
G01X1363432Y605754D02*
Y605756D01*
G01X1363433Y605751D02*
X1363432Y605754D01*
G01X1372804Y588622D02*
X1372805Y588621D01*
G01X1372804Y588624D02*
Y588622D01*
G01X1372803Y588627D02*
X1372804Y588624D01*
G01X1371306Y605756D02*
X1371305Y605757D01*
G01X1371307Y605754D02*
X1371306Y605756D01*
G01X1371307Y605751D02*
Y605754D01*
G01X1380678Y588622D02*
X1380679Y588621D01*
G01X1380678Y588624D02*
Y588622D01*
G01X1380677Y588627D02*
X1380678Y588624D01*
G01X1379180Y605756D02*
X1379179Y605757D01*
G01X1379181Y605754D02*
X1379180Y605756D01*
G01X1379181Y605751D02*
Y605754D01*
G01X1386750Y588823D02*
X1386734D01*
G01X1386765Y588824D02*
X1386750Y588823D01*
G01X1386780Y588825D02*
X1386765Y588824D01*
G01X1382808Y588823D02*
X1382793D01*
G01X1382823Y588824D02*
X1382808Y588823D01*
G01X1382838Y588825D02*
X1382823Y588824D01*
G01X1378876Y588823D02*
X1378860D01*
G01X1378890Y588824D02*
X1378876Y588823D01*
G01X1378906Y588825D02*
X1378890Y588824D01*
G01X1371001Y588823D02*
X1370986D01*
G01X1371016Y588824D02*
X1371001Y588823D01*
G01X1371031Y588825D02*
X1371016Y588824D01*
G01X1386750Y587839D02*
X1386734D01*
G01X1386765D02*
X1386750D01*
G01X1386780Y587840D02*
X1386765Y587839D01*
G01X1382808D02*
X1382793D01*
G01X1382823D02*
X1382808D01*
G01X1382838Y587840D02*
X1382823Y587839D01*
G01X1374934D02*
X1374919D01*
G01X1374949D02*
X1374934D01*
G01X1374964Y587840D02*
X1374949Y587839D01*
G01X1372804Y589610D02*
X1372803Y589617D01*
G01X1372804Y589607D02*
Y589610D01*
G01X1372805Y589606D02*
X1372804Y589607D01*
G01X1371306Y604768D02*
X1371307Y604761D01*
G01X1371306Y604771D02*
Y604768D01*
G01X1371305Y604772D02*
X1371306Y604771D01*
G01X1380678Y589610D02*
X1380677Y589617D01*
G01X1380678Y589607D02*
Y589610D01*
G01X1380679Y589606D02*
X1380678Y589607D01*
G01X1387054Y605756D02*
X1387053Y605757D01*
G01X1387055Y605754D02*
X1387054Y605756D01*
G01X1387055Y605751D02*
Y605754D01*
G01X1363127Y588823D02*
X1363112D01*
G01X1363142Y588824D02*
X1363127Y588823D01*
G01X1363157Y588825D02*
X1363142Y588824D01*
G01X1359186Y588823D02*
X1359171D01*
G01X1359201Y588824D02*
X1359186Y588823D01*
G01X1359216Y588825D02*
X1359201Y588824D01*
G01X1355253Y588823D02*
X1355238D01*
G01X1355268Y588824D02*
X1355253Y588823D01*
G01X1355283Y588825D02*
X1355268Y588824D01*
G01X1351312Y588823D02*
X1351297D01*
G01X1351327Y588824D02*
X1351312Y588823D01*
G01X1351342Y588825D02*
X1351327Y588824D01*
G01X1347379Y588823D02*
X1347364D01*
G01X1347394Y588824D02*
X1347379Y588823D01*
G01X1347409Y588825D02*
X1347394Y588824D01*
G01X1343438Y588823D02*
X1343423D01*
G01X1343453Y588824D02*
X1343438Y588823D01*
G01X1343468Y588825D02*
X1343453Y588824D01*
G01X1339505Y588823D02*
X1339490D01*
G01X1339520Y588824D02*
X1339505Y588823D01*
G01X1339535Y588825D02*
X1339520Y588824D01*
G01X1335564Y588823D02*
X1335549D01*
G01X1335579Y588824D02*
X1335564Y588823D01*
G01X1335594Y588825D02*
X1335579Y588824D01*
G01X1331631Y588823D02*
X1331616D01*
G01X1331646Y588824D02*
X1331631Y588823D01*
G01X1331661Y588825D02*
X1331646Y588824D01*
G01X1327690Y588823D02*
X1327675D01*
G01X1327705Y588824D02*
X1327690Y588823D01*
G01X1327720Y588825D02*
X1327705Y588824D01*
G01X1323757Y588823D02*
X1323742D01*
G01X1323772Y588824D02*
X1323757Y588823D01*
G01X1323787Y588825D02*
X1323772Y588824D01*
G01X1380983Y605555D02*
X1380998D01*
G01X1380968Y605554D02*
X1380983Y605555D01*
G01X1380953Y605553D02*
X1380968Y605554D01*
G01X1377050Y605555D02*
X1377065D01*
G01X1377035Y605554D02*
X1377050Y605555D01*
G01X1377020Y605553D02*
X1377035Y605554D01*
G01X1373109Y605555D02*
X1373124D01*
G01X1373094Y605554D02*
X1373109Y605555D01*
G01X1373079Y605553D02*
X1373094Y605554D01*
G01X1369176Y605555D02*
X1369191D01*
G01X1369161Y605554D02*
X1369176Y605555D01*
G01X1369146Y605553D02*
X1369161Y605554D01*
G01X1365235Y605555D02*
X1365250D01*
G01X1365220Y605554D02*
X1365235Y605555D01*
G01X1365205Y605553D02*
X1365220Y605554D01*
G01X1361302Y605555D02*
X1361317D01*
G01X1361287Y605554D02*
X1361302Y605555D01*
G01X1361272Y605553D02*
X1361287Y605554D01*
G01X1357361Y605555D02*
X1357376D01*
G01X1357346Y605554D02*
X1357361Y605555D01*
G01X1357331Y605553D02*
X1357346Y605554D01*
G01X1349487Y605555D02*
X1349502D01*
G01X1349472Y605554D02*
X1349487Y605555D01*
G01X1349457Y605553D02*
X1349472Y605554D01*
G01X1341613Y605555D02*
X1341628D01*
G01X1341598Y605554D02*
X1341613Y605555D01*
G01X1341583Y605553D02*
X1341598Y605554D01*
G01X1337680Y605555D02*
X1337695D01*
G01X1337665Y605554D02*
X1337680Y605555D01*
G01X1337650Y605553D02*
X1337665Y605554D01*
G01X1333739Y605555D02*
X1333754D01*
G01X1333724Y605554D02*
X1333739Y605555D01*
G01X1333709Y605553D02*
X1333724Y605554D01*
G01X1329806Y605555D02*
X1329821D01*
G01X1329791Y605554D02*
X1329806Y605555D01*
G01X1329776Y605553D02*
X1329791Y605554D01*
G01X1325865Y605555D02*
X1325880D01*
G01X1325850Y605554D02*
X1325865Y605555D01*
G01X1325835Y605553D02*
X1325850Y605554D01*
G01X1367060Y587839D02*
X1367045D01*
G01X1367075D02*
X1367060D01*
G01X1367090Y587840D02*
X1367075Y587839D01*
G01X1363127D02*
X1363112D01*
G01X1363142D02*
X1363127D01*
G01X1363157Y587840D02*
X1363142Y587839D01*
G01X1359186D02*
X1359171D01*
G01X1359201D02*
X1359186D01*
G01X1359216Y587840D02*
X1359201Y587839D01*
G01X1355253D02*
X1355238D01*
G01X1355268D02*
X1355253D01*
G01X1355283Y587840D02*
X1355268Y587839D01*
G01X1351312D02*
X1351297D01*
G01X1351327D02*
X1351312D01*
G01X1351342Y587840D02*
X1351327Y587839D01*
G01X1347379D02*
X1347364D01*
G01X1347394D02*
X1347379D01*
G01X1347409Y587840D02*
X1347394Y587839D01*
G01X1343438D02*
X1343423D01*
G01X1343453D02*
X1343438D01*
G01X1343468Y587840D02*
X1343453Y587839D01*
G01X1339505D02*
X1339490D01*
G01X1339520D02*
X1339505D01*
G01X1339535Y587840D02*
X1339520Y587839D01*
G01X1335564D02*
X1335549D01*
G01X1335579D02*
X1335564D01*
G01X1335594Y587840D02*
X1335579Y587839D01*
G01X1331631D02*
X1331616D01*
G01X1331646D02*
X1331631D01*
G01X1331661Y587840D02*
X1331646Y587839D01*
G01X1327690D02*
X1327675D01*
G01X1327705D02*
X1327690D01*
G01X1327720Y587840D02*
X1327705Y587839D01*
G01X1323757D02*
X1323742D01*
G01X1323772D02*
X1323757D01*
G01X1323787Y587840D02*
X1323772Y587839D01*
G01X1384924Y606539D02*
X1384939D01*
G01X1384909D02*
X1384924D01*
G01X1384894Y606538D02*
X1384909Y606539D01*
G01X1369176D02*
X1369191D01*
G01X1369161D02*
X1369176D01*
G01X1369146Y606538D02*
X1369161Y606539D01*
G01X1365235D02*
X1365250D01*
G01X1365220D02*
X1365235D01*
G01X1365205Y606538D02*
X1365220Y606539D01*
G01X1361302D02*
X1361317D01*
G01X1361287D02*
X1361302D01*
G01X1361272Y606538D02*
X1361287Y606539D01*
G01X1357361D02*
X1357376D01*
G01X1357346D02*
X1357361D01*
G01X1357331Y606538D02*
X1357346Y606539D01*
G01X1353428D02*
X1353443D01*
G01X1353413D02*
X1353428D01*
G01X1353398Y606538D02*
X1353413Y606539D01*
G01X1349487D02*
X1349502D01*
G01X1349472D02*
X1349487D01*
G01X1349457Y606538D02*
X1349472Y606539D01*
G01X1345554D02*
X1345569D01*
G01X1345539D02*
X1345554D01*
G01X1345524Y606538D02*
X1345539Y606539D01*
G01X1341613D02*
X1341628D01*
G01X1341598D02*
X1341613D01*
G01X1341583Y606538D02*
X1341598Y606539D01*
G01X1337680D02*
X1337695D01*
G01X1337665D02*
X1337680D01*
G01X1337650Y606538D02*
X1337665Y606539D01*
G01X1333739D02*
X1333754D01*
G01X1333724D02*
X1333739D01*
G01X1333709Y606538D02*
X1333724Y606539D01*
G01X1329806D02*
X1329821D01*
G01X1329791D02*
X1329806D01*
G01X1329776Y606538D02*
X1329791Y606539D01*
G01X1325865D02*
X1325880D01*
G01X1325850D02*
X1325865D01*
G01X1325835Y606538D02*
X1325850Y606539D01*
G01X1321932D02*
X1321947D01*
G01X1321917D02*
X1321932D01*
G01X1321902Y606538D02*
X1321917Y606539D01*
G01X1321908Y587839D02*
X1321893Y587840D01*
G01X1321923Y587839D02*
X1321908D01*
G01X1321938D02*
X1321923D01*
G01X1325850D02*
X1325835Y587840D01*
G01X1325865Y587839D02*
X1325850D01*
G01X1325880D02*
X1325865D01*
G01X1329782D02*
X1329767Y587840D01*
G01X1329797Y587839D02*
X1329782D01*
G01X1329812D02*
X1329797D01*
G01X1333724D02*
X1333709Y587840D01*
G01X1333739Y587839D02*
X1333724D01*
G01X1333754D02*
X1333739D01*
G01X1337656D02*
X1337641Y587840D01*
G01X1337671Y587839D02*
X1337656D01*
G01X1337686D02*
X1337671D01*
G01X1341598D02*
X1341583Y587840D01*
G01X1341613Y587839D02*
X1341598D01*
G01X1341628D02*
X1341613D01*
G01X1345530D02*
X1345515Y587840D01*
G01X1345545Y587839D02*
X1345530D01*
G01X1345560D02*
X1345545D01*
G01X1349472D02*
X1349457Y587840D01*
G01X1349487Y587839D02*
X1349472D01*
G01X1349502D02*
X1349487D01*
G01X1353404D02*
X1353389Y587840D01*
G01X1353419Y587839D02*
X1353404D01*
G01X1353434D02*
X1353419D01*
G01X1357346D02*
X1357331Y587840D01*
G01X1357361Y587839D02*
X1357346D01*
G01X1357376D02*
X1357361D01*
G01X1361278D02*
X1361263Y587840D01*
G01X1361293Y587839D02*
X1361278D01*
G01X1361308D02*
X1361293D01*
G01X1365220D02*
X1365205Y587840D01*
G01X1365235Y587839D02*
X1365220D01*
G01X1365250D02*
X1365235D01*
G01X1369152D02*
X1369137Y587840D01*
G01X1369167Y587839D02*
X1369152D01*
G01X1369182D02*
X1369167D01*
G01X1373094D02*
X1373079Y587840D01*
G01X1373109Y587839D02*
X1373094D01*
G01X1373124D02*
X1373109D01*
G01X1377026D02*
X1377011Y587840D01*
G01X1377041Y587839D02*
X1377026D01*
G01X1377056D02*
X1377041D01*
G01X1380968D02*
X1380953Y587840D01*
G01X1380983Y587839D02*
X1380968D01*
G01X1380998D02*
X1380983D01*
G01X1384900D02*
X1384885Y587840D01*
G01X1384915Y587839D02*
X1384900D01*
G01X1384930D02*
X1384915D01*
G01X1323772Y606539D02*
X1323787Y606538D01*
G01X1323757Y606539D02*
X1323772D01*
G01X1323742D02*
X1323757D01*
G01X1327714D02*
X1327729Y606538D01*
G01X1327699Y606539D02*
X1327714D01*
G01X1327684D02*
X1327699D01*
G01X1331646D02*
X1331661Y606538D01*
G01X1331631Y606539D02*
X1331646D01*
G01X1331616D02*
X1331631D01*
G01X1335588D02*
X1335603Y606538D01*
G01X1335573Y606539D02*
X1335588D01*
G01X1335558D02*
X1335573D01*
G01X1339520D02*
X1339535Y606538D01*
G01X1339505Y606539D02*
X1339520D01*
G01X1339490D02*
X1339505D01*
G01X1343462D02*
X1343477Y606538D01*
G01X1343447Y606539D02*
X1343462D01*
G01X1343432D02*
X1343447D01*
G01X1347394D02*
X1347409Y606538D01*
G01X1347379Y606539D02*
X1347394D01*
G01X1347364D02*
X1347379D01*
G01X1351336D02*
X1351351Y606538D01*
G01X1351321Y606539D02*
X1351336D01*
G01X1351306D02*
X1351321D01*
G01X1355268D02*
X1355283Y606538D01*
G01X1355253Y606539D02*
X1355268D01*
G01X1355238D02*
X1355253D01*
G01X1359210D02*
X1359225Y606538D01*
G01X1359195Y606539D02*
X1359210D01*
G01X1359180D02*
X1359195D01*
G01X1363142D02*
X1363157Y606538D01*
G01X1363127Y606539D02*
X1363142D01*
G01X1363112D02*
X1363127D01*
G01X1367084D02*
X1367099Y606538D01*
G01X1367069Y606539D02*
X1367084D01*
G01X1367054D02*
X1367069D01*
G01X1371016D02*
X1371031Y606538D01*
G01X1371001Y606539D02*
X1371016D01*
G01X1370986D02*
X1371001D01*
G01X1374958D02*
X1374973Y606538D01*
G01X1374943Y606539D02*
X1374958D01*
G01X1374928D02*
X1374943D01*
G01X1378890D02*
X1378906Y606538D01*
G01X1378875Y606539D02*
X1378890D01*
G01X1378860D02*
X1378875D01*
G01X1382832D02*
X1382847Y606538D01*
G01X1382817Y606539D02*
X1382832D01*
G01X1382802D02*
X1382817D01*
G01X1386765D02*
X1386780Y606538D01*
G01X1386750Y606539D02*
X1386765D01*
G01X1386734D02*
X1386750D01*
G01X1321908Y588824D02*
X1321893Y588825D01*
G01X1321923Y588823D02*
X1321908Y588824D01*
G01X1321938Y588823D02*
X1321923D01*
G01X1325850Y588824D02*
X1325835Y588825D01*
G01X1325865Y588823D02*
X1325850Y588824D01*
G01X1325880Y588823D02*
X1325865D01*
G01X1329782Y588824D02*
X1329767Y588825D01*
G01X1329797Y588823D02*
X1329782Y588824D01*
G01X1329812Y588823D02*
X1329797D01*
G01X1333724Y588824D02*
X1333709Y588825D01*
G01X1333739Y588823D02*
X1333724Y588824D01*
G01X1333754Y588823D02*
X1333739D01*
G01X1337656Y588824D02*
X1337641Y588825D01*
G01X1337671Y588823D02*
X1337656Y588824D01*
G01X1337686Y588823D02*
X1337671D01*
G01X1341598Y588824D02*
X1341583Y588825D01*
G01X1341613Y588823D02*
X1341598Y588824D01*
G01X1341628Y588823D02*
X1341613D01*
G01X1345530Y588824D02*
X1345515Y588825D01*
G01X1345545Y588823D02*
X1345530Y588824D01*
G01X1345560Y588823D02*
X1345545D01*
G01X1349472Y588824D02*
X1349457Y588825D01*
G01X1349487Y588823D02*
X1349472Y588824D01*
G01X1349502Y588823D02*
X1349487D01*
G01X1353404Y588824D02*
X1353389Y588825D01*
G01X1353419Y588823D02*
X1353404Y588824D01*
G01X1353434Y588823D02*
X1353419D01*
G01X1357346Y588824D02*
X1357331Y588825D01*
G01X1357361Y588823D02*
X1357346Y588824D01*
G01X1357376Y588823D02*
X1357361D01*
G01X1361278Y588824D02*
X1361263Y588825D01*
G01X1361293Y588823D02*
X1361278Y588824D01*
G01X1361308Y588823D02*
X1361293D01*
G01X1365220Y588824D02*
X1365205Y588825D01*
G01X1365235Y588823D02*
X1365220Y588824D01*
G01X1365250Y588823D02*
X1365235D01*
G01X1373094Y588824D02*
X1373079Y588825D01*
G01X1373109Y588823D02*
X1373094Y588824D01*
G01X1373124Y588823D02*
X1373109D01*
G01X1380968Y588824D02*
X1380953Y588825D01*
G01X1380983Y588823D02*
X1380968Y588824D01*
G01X1380998Y588823D02*
X1380983D01*
G01X1384900Y588824D02*
X1384885Y588825D01*
G01X1384915Y588823D02*
X1384900Y588824D01*
G01X1384930Y588823D02*
X1384915D01*
G01X1323772Y605554D02*
X1323787Y605553D01*
G01X1323757Y605555D02*
X1323772Y605554D01*
G01X1323742Y605555D02*
X1323757D01*
G01X1331646Y605554D02*
X1331661Y605553D01*
G01X1331631Y605555D02*
X1331646Y605554D01*
G01X1331616Y605555D02*
X1331631D01*
G01X1339520Y605554D02*
X1339535Y605553D01*
G01X1339505Y605555D02*
X1339520Y605554D01*
G01X1339490Y605555D02*
X1339505D01*
G01X1343462Y605554D02*
X1343477Y605553D01*
G01X1343447Y605555D02*
X1343462Y605554D01*
G01X1343432Y605555D02*
X1343447D01*
G01X1347394Y605554D02*
X1347409Y605553D01*
G01X1347379Y605555D02*
X1347394Y605554D01*
G01X1347364Y605555D02*
X1347379D01*
G01X1351336Y605554D02*
X1351351Y605553D01*
G01X1351321Y605555D02*
X1351336Y605554D01*
G01X1351306Y605555D02*
X1351321D01*
G01X1355268Y605554D02*
X1355283Y605553D01*
G01X1355253Y605555D02*
X1355268Y605554D01*
G01X1355238Y605555D02*
X1355253D01*
G01X1363142Y605554D02*
X1363157Y605553D01*
G01X1363127Y605555D02*
X1363142Y605554D01*
G01X1363112Y605555D02*
X1363127D01*
G01X1367084Y605554D02*
X1367099Y605553D01*
G01X1367069Y605555D02*
X1367084Y605554D01*
G01X1367054Y605555D02*
X1367069D01*
G01X1371016Y605554D02*
X1371031Y605553D01*
G01X1371001Y605555D02*
X1371016Y605554D01*
G01X1370986Y605555D02*
X1371001D01*
G01X1374958Y605554D02*
X1374973Y605553D01*
G01X1374943Y605555D02*
X1374958Y605554D01*
G01X1374928Y605555D02*
X1374943D01*
G01X1378890Y605554D02*
X1378906Y605553D01*
G01X1378875Y605555D02*
X1378890Y605554D01*
G01X1378860Y605555D02*
X1378875D01*
G01X1382832Y605554D02*
X1382847Y605553D01*
G01X1382817Y605555D02*
X1382832Y605554D01*
G01X1382802Y605555D02*
X1382817D01*
G01X1386765Y605554D02*
X1386780Y605553D01*
G01X1386750Y605555D02*
X1386765Y605554D01*
G01X1386734Y605555D02*
X1386750D01*
G01X1369167Y588823D02*
X1369182D01*
G01X1369152Y588824D02*
X1369167Y588823D01*
G01X1369137Y588825D02*
X1369152Y588824D01*
G01X1377041Y588823D02*
X1377056D01*
G01X1377026Y588824D02*
X1377041Y588823D01*
G01X1377011Y588825D02*
X1377026Y588824D01*
G01X1327699Y605555D02*
X1327684D01*
G01X1327714Y605554D02*
X1327699Y605555D01*
G01X1327729Y605553D02*
X1327714Y605554D01*
G01X1335573Y605555D02*
X1335558D01*
G01X1335588Y605554D02*
X1335573Y605555D01*
G01X1335603Y605553D02*
X1335588Y605554D01*
G01X1359195Y605555D02*
X1359180D01*
G01X1359210Y605554D02*
X1359195Y605555D01*
G01X1359225Y605553D02*
X1359210Y605554D01*
G01X1379180Y604768D02*
X1379181Y604761D01*
G01X1379180Y604771D02*
Y604768D01*
G01X1379179Y604772D02*
X1379180Y604771D01*
G01X1387067Y605738D02*
X1387320Y605368D01*
G01X1325992Y610476D02*
X1323630D01*
G01X1329929D02*
X1327567D01*
G01X1333866D02*
X1331504D01*
G01X1337803D02*
X1335441D01*
G01X1341740D02*
X1339378D01*
G01X1345677D02*
X1343315D01*
G01X1349614D02*
X1347252D01*
G01X1353551D02*
X1351189D01*
G01X1357488D02*
X1355126D01*
G01X1361425D02*
X1359063D01*
G01X1365362D02*
X1363000D01*
G01X1369299D02*
X1366937D01*
G01X1373236D02*
X1370874D01*
G01X1377173D02*
X1374811D01*
G01X1381110D02*
X1378748D01*
G01X1385047D02*
X1382685D01*
G01X1388984D02*
X1386622D01*
G01X1325480Y609492D02*
X1324142D01*
G01X1333354D02*
X1332016D01*
G01X1341228D02*
X1339890D01*
G01X1349102D02*
X1347764D01*
G01X1356976D02*
X1355638D01*
G01X1364850D02*
X1363512D01*
G01X1372724D02*
X1371386D01*
G01X1380598D02*
X1379260D01*
G01X1388472D02*
X1387134D01*
G01X1386976Y609394D02*
X1388630D01*
G01X1379102D02*
X1380756D01*
G01X1371228D02*
X1372882D01*
G01X1363354D02*
X1365008D01*
G01X1355480D02*
X1357134D01*
G01X1347606D02*
X1349260D01*
G01X1339732D02*
X1341386D01*
G01X1331858D02*
X1333512D01*
G01X1323984D02*
X1325638D01*
G01X1325992Y609295D02*
X1323630D01*
G01X1329929D02*
X1327567D01*
G01X1333866D02*
X1331504D01*
G01X1337803D02*
X1335441D01*
G01X1341740D02*
X1339378D01*
G01X1345677D02*
X1343315D01*
G01X1349614D02*
X1347252D01*
G01X1353551D02*
X1351189D01*
G01X1357488D02*
X1355126D01*
G01X1361425D02*
X1359063D01*
G01X1365362D02*
X1363000D01*
G01X1369299D02*
X1366937D01*
G01X1373236D02*
X1370874D01*
G01X1377173D02*
X1374811D01*
G01X1381110D02*
X1378748D01*
G01X1385047D02*
X1382685D01*
G01X1388984D02*
X1386622D01*
G01X1387275Y604441D02*
X1387054Y604763D01*
G01X1383134Y605738D02*
X1383388Y605368D01*
G01X1383343Y604441D02*
X1383121Y604763D01*
G01X1379446Y605368D02*
X1379193Y605738D01*
G01X1379181Y604760D02*
X1379401Y604441D01*
G01X1375514Y605368D02*
X1375260Y605738D01*
G01X1375469Y604441D02*
X1375247Y604763D01*
G01X1384390Y589937D02*
X1384611Y589615D01*
G01X1384598Y588640D02*
X1384344Y589010D01*
G01X1371572Y605368D02*
X1371319Y605738D01*
G01X1371307Y604760D02*
X1371527Y604441D01*
G01X1380677Y589618D02*
X1380457Y589937D01*
G01X1380412Y589010D02*
X1380666Y588640D01*
G01X1367640Y605368D02*
X1367386Y605738D01*
G01X1367594Y604441D02*
X1367373Y604763D01*
G01X1376516Y589937D02*
X1376737Y589615D01*
G01X1376470Y589010D02*
X1376724Y588640D01*
G01X1363445Y605738D02*
X1363698Y605368D01*
G01X1363653Y604441D02*
X1363431Y604763D01*
G01X1372803Y589618D02*
X1372583Y589937D01*
G01X1372538Y589010D02*
X1372792Y588640D01*
G01X1359512Y605738D02*
X1359766Y605368D01*
G01X1359720Y604441D02*
X1359499Y604763D01*
G01X1368642Y589937D02*
X1368863Y589615D01*
G01X1368596Y589010D02*
X1368850Y588640D01*
G01X1325638Y608902D02*
X1323984D01*
G01X1333512D02*
X1331858D01*
G01X1341386D02*
X1339732D01*
G01X1349260D02*
X1347606D01*
G01X1357134D02*
X1355480D01*
G01X1365008D02*
X1363354D01*
G01X1372882D02*
X1371228D01*
G01X1380756D02*
X1379102D01*
G01X1388630D02*
X1386976D01*
G01X1326228Y608035D02*
X1323394D01*
G01X1330165D02*
X1327331D01*
G01X1334102D02*
X1331268D01*
G01X1338039D02*
X1335205D01*
G01X1341976D02*
X1339142D01*
G01X1345913D02*
X1343079D01*
G01X1349850D02*
X1347016D01*
G01X1353787D02*
X1350953D01*
G01X1357724D02*
X1354890D01*
G01X1361661D02*
X1358827D01*
G01X1365598D02*
X1362764D01*
G01X1369535D02*
X1366701D01*
G01X1373472D02*
X1370638D01*
G01X1377409D02*
X1374575D01*
G01X1381346D02*
X1378512D01*
G01X1385283D02*
X1382449D01*
G01X1389220D02*
X1386386D01*
G01X1325638Y607130D02*
X1323984D01*
G01X1333512D02*
X1331858D01*
G01X1341386D02*
X1339732D01*
G01X1349260D02*
X1347606D01*
G01X1357134D02*
X1355480D01*
G01X1365008D02*
X1363354D01*
G01X1372882D02*
X1371228D01*
G01X1380756D02*
X1379102D01*
G01X1388630D02*
X1386976D01*
G01Y606638D02*
X1388630D01*
G01X1379102D02*
X1380756D01*
G01X1371228D02*
X1372882D01*
G01X1363354D02*
X1365008D01*
G01X1355480D02*
X1357134D01*
G01X1347606D02*
X1349260D01*
G01X1339732D02*
X1341386D01*
G01X1331858D02*
X1333512D01*
G01X1323984D02*
X1325638D01*
G01X1326228Y606539D02*
X1323394D01*
G01X1330165D02*
X1327331D01*
G01X1334102D02*
X1331268D01*
G01X1338039D02*
X1335205D01*
G01X1341976D02*
X1339142D01*
G01X1345913D02*
X1343079D01*
G01X1349850D02*
X1347016D01*
G01X1353787D02*
X1350953D01*
G01X1357724D02*
X1354890D01*
G01X1361661D02*
X1358827D01*
G01X1365598D02*
X1362764D01*
G01X1369535D02*
X1366701D01*
G01X1373472D02*
X1370638D01*
G01X1377409D02*
X1374575D01*
G01X1381346D02*
X1378512D01*
G01X1385283D02*
X1382449D01*
G01X1389220D02*
X1386386D01*
G01Y606382D02*
X1386976D01*
G01X1384693D02*
X1385283D01*
G01X1382449D02*
X1383039D01*
G01X1380756D02*
X1381346D01*
G01X1378512D02*
X1379102D01*
G01X1376819D02*
X1377409D01*
G01X1374575D02*
X1375165D01*
G01X1372882D02*
X1373472D01*
G01X1370638D02*
X1371228D01*
G01X1368945D02*
X1369535D01*
G01X1366701D02*
X1367291D01*
G01X1365008D02*
X1365598D01*
G01X1362764D02*
X1363354D01*
G01X1361071D02*
X1361661D01*
G01X1358827D02*
X1359417D01*
G01X1357134D02*
X1357724D01*
G01X1354890D02*
X1355480D01*
G01X1353197D02*
X1353787D01*
G01X1350953D02*
X1351543D01*
G01X1349260D02*
X1349850D01*
G01X1347016D02*
X1347606D01*
G01X1345323D02*
X1345913D01*
G01X1343079D02*
X1343669D01*
G01X1341386D02*
X1341976D01*
G01X1339142D02*
X1339732D01*
G01X1337449D02*
X1338039D01*
G01X1335205D02*
X1335795D01*
G01X1333512D02*
X1334102D01*
G01X1331268D02*
X1331858D01*
G01X1329575D02*
X1330165D01*
G01X1327331D02*
X1327921D01*
G01X1325638D02*
X1326228D01*
G01X1323394D02*
X1323984D01*
G01X1321701D02*
X1322291D01*
G01X1386798Y606147D02*
X1388809D01*
G01X1382865D02*
X1384876D01*
G01X1378924D02*
X1380935D01*
G01X1374991D02*
X1377002D01*
G01X1371049D02*
X1373061D01*
G01X1367117D02*
X1369128D01*
G01X1363175D02*
X1365187D01*
G01X1359243D02*
X1361254D01*
G01X1355301D02*
X1357313D01*
G01X1351369D02*
X1353380D01*
G01X1347427D02*
X1349439D01*
G01X1343495D02*
X1345506D01*
G01X1339553D02*
X1341565D01*
G01X1335621D02*
X1337632D01*
G01X1331679D02*
X1333691D01*
G01X1327747D02*
X1329758D01*
G01X1323805D02*
X1325817D01*
G01X1325561Y605757D02*
X1324061D01*
G01X1329502D02*
X1328003D01*
G01X1333435D02*
X1331935D01*
G01X1337376D02*
X1335877D01*
G01X1341309D02*
X1339809D01*
G01X1345250D02*
X1343751D01*
G01X1349183D02*
X1347683D01*
G01X1353124D02*
X1351625D01*
G01X1357057D02*
X1355557D01*
G01X1360998D02*
X1359499D01*
G01X1364931D02*
X1363431D01*
G01X1368872D02*
X1367373D01*
G01X1372805D02*
X1371305D01*
G01X1376747D02*
X1375247D01*
G01X1380679D02*
X1379179D01*
G01X1384621D02*
X1383121D01*
G01X1388553D02*
X1387053D01*
G01X1387067Y605738D02*
X1388540D01*
G01X1383134D02*
X1384607D01*
G01X1379193D02*
X1380666D01*
G01X1375260D02*
X1376733D01*
G01X1371319D02*
X1372792D01*
G01X1367386D02*
X1368859D01*
G01X1363445D02*
X1364918D01*
G01X1359512D02*
X1360985D01*
G01X1355571D02*
X1357044D01*
G01X1351638D02*
X1353111D01*
G01X1347697D02*
X1349170D01*
G01X1343764D02*
X1345237D01*
G01X1339823D02*
X1341296D01*
G01X1335890D02*
X1337363D01*
G01X1331949D02*
X1333422D01*
G01X1328016D02*
X1329489D01*
G01X1324075D02*
X1325548D01*
G01X1322291Y605713D02*
X1321701D01*
G01X1323984D02*
X1323394D01*
G01X1326228D02*
X1325638D01*
G01X1327921D02*
X1327331D01*
G01X1330165D02*
X1329575D01*
G01X1331858D02*
X1331268D01*
G01X1334102D02*
X1333512D01*
G01X1335795D02*
X1335205D01*
G01X1338039D02*
X1337449D01*
G01X1339732D02*
X1339142D01*
G01X1341976D02*
X1341386D01*
G01X1343669D02*
X1343079D01*
G01X1345913D02*
X1345323D01*
G01X1347606D02*
X1347016D01*
G01X1349850D02*
X1349260D01*
G01X1351543D02*
X1350953D01*
G01X1353787D02*
X1353197D01*
G01X1355480D02*
X1354890D01*
G01X1357724D02*
X1357134D01*
G01X1359417D02*
X1358827D01*
G01X1361661D02*
X1361071D01*
G01X1363354D02*
X1362764D01*
G01X1365598D02*
X1365008D01*
G01X1367291D02*
X1366701D01*
G01X1369535D02*
X1368945D01*
G01X1371228D02*
X1370638D01*
G01X1373472D02*
X1372882D01*
G01X1375165D02*
X1374575D01*
G01X1377409D02*
X1376819D01*
G01X1379102D02*
X1378512D01*
G01X1381346D02*
X1380756D01*
G01X1383039D02*
X1382449D01*
G01X1385283D02*
X1384693D01*
G01X1386976D02*
X1386386D01*
G01Y605555D02*
X1389220D01*
G01X1382449D02*
X1385283D01*
G01X1378512D02*
X1381346D01*
G01X1374575D02*
X1377409D01*
G01X1370638D02*
X1373472D01*
G01X1366701D02*
X1369535D01*
G01X1362764D02*
X1365598D01*
G01X1354890D02*
X1357724D01*
G01X1350953D02*
X1353787D01*
G01X1347016D02*
X1349850D01*
G01X1343079D02*
X1345913D01*
G01X1339142D02*
X1341976D01*
G01X1335205D02*
X1338039D01*
G01X1331268D02*
X1334102D01*
G01X1323394D02*
X1326228D01*
G01X1330165D02*
X1327331D01*
G01X1361661D02*
X1358827D01*
G01X1329575Y605457D02*
X1327921D01*
G01X1337449D02*
X1335795D01*
G01X1345323D02*
X1343669D01*
G01X1353197D02*
X1351543D01*
G01X1361071D02*
X1359417D01*
G01X1368945D02*
X1367291D01*
G01X1376819D02*
X1375165D01*
G01X1384693D02*
X1383039D01*
G01X1321361Y605368D02*
X1320396D01*
G01X1325294D02*
X1324328D01*
G01X1329235D02*
X1328270D01*
G01X1333168D02*
X1332202D01*
G01X1337109D02*
X1336144D01*
G01X1341042D02*
X1340076D01*
G01X1344983D02*
X1344018D01*
G01X1348916D02*
X1347950D01*
G01X1352857D02*
X1351892D01*
G01X1356790D02*
X1355824D01*
G01X1360731D02*
X1359766D01*
G01X1364664D02*
X1363698D01*
G01X1368605D02*
X1367640D01*
G01X1372538D02*
X1371572D01*
G01X1376479D02*
X1375514D01*
G01X1380412D02*
X1379446D01*
G01X1384353D02*
X1383388D01*
G01X1388286D02*
X1387320D01*
G01X1386386Y605358D02*
X1386701D01*
G01X1382449D02*
X1382764D01*
G01X1374575D02*
X1374890D01*
G01X1366701D02*
X1367016D01*
G01X1362764D02*
X1363079D01*
G01X1358827D02*
X1359142D01*
G01X1354890D02*
X1355205D01*
G01X1350953D02*
X1351268D01*
G01X1347016D02*
X1347331D01*
G01X1343079D02*
X1343394D01*
G01X1339142D02*
X1339457D01*
G01X1335205D02*
X1335520D01*
G01X1331268D02*
X1331583D01*
G01X1327331D02*
X1327646D01*
G01X1323394D02*
X1323709D01*
G01X1322291D02*
X1321976D01*
G01X1326228D02*
X1325913D01*
G01X1330165D02*
X1329850D01*
G01X1334102D02*
X1333787D01*
G01X1338039D02*
X1337724D01*
G01X1341976D02*
X1341661D01*
G01X1345913D02*
X1345598D01*
G01X1349850D02*
X1349535D01*
G01X1353787D02*
X1353472D01*
G01X1357724D02*
X1357409D01*
G01X1361661D02*
X1361346D01*
G01X1365598D02*
X1365283D01*
G01X1369535D02*
X1369220D01*
G01X1370953D02*
X1370638D01*
G01X1373472D02*
X1373157D01*
G01X1377409D02*
X1377094D01*
G01X1378827D02*
X1378512D01*
G01X1381346D02*
X1381031D01*
G01X1385283D02*
X1384968D01*
G01X1325821Y605261D02*
X1323801D01*
G01X1329763D02*
X1327742D01*
G01X1333695D02*
X1331675D01*
G01X1337637D02*
X1335616D01*
G01X1341569D02*
X1339549D01*
G01X1345511D02*
X1343490D01*
G01X1349443D02*
X1347423D01*
G01X1353385D02*
X1351364D01*
G01X1357317D02*
X1355297D01*
G01X1361259D02*
X1359238D01*
G01X1365192D02*
X1363171D01*
G01X1369133D02*
X1367112D01*
G01X1373066D02*
X1371045D01*
G01X1377007D02*
X1374986D01*
G01X1380940D02*
X1378919D01*
G01X1384881D02*
X1382860D01*
G01X1388814D02*
X1386793D01*
G01X1383039Y604965D02*
X1384693D01*
G01X1375165D02*
X1376819D01*
G01X1367291D02*
X1368945D01*
G01X1359417D02*
X1361071D01*
G01X1351543D02*
X1353197D01*
G01X1343669D02*
X1345323D01*
G01X1335795D02*
X1337449D01*
G01X1327921D02*
X1329575D01*
G01X1325561Y604772D02*
X1324061D01*
G01X1329502D02*
X1328003D01*
G01X1333435D02*
X1331935D01*
G01X1337376D02*
X1335877D01*
G01X1341309D02*
X1339809D01*
G01X1345250D02*
X1343751D01*
G01X1349183D02*
X1347683D01*
G01X1353124D02*
X1351625D01*
G01X1357057D02*
X1355557D01*
G01X1360998D02*
X1359499D01*
G01X1364931D02*
X1363431D01*
G01X1368873D02*
X1367373D01*
G01X1372805D02*
X1371305D01*
G01X1376747D02*
X1375247D01*
G01X1380679D02*
X1379179D01*
G01X1384621D02*
X1383121D01*
G01X1388553D02*
X1387053D01*
G01X1325559Y604763D02*
X1324063D01*
G01X1329501D02*
X1328004D01*
G01X1333433D02*
X1331937D01*
G01X1337375D02*
X1335878D01*
G01X1341307D02*
X1339811D01*
G01X1345249D02*
X1343753D01*
G01X1349181D02*
X1347685D01*
G01X1353123D02*
X1351627D01*
G01X1357055D02*
X1355559D01*
G01X1360997D02*
X1359501D01*
G01X1364929D02*
X1363433D01*
G01X1368871D02*
X1367375D01*
G01X1372803D02*
X1371307D01*
G01X1376745D02*
X1375249D01*
G01X1380677D02*
X1379181D01*
G01X1384619D02*
X1383123D01*
G01X1388551D02*
X1387055D01*
G01X1387275Y604441D02*
X1388331D01*
G01X1383343D02*
X1384399D01*
G01X1379401D02*
X1380457D01*
G01X1375469D02*
X1376525D01*
G01X1371527D02*
X1372583D01*
G01X1367594D02*
X1368651D01*
G01X1363653D02*
X1364709D01*
G01X1359720D02*
X1360777D01*
G01X1355779D02*
X1356835D01*
G01X1351846D02*
X1352903D01*
G01X1347905D02*
X1348961D01*
G01X1343972D02*
X1345029D01*
G01X1340031D02*
X1341087D01*
G01X1336098D02*
X1337155D01*
G01X1332157D02*
X1333213D01*
G01X1328224D02*
X1329281D01*
G01X1324283D02*
X1325339D01*
G01X1320350D02*
X1321407D01*
G01X1378748Y604394D02*
X1381110D01*
G01X1374811D02*
X1377173D01*
G01X1370874D02*
X1373236D01*
G01X1325992D02*
X1323630D01*
G01X1329929D02*
X1327567D01*
G01X1333866D02*
X1331504D01*
G01X1337803D02*
X1335441D01*
G01X1341740D02*
X1339378D01*
G01X1345677D02*
X1343315D01*
G01X1349614D02*
X1347252D01*
G01X1353551D02*
X1351189D01*
G01X1357488D02*
X1355126D01*
G01X1361425D02*
X1359063D01*
G01X1365362D02*
X1363000D01*
G01X1369299D02*
X1366937D01*
G01X1385047D02*
X1382685D01*
G01X1388984D02*
X1386622D01*
G01X1386386Y603862D02*
X1386701D01*
G01X1384968D02*
X1385283D01*
G01X1382449D02*
X1382764D01*
G01X1381031D02*
X1381346D01*
G01X1378512D02*
X1378827D01*
G01X1377094D02*
X1377409D01*
G01X1374575D02*
X1374890D01*
G01X1373157D02*
X1373472D01*
G01X1369220D02*
X1369535D01*
G01X1370638D02*
X1370953D01*
G01X1366701D02*
X1367016D01*
G01X1365283D02*
X1365598D01*
G01X1362764D02*
X1363079D01*
G01X1361346D02*
X1361661D01*
G01X1358827D02*
X1359142D01*
G01X1357409D02*
X1357724D01*
G01X1354890D02*
X1355205D01*
G01X1353472D02*
X1353787D01*
G01X1350953D02*
X1351268D01*
G01X1349535D02*
X1349850D01*
G01X1347016D02*
X1347331D01*
G01X1345598D02*
X1345913D01*
G01X1343079D02*
X1343394D01*
G01X1341661D02*
X1341976D01*
G01X1337724D02*
X1338039D01*
G01X1339142D02*
X1339457D01*
G01X1335205D02*
X1335520D01*
G01X1333787D02*
X1334102D01*
G01X1331268D02*
X1331583D01*
G01X1329850D02*
X1330165D01*
G01X1327331D02*
X1327646D01*
G01X1325913D02*
X1326228D01*
G01X1323394D02*
X1323709D01*
G01X1321976D02*
X1322291D01*
G01X1387031Y603826D02*
X1388575D01*
G01X1383099D02*
X1384642D01*
G01X1379157D02*
X1380701D01*
G01X1375225D02*
X1376768D01*
G01X1371283D02*
X1372827D01*
G01X1367351D02*
X1368894D01*
G01X1363409D02*
X1364953D01*
G01X1359477D02*
X1361020D01*
G01X1355535D02*
X1357079D01*
G01X1351603D02*
X1353146D01*
G01X1347661D02*
X1349205D01*
G01X1343729D02*
X1345272D01*
G01X1339787D02*
X1341331D01*
G01X1335855D02*
X1337398D01*
G01X1331913D02*
X1333457D01*
G01X1327981D02*
X1329524D01*
G01X1324039D02*
X1325583D01*
G01X1387042Y603807D02*
X1388564D01*
G01X1383110D02*
X1384632D01*
G01X1379168D02*
X1380690D01*
G01X1375236D02*
X1376758D01*
G01X1371294D02*
X1372816D01*
G01X1367362D02*
X1368883D01*
G01X1363420D02*
X1364942D01*
G01X1359488D02*
X1361009D01*
G01X1355546D02*
X1357068D01*
G01X1351614D02*
X1353135D01*
G01X1347672D02*
X1349194D01*
G01X1343740D02*
X1345261D01*
G01X1339798D02*
X1341320D01*
G01X1335866D02*
X1337387D01*
G01X1331924D02*
X1333446D01*
G01X1327992D02*
X1329513D01*
G01X1324050D02*
X1325572D01*
G01X1383039Y603193D02*
X1384693D01*
G01X1375165D02*
X1376819D01*
G01X1367291D02*
X1368945D01*
G01X1359417D02*
X1361071D01*
G01X1351543D02*
X1353197D01*
G01X1343669D02*
X1345323D01*
G01X1335795D02*
X1337449D01*
G01X1327921D02*
X1329575D01*
G01Y602701D02*
X1327921D01*
G01X1337449D02*
X1335795D01*
G01X1345323D02*
X1343669D01*
G01X1353197D02*
X1351543D01*
G01X1361071D02*
X1359417D01*
G01X1368945D02*
X1367291D01*
G01X1376819D02*
X1375165D01*
G01X1384693D02*
X1383039D01*
G01X1329417Y602602D02*
X1328079D01*
G01X1337291D02*
X1335953D01*
G01X1345165D02*
X1343827D01*
G01X1353039D02*
X1351701D01*
G01X1360913D02*
X1359575D01*
G01X1368787D02*
X1367449D01*
G01X1376661D02*
X1375323D01*
G01X1384535D02*
X1383197D01*
G01Y601618D02*
X1384535D01*
G01X1375323D02*
X1376661D01*
G01X1367449D02*
X1368787D01*
G01X1359575D02*
X1360913D01*
G01X1351701D02*
X1353039D01*
G01X1343827D02*
X1345165D01*
G01X1335953D02*
X1337291D01*
G01X1328079D02*
X1329417D01*
G01X1325609Y600999D02*
X1324013D01*
G01X1329550D02*
X1327955D01*
G01X1333483D02*
X1331887D01*
G01X1337424D02*
X1335829D01*
G01X1341357D02*
X1339761D01*
G01X1345298D02*
X1343703D01*
G01X1349231D02*
X1347635D01*
G01X1353172D02*
X1351577D01*
G01X1357105D02*
X1355510D01*
G01X1361046D02*
X1359451D01*
G01X1364979D02*
X1363384D01*
G01X1368920D02*
X1367325D01*
G01X1372853D02*
X1371258D01*
G01X1376794D02*
X1375199D01*
G01X1380727D02*
X1379132D01*
G01X1384668D02*
X1383073D01*
G01X1388601D02*
X1387006D01*
G01X1325913Y600890D02*
X1323709D01*
G01X1329850D02*
X1327646D01*
G01X1333787D02*
X1331583D01*
G01X1337724D02*
X1335520D01*
G01X1341661D02*
X1339457D01*
G01X1345598D02*
X1343394D01*
G01X1349535D02*
X1347331D01*
G01X1353472D02*
X1351268D01*
G01X1357409D02*
X1355205D01*
G01X1361346D02*
X1359142D01*
G01X1365283D02*
X1363079D01*
G01X1369220D02*
X1367016D01*
G01X1373157D02*
X1370953D01*
G01X1377094D02*
X1374890D01*
G01X1381031D02*
X1378827D01*
G01X1384968D02*
X1382764D01*
G01X1388906D02*
X1386701D01*
G01X1325680Y600239D02*
X1323942D01*
G01X1329622D02*
X1327883D01*
G01X1333554D02*
X1331816D01*
G01X1337496D02*
X1335757D01*
G01X1341428D02*
X1339690D01*
G01X1345370D02*
X1343631D01*
G01X1349302D02*
X1347564D01*
G01X1353244D02*
X1351505D01*
G01X1357176D02*
X1355438D01*
G01X1361118D02*
X1359379D01*
G01X1365051D02*
X1363312D01*
G01X1368992D02*
X1367253D01*
G01X1372925D02*
X1371186D01*
G01X1376866D02*
X1375127D01*
G01X1380799D02*
X1379060D01*
G01X1384740D02*
X1383001D01*
G01X1388673D02*
X1386934D01*
G01X1387008Y600037D02*
X1388598D01*
G01X1383076D02*
X1384666D01*
G01X1379134D02*
X1380724D01*
G01X1375202D02*
X1376792D01*
G01X1371260D02*
X1372850D01*
G01X1367328D02*
X1368918D01*
G01X1363386D02*
X1364976D01*
G01X1359454D02*
X1361044D01*
G01X1355512D02*
X1357102D01*
G01X1351579D02*
X1353170D01*
G01X1347638D02*
X1349228D01*
G01X1343705D02*
X1345296D01*
G01X1339764D02*
X1341354D01*
G01X1335831D02*
X1337422D01*
G01X1331890D02*
X1333480D01*
G01X1327957D02*
X1329548D01*
G01X1324016D02*
X1325606D01*
G01X1386955Y600013D02*
X1388651D01*
G01X1383023D02*
X1384719D01*
G01X1379081D02*
X1380777D01*
G01X1375149D02*
X1376845D01*
G01X1371207D02*
X1372903D01*
G01X1367275D02*
X1368971D01*
G01X1363333D02*
X1365029D01*
G01X1359401D02*
X1361097D01*
G01X1355459D02*
X1357155D01*
G01X1351527D02*
X1353223D01*
G01X1347585D02*
X1349281D01*
G01X1343653D02*
X1345349D01*
G01X1339711D02*
X1341407D01*
G01X1335779D02*
X1337475D01*
G01X1331837D02*
X1333533D01*
G01X1327905D02*
X1329601D01*
G01X1323963D02*
X1325659D01*
G01X1325666Y599945D02*
X1323956D01*
G01X1329608D02*
X1327898D01*
G01X1333540D02*
X1331830D01*
G01X1337482D02*
X1335772D01*
G01X1341414D02*
X1339704D01*
G01X1345356D02*
X1343646D01*
G01X1349288D02*
X1347578D01*
G01X1353230D02*
X1351520D01*
G01X1357162D02*
X1355452D01*
G01X1361104D02*
X1359394D01*
G01X1365036D02*
X1363326D01*
G01X1368978D02*
X1367268D01*
G01X1372910D02*
X1371200D01*
G01X1376852D02*
X1375142D01*
G01X1380784D02*
X1379074D01*
G01X1384726D02*
X1383016D01*
G01X1388658D02*
X1386948D01*
G01X1386929Y599353D02*
X1388677D01*
G01X1382997D02*
X1384745D01*
G01X1379055D02*
X1380803D01*
G01X1375123D02*
X1376871D01*
G01X1371181D02*
X1372929D01*
G01X1367249D02*
X1368997D01*
G01X1363307D02*
X1365055D01*
G01X1359375D02*
X1361123D01*
G01X1355433D02*
X1357181D01*
G01X1351501D02*
X1353249D01*
G01X1347559D02*
X1349307D01*
G01X1343627D02*
X1345375D01*
G01X1339685D02*
X1341433D01*
G01X1335753D02*
X1337501D01*
G01X1331811D02*
X1333559D01*
G01X1327879D02*
X1329627D01*
G01X1323937D02*
X1325685D01*
G01X1325657Y599051D02*
X1323965D01*
G01X1329598D02*
X1327907D01*
G01X1333531D02*
X1331839D01*
G01X1337472D02*
X1335781D01*
G01X1341405D02*
X1339713D01*
G01X1345346D02*
X1343655D01*
G01X1349279D02*
X1347587D01*
G01X1353220D02*
X1351529D01*
G01X1357153D02*
X1355461D01*
G01X1361094D02*
X1359403D01*
G01X1365027D02*
X1363335D01*
G01X1368969D02*
X1367277D01*
G01X1372901D02*
X1371209D01*
G01X1376843D02*
X1375151D01*
G01X1380775D02*
X1379083D01*
G01X1384717D02*
X1383025D01*
G01X1388649D02*
X1386957D01*
G01X1325666Y598961D02*
X1323956D01*
G01X1329608D02*
X1327898D01*
G01X1333540D02*
X1331830D01*
G01X1337482D02*
X1335772D01*
G01X1341414D02*
X1339704D01*
G01X1345356D02*
X1343646D01*
G01X1349288D02*
X1347578D01*
G01X1353230D02*
X1351520D01*
G01X1357162D02*
X1355452D01*
G01X1361104D02*
X1359394D01*
G01X1365036D02*
X1363326D01*
G01X1368978D02*
X1367268D01*
G01X1372910D02*
X1371200D01*
G01X1376852D02*
X1375142D01*
G01X1380784D02*
X1379074D01*
G01X1384726D02*
X1383016D01*
G01X1388658D02*
X1386948D01*
G01X1386701Y598635D02*
X1388906D01*
G01X1382764D02*
X1384968D01*
G01X1378827D02*
X1381031D01*
G01X1374890D02*
X1377094D01*
G01X1370953D02*
X1373157D01*
G01X1367016D02*
X1369220D01*
G01X1363079D02*
X1365283D01*
G01X1359142D02*
X1361346D01*
G01X1355205D02*
X1357409D01*
G01X1351268D02*
X1353472D01*
G01X1347331D02*
X1349535D01*
G01X1343394D02*
X1345598D01*
G01X1339457D02*
X1341661D01*
G01X1335520D02*
X1337724D01*
G01X1331583D02*
X1333787D01*
G01X1327646D02*
X1329850D01*
G01X1323709D02*
X1325913D01*
G01X1386701Y598468D02*
X1388906D01*
G01X1382764D02*
X1384968D01*
G01X1378827D02*
X1381031D01*
G01X1374890D02*
X1377094D01*
G01X1370953D02*
X1373157D01*
G01X1367016D02*
X1369220D01*
G01X1363079D02*
X1365283D01*
G01X1359142D02*
X1361346D01*
G01X1355205D02*
X1357409D01*
G01X1351268D02*
X1353472D01*
G01X1347331D02*
X1349535D01*
G01X1343394D02*
X1345598D01*
G01X1339457D02*
X1341661D01*
G01X1335520D02*
X1337724D01*
G01X1331583D02*
X1333787D01*
G01X1327646D02*
X1329850D01*
G01X1323709D02*
X1325913D01*
G01Y595910D02*
X1323709D01*
G01X1329850D02*
X1327646D01*
G01X1333787D02*
X1331583D01*
G01X1337724D02*
X1335520D01*
G01X1341661D02*
X1339457D01*
G01X1345598D02*
X1343394D01*
G01X1349535D02*
X1347331D01*
G01X1353472D02*
X1351268D01*
G01X1357409D02*
X1355205D01*
G01X1361346D02*
X1359142D01*
G01X1365283D02*
X1363079D01*
G01X1369220D02*
X1367016D01*
G01X1373157D02*
X1370953D01*
G01X1377094D02*
X1374890D01*
G01X1381031D02*
X1378827D01*
G01X1384968D02*
X1382764D01*
G01X1388906D02*
X1386701D01*
G01X1325913Y595743D02*
X1323709D01*
G01X1329850D02*
X1327646D01*
G01X1333787D02*
X1331583D01*
G01X1337724D02*
X1335520D01*
G01X1341661D02*
X1339457D01*
G01X1345598D02*
X1343394D01*
G01X1349535D02*
X1347331D01*
G01X1353472D02*
X1351268D01*
G01X1357409D02*
X1355205D01*
G01X1361346D02*
X1359142D01*
G01X1365283D02*
X1363079D01*
G01X1369220D02*
X1367016D01*
G01X1373157D02*
X1370953D01*
G01X1377094D02*
X1374890D01*
G01X1381031D02*
X1378827D01*
G01X1384968D02*
X1382764D01*
G01X1388906D02*
X1386701D01*
G01X1386948Y595417D02*
X1388658D01*
G01X1383006D02*
X1384717D01*
G01X1379074D02*
X1380784D01*
G01X1375132D02*
X1376843D01*
G01X1371200D02*
X1372910D01*
G01X1367258D02*
X1368969D01*
G01X1363326D02*
X1365036D01*
G01X1359384D02*
X1361094D01*
G01X1355452D02*
X1357162D01*
G01X1351510D02*
X1353220D01*
G01X1347578D02*
X1349288D01*
G01X1343636D02*
X1345346D01*
G01X1339704D02*
X1341414D01*
G01X1335762D02*
X1337472D01*
G01X1331830D02*
X1333540D01*
G01X1327888D02*
X1329598D01*
G01X1323956D02*
X1325666D01*
G01X1386957Y595327D02*
X1388649D01*
G01X1383016D02*
X1384707D01*
G01X1379083D02*
X1380775D01*
G01X1375142D02*
X1376833D01*
G01X1371209D02*
X1372901D01*
G01X1367268D02*
X1368959D01*
G01X1363335D02*
X1365027D01*
G01X1359394D02*
X1361085D01*
G01X1355461D02*
X1357153D01*
G01X1351520D02*
X1353211D01*
G01X1347587D02*
X1349279D01*
G01X1343646D02*
X1345337D01*
G01X1339713D02*
X1341405D01*
G01X1335772D02*
X1337463D01*
G01X1331839D02*
X1333531D01*
G01X1327898D02*
X1329589D01*
G01X1323965D02*
X1325657D01*
G01X1325685Y595025D02*
X1323937D01*
G01X1329618D02*
X1327869D01*
G01X1333559D02*
X1331811D01*
G01X1337492D02*
X1335743D01*
G01X1341433D02*
X1339685D01*
G01X1345366D02*
X1343617D01*
G01X1349307D02*
X1347559D01*
G01X1353240D02*
X1351491D01*
G01X1357181D02*
X1355433D01*
G01X1361114D02*
X1359365D01*
G01X1365055D02*
X1363307D01*
G01X1368988D02*
X1367239D01*
G01X1372929D02*
X1371181D01*
G01X1376862D02*
X1375113D01*
G01X1380803D02*
X1379055D01*
G01X1384736D02*
X1382987D01*
G01X1388677D02*
X1386929D01*
G01X1386948Y594433D02*
X1388658D01*
G01X1383006D02*
X1384717D01*
G01X1379074D02*
X1380784D01*
G01X1375132D02*
X1376843D01*
G01X1371200D02*
X1372910D01*
G01X1367258D02*
X1368969D01*
G01X1363326D02*
X1365036D01*
G01X1359384D02*
X1361094D01*
G01X1355452D02*
X1357162D01*
G01X1351510D02*
X1353220D01*
G01X1347578D02*
X1349288D01*
G01X1343636D02*
X1345346D01*
G01X1339704D02*
X1341414D01*
G01X1335762D02*
X1337472D01*
G01X1331830D02*
X1333540D01*
G01X1327888D02*
X1329598D01*
G01X1323956D02*
X1325666D01*
G01X1325659Y594365D02*
X1323963D01*
G01X1329591D02*
X1327895D01*
G01X1333533D02*
X1331837D01*
G01X1337465D02*
X1335769D01*
G01X1341407D02*
X1339711D01*
G01X1345339D02*
X1343643D01*
G01X1349281D02*
X1347585D01*
G01X1353213D02*
X1351517D01*
G01X1357155D02*
X1355459D01*
G01X1361087D02*
X1359391D01*
G01X1365029D02*
X1363333D01*
G01X1368962D02*
X1367265D01*
G01X1372903D02*
X1371207D01*
G01X1376836D02*
X1375139D01*
G01X1380777D02*
X1379081D01*
G01X1384710D02*
X1383013D01*
G01X1388651D02*
X1386955D01*
G01X1325606Y594341D02*
X1324016D01*
G01X1329539D02*
X1327948D01*
G01X1333480D02*
X1331890D01*
G01X1337413D02*
X1335822D01*
G01X1341354D02*
X1339764D01*
G01X1345287D02*
X1343696D01*
G01X1349228D02*
X1347638D01*
G01X1353161D02*
X1351570D01*
G01X1357102D02*
X1355512D01*
G01X1361035D02*
X1359444D01*
G01X1364976D02*
X1363386D01*
G01X1368909D02*
X1367318D01*
G01X1372850D02*
X1371260D01*
G01X1376783D02*
X1375192D01*
G01X1380724D02*
X1379134D01*
G01X1384657D02*
X1383066D01*
G01X1388598D02*
X1387008D01*
G01X1386934Y594139D02*
X1388673D01*
G01X1382992D02*
X1384731D01*
G01X1379060D02*
X1380799D01*
G01X1375118D02*
X1376857D01*
G01X1371186D02*
X1372925D01*
G01X1367244D02*
X1368983D01*
G01X1363312D02*
X1365051D01*
G01X1359370D02*
X1361109D01*
G01X1355438D02*
X1357176D01*
G01X1351496D02*
X1353235D01*
G01X1347564D02*
X1349302D01*
G01X1343622D02*
X1345361D01*
G01X1339690D02*
X1341428D01*
G01X1335748D02*
X1337487D01*
G01X1331816D02*
X1333554D01*
G01X1327874D02*
X1329613D01*
G01X1323942D02*
X1325680D01*
G01X1386701Y593488D02*
X1388906D01*
G01X1382764D02*
X1384968D01*
G01X1378827D02*
X1381031D01*
G01X1374890D02*
X1377094D01*
G01X1370953D02*
X1373157D01*
G01X1367016D02*
X1369220D01*
G01X1363079D02*
X1365283D01*
G01X1359142D02*
X1361346D01*
G01X1355205D02*
X1357409D01*
G01X1351268D02*
X1353472D01*
G01X1347331D02*
X1349535D01*
G01X1343394D02*
X1345598D01*
G01X1339457D02*
X1341661D01*
G01X1335520D02*
X1337724D01*
G01X1331583D02*
X1333787D01*
G01X1327646D02*
X1329850D01*
G01X1323709D02*
X1325913D01*
G01X1387006Y593379D02*
X1388601D01*
G01X1383064D02*
X1384659D01*
G01X1379132D02*
X1380727D01*
G01X1375190D02*
X1376785D01*
G01X1371258D02*
X1372853D01*
G01X1367316D02*
X1368911D01*
G01X1363384D02*
X1364979D01*
G01X1359442D02*
X1361037D01*
G01X1355510D02*
X1357105D01*
G01X1351568D02*
X1353163D01*
G01X1347635D02*
X1349231D01*
G01X1343694D02*
X1345289D01*
G01X1339761D02*
X1341357D01*
G01X1335820D02*
X1337415D01*
G01X1331887D02*
X1333483D01*
G01X1327946D02*
X1329541D01*
G01X1324013D02*
X1325609D01*
G01X1329417Y592760D02*
X1328079D01*
G01X1337291D02*
X1335953D01*
G01X1345165D02*
X1343827D01*
G01X1353039D02*
X1351701D01*
G01X1360913D02*
X1359575D01*
G01X1368787D02*
X1367449D01*
G01X1376661D02*
X1375323D01*
G01X1384535D02*
X1383197D01*
G01X1329417Y591776D02*
X1328079D01*
G01X1337291D02*
X1335953D01*
G01X1345165D02*
X1343827D01*
G01X1353039D02*
X1351701D01*
G01X1360913D02*
X1359575D01*
G01X1368787D02*
X1367449D01*
G01X1376661D02*
X1375323D01*
G01X1384535D02*
X1383197D01*
G01X1383039Y591677D02*
X1384693D01*
G01X1375165D02*
X1376819D01*
G01X1367291D02*
X1368945D01*
G01X1359417D02*
X1361071D01*
G01X1351543D02*
X1353197D01*
G01X1343669D02*
X1345323D01*
G01X1335795D02*
X1337449D01*
G01X1327921D02*
X1329575D01*
G01Y591185D02*
X1327921D01*
G01X1337449D02*
X1335795D01*
G01X1345323D02*
X1343669D01*
G01X1353197D02*
X1351543D01*
G01X1361071D02*
X1359417D01*
G01X1368945D02*
X1367291D01*
G01X1376819D02*
X1375165D01*
G01X1384693D02*
X1383039D01*
G01X1325572Y590571D02*
X1324050D01*
G01X1329504D02*
X1327983D01*
G01X1333446D02*
X1331924D01*
G01X1337378D02*
X1335857D01*
G01X1341320D02*
X1339798D01*
G01X1345252D02*
X1343731D01*
G01X1349194D02*
X1347672D01*
G01X1353126D02*
X1351605D01*
G01X1357068D02*
X1355546D01*
G01X1361000D02*
X1359479D01*
G01X1364942D02*
X1363420D01*
G01X1368874D02*
X1367353D01*
G01X1372816D02*
X1371294D01*
G01X1376748D02*
X1375227D01*
G01X1380690D02*
X1379168D01*
G01X1384622D02*
X1383101D01*
G01X1388564D02*
X1387042D01*
G01X1325583Y590552D02*
X1324039D01*
G01X1329515D02*
X1327972D01*
G01X1333457D02*
X1331913D01*
G01X1337389D02*
X1335846D01*
G01X1341331D02*
X1339787D01*
G01X1345263D02*
X1343720D01*
G01X1349205D02*
X1347661D01*
G01X1353137D02*
X1351594D01*
G01X1357079D02*
X1355535D01*
G01X1361011D02*
X1359468D01*
G01X1364953D02*
X1363409D01*
G01X1368885D02*
X1367342D01*
G01X1372827D02*
X1371283D01*
G01X1376759D02*
X1375216D01*
G01X1380701D02*
X1379157D01*
G01X1384633D02*
X1383090D01*
G01X1388575D02*
X1387031D01*
G01X1322291Y590516D02*
X1321976D01*
G01X1323709D02*
X1323394D01*
G01X1326228D02*
X1325913D01*
G01X1327646D02*
X1327331D01*
G01X1330165D02*
X1329850D01*
G01X1331583D02*
X1331268D01*
G01X1334102D02*
X1333787D01*
G01X1335520D02*
X1335205D01*
G01X1338039D02*
X1337724D01*
G01X1339457D02*
X1339142D01*
G01X1341976D02*
X1341661D01*
G01X1343394D02*
X1343079D01*
G01X1345913D02*
X1345598D01*
G01X1347331D02*
X1347016D01*
G01X1349850D02*
X1349535D01*
G01X1351268D02*
X1350953D01*
G01X1353787D02*
X1353472D01*
G01X1355205D02*
X1354890D01*
G01X1357724D02*
X1357409D01*
G01X1359142D02*
X1358827D01*
G01X1361661D02*
X1361346D01*
G01X1363079D02*
X1362764D01*
G01X1365598D02*
X1365283D01*
G01X1367016D02*
X1366701D01*
G01X1369535D02*
X1369220D01*
G01X1370953D02*
X1370638D01*
G01X1373472D02*
X1373157D01*
G01X1374890D02*
X1374575D01*
G01X1377409D02*
X1377094D01*
G01X1378827D02*
X1378512D01*
G01X1381346D02*
X1381031D01*
G01X1382764D02*
X1382449D01*
G01X1385283D02*
X1384968D01*
G01X1386701D02*
X1386386D01*
G01X1325992Y589984D02*
X1323630D01*
G01X1329929D02*
X1327567D01*
G01X1333866D02*
X1331504D01*
G01X1337803D02*
X1335441D01*
G01X1341740D02*
X1339378D01*
G01X1345677D02*
X1343315D01*
G01X1349614D02*
X1347252D01*
G01X1353551D02*
X1351189D01*
G01X1357488D02*
X1355126D01*
G01X1361425D02*
X1359063D01*
G01X1365362D02*
X1363000D01*
G01X1369299D02*
X1366937D01*
G01X1373236D02*
X1370874D01*
G01X1377173D02*
X1374811D01*
G01X1381110D02*
X1378748D01*
G01X1385047D02*
X1382685D01*
G01X1388984D02*
X1386622D01*
G01X1321398Y589937D02*
X1320341D01*
G01X1325339D02*
X1324283D01*
G01X1329272D02*
X1328215D01*
G01X1333213D02*
X1332157D01*
G01X1337146D02*
X1336089D01*
G01X1341087D02*
X1340031D01*
G01X1345020D02*
X1343963D01*
G01X1348961D02*
X1347905D01*
G01X1352894D02*
X1351837D01*
G01X1356835D02*
X1355779D01*
G01X1360768D02*
X1359711D01*
G01X1364709D02*
X1363653D01*
G01X1368642D02*
X1367585D01*
G01X1372583D02*
X1371527D01*
G01X1376516D02*
X1375459D01*
G01X1380457D02*
X1379401D01*
G01X1384390D02*
X1383333D01*
G01X1388331D02*
X1387275D01*
G01X1387055Y589615D02*
X1388551D01*
G01X1383113D02*
X1384610D01*
G01X1379181D02*
X1380677D01*
G01X1375239D02*
X1376736D01*
G01X1371307D02*
X1372803D01*
G01X1367365D02*
X1368862D01*
G01X1363433D02*
X1364929D01*
G01X1359491D02*
X1360988D01*
G01X1355559D02*
X1357055D01*
G01X1351617D02*
X1353114D01*
G01X1347685D02*
X1349181D01*
G01X1343743D02*
X1345240D01*
G01X1339811D02*
X1341307D01*
G01X1335869D02*
X1337366D01*
G01X1331937D02*
X1333433D01*
G01X1327995D02*
X1329492D01*
G01X1324063D02*
X1325559D01*
G01X1387053Y589606D02*
X1388553D01*
G01X1383112D02*
X1384611D01*
G01X1379179D02*
X1380679D01*
G01X1375238D02*
X1376737D01*
G01X1371305D02*
X1372805D01*
G01X1367364D02*
X1368863D01*
G01X1363431D02*
X1364931D01*
G01X1359490D02*
X1360989D01*
G01X1355557D02*
X1357057D01*
G01X1351616D02*
X1353115D01*
G01X1347683D02*
X1349183D01*
G01X1343742D02*
X1345241D01*
G01X1339809D02*
X1341309D01*
G01X1335868D02*
X1337367D01*
G01X1331935D02*
X1333435D01*
G01X1327994D02*
X1329493D01*
G01X1324061D02*
X1325561D01*
G01X1329575Y589413D02*
X1327921D01*
G01X1337449D02*
X1335795D01*
G01X1345323D02*
X1343669D01*
G01X1353197D02*
X1351543D01*
G01X1361071D02*
X1359417D01*
G01X1368945D02*
X1367291D01*
G01X1376819D02*
X1375165D01*
G01X1384693D02*
X1383039D01*
G01X1386793Y589117D02*
X1388814D01*
G01X1382851D02*
X1384872D01*
G01X1378919D02*
X1380940D01*
G01X1374977D02*
X1376998D01*
G01X1371045D02*
X1373066D01*
G01X1367103D02*
X1369124D01*
G01X1363171D02*
X1365192D01*
G01X1359229D02*
X1361250D01*
G01X1355297D02*
X1357317D01*
G01X1351355D02*
X1353376D01*
G01X1347423D02*
X1349443D01*
G01X1343481D02*
X1345502D01*
G01X1339549D02*
X1341569D01*
G01X1335607D02*
X1337628D01*
G01X1331675D02*
X1333695D01*
G01X1327733D02*
X1329754D01*
G01X1323801D02*
X1325821D01*
G01X1384968Y589020D02*
X1385283D01*
G01X1377094D02*
X1377409D01*
G01X1369220D02*
X1369535D01*
G01X1365283D02*
X1365598D01*
G01X1361346D02*
X1361661D01*
G01X1357409D02*
X1357724D01*
G01X1353472D02*
X1353787D01*
G01X1349535D02*
X1349850D01*
G01X1345598D02*
X1345913D01*
G01X1341661D02*
X1341976D01*
G01X1337724D02*
X1338039D01*
G01X1333787D02*
X1334102D01*
G01X1329850D02*
X1330165D01*
G01X1325913D02*
X1326228D01*
G01X1321976D02*
X1322291D01*
G01X1323709D02*
X1323394D01*
G01X1327646D02*
X1327331D01*
G01X1331583D02*
X1331268D01*
G01X1335520D02*
X1335205D01*
G01X1339457D02*
X1339142D01*
G01X1343394D02*
X1343079D01*
G01X1347331D02*
X1347016D01*
G01X1351268D02*
X1350953D01*
G01X1355205D02*
X1354890D01*
G01X1359142D02*
X1358827D01*
G01X1363079D02*
X1362764D01*
G01X1367016D02*
X1366701D01*
G01X1370953D02*
X1370638D01*
G01X1373472D02*
X1373157D01*
G01X1374890D02*
X1374575D01*
G01X1378827D02*
X1378512D01*
G01X1381346D02*
X1381031D01*
G01X1382764D02*
X1382449D01*
G01X1386701D02*
X1386386D01*
G01X1387320Y589010D02*
X1388286D01*
G01X1383379D02*
X1384344D01*
G01X1379446D02*
X1380412D01*
G01X1375505D02*
X1376470D01*
G01X1371572D02*
X1372538D01*
G01X1367631D02*
X1368596D01*
G01X1363698D02*
X1364664D01*
G01X1359757D02*
X1360722D01*
G01X1355824D02*
X1356790D01*
G01X1351883D02*
X1352848D01*
G01X1347950D02*
X1348916D01*
G01X1344009D02*
X1344974D01*
G01X1340076D02*
X1341042D01*
G01X1336135D02*
X1337100D01*
G01X1332202D02*
X1333168D01*
G01X1328261D02*
X1329226D01*
G01X1324328D02*
X1325294D01*
G01X1320387D02*
X1321352D01*
G01X1383039Y588921D02*
X1384693D01*
G01X1375165D02*
X1376819D01*
G01X1367291D02*
X1368945D01*
G01X1359417D02*
X1361071D01*
G01X1351543D02*
X1353197D01*
G01X1343669D02*
X1345323D01*
G01X1335795D02*
X1337449D01*
G01X1327921D02*
X1329575D01*
G01X1386386Y588823D02*
X1389220D01*
G01X1382449D02*
X1385283D01*
G01X1378512D02*
X1381346D01*
G01X1374575D02*
X1377409D01*
G01X1370638D02*
X1373472D01*
G01X1366701D02*
X1369535D01*
G01X1362764D02*
X1365598D01*
G01X1358827D02*
X1361661D01*
G01X1354890D02*
X1357724D01*
G01X1350953D02*
X1353787D01*
G01X1347016D02*
X1349850D01*
G01X1343079D02*
X1345913D01*
G01X1339142D02*
X1341976D01*
G01X1335205D02*
X1338039D01*
G01X1331268D02*
X1334102D01*
G01X1327331D02*
X1330165D01*
G01X1323394D02*
X1326228D01*
G01X1386386Y588665D02*
X1386976D01*
G01X1384693D02*
X1385283D01*
G01X1382449D02*
X1383039D01*
G01X1380756D02*
X1381346D01*
G01X1378512D02*
X1379102D01*
G01X1376819D02*
X1377409D01*
G01X1374575D02*
X1375165D01*
G01X1372882D02*
X1373472D01*
G01X1370638D02*
X1371228D01*
G01X1368945D02*
X1369535D01*
G01X1366701D02*
X1367291D01*
G01X1365008D02*
X1365598D01*
G01X1362764D02*
X1363354D01*
G01X1361071D02*
X1361661D01*
G01X1358827D02*
X1359417D01*
G01X1357134D02*
X1357724D01*
G01X1354890D02*
X1355480D01*
G01X1353197D02*
X1353787D01*
G01X1350953D02*
X1351543D01*
G01X1349260D02*
X1349850D01*
G01X1347016D02*
X1347606D01*
G01X1345323D02*
X1345913D01*
G01X1343079D02*
X1343669D01*
G01X1341386D02*
X1341976D01*
G01X1339142D02*
X1339732D01*
G01X1337449D02*
X1338039D01*
G01X1335205D02*
X1335795D01*
G01X1333512D02*
X1334102D01*
G01X1331268D02*
X1331858D01*
G01X1329575D02*
X1330165D01*
G01X1327331D02*
X1327921D01*
G01X1325638D02*
X1326228D01*
G01X1323394D02*
X1323984D01*
G01X1321701D02*
X1322291D01*
G01X1325548Y588640D02*
X1324075D01*
G01X1329480D02*
X1328007D01*
G01X1333422D02*
X1331949D01*
G01X1337354D02*
X1335881D01*
G01X1341296D02*
X1339823D01*
G01X1345228D02*
X1343755D01*
G01X1349170D02*
X1347697D01*
G01X1353102D02*
X1351629D01*
G01X1357044D02*
X1355571D01*
G01X1360976D02*
X1359503D01*
G01X1364918D02*
X1363445D01*
G01X1368850D02*
X1367377D01*
G01X1372792D02*
X1371319D01*
G01X1376724D02*
X1375251D01*
G01X1380666D02*
X1379193D01*
G01X1384598D02*
X1383125D01*
G01X1388540D02*
X1387067D01*
G01X1387053Y588621D02*
X1388553D01*
G01X1383112D02*
X1384611D01*
G01X1379179D02*
X1380679D01*
G01X1375238D02*
X1376737D01*
G01X1371305D02*
X1372805D01*
G01X1367364D02*
X1368863D01*
G01X1363431D02*
X1364931D01*
G01X1359490D02*
X1360989D01*
G01X1355557D02*
X1357057D01*
G01X1351616D02*
X1353115D01*
G01X1347683D02*
X1349183D01*
G01X1343742D02*
X1345241D01*
G01X1339809D02*
X1341309D01*
G01X1335868D02*
X1337367D01*
G01X1331935D02*
X1333435D01*
G01X1327994D02*
X1329493D01*
G01X1324061D02*
X1325561D01*
G01X1325817Y588231D02*
X1323805D01*
G01X1329749D02*
X1327738D01*
G01X1333691D02*
X1331679D01*
G01X1337623D02*
X1335612D01*
G01X1341565D02*
X1339553D01*
G01X1345497D02*
X1343486D01*
G01X1349439D02*
X1347427D01*
G01X1353371D02*
X1351360D01*
G01X1357313D02*
X1355301D01*
G01X1361245D02*
X1359234D01*
G01X1365187D02*
X1363175D01*
G01X1369119D02*
X1367108D01*
G01X1373061D02*
X1371049D01*
G01X1376993D02*
X1374982D01*
G01X1380935D02*
X1378924D01*
G01X1384867D02*
X1382856D01*
G01X1388809D02*
X1386798D01*
G01X1322291Y587996D02*
X1321701D01*
G01X1323984D02*
X1323394D01*
G01X1326228D02*
X1325638D01*
G01X1327921D02*
X1327331D01*
G01X1330165D02*
X1329575D01*
G01X1331858D02*
X1331268D01*
G01X1334102D02*
X1333512D01*
G01X1335795D02*
X1335205D01*
G01X1338039D02*
X1337449D01*
G01X1339732D02*
X1339142D01*
G01X1341976D02*
X1341386D01*
G01X1343669D02*
X1343079D01*
G01X1345913D02*
X1345323D01*
G01X1347606D02*
X1347016D01*
G01X1349850D02*
X1349260D01*
G01X1351543D02*
X1350953D01*
G01X1353787D02*
X1353197D01*
G01X1355480D02*
X1354890D01*
G01X1357724D02*
X1357134D01*
G01X1359417D02*
X1358827D01*
G01X1361661D02*
X1361071D01*
G01X1363354D02*
X1362764D01*
G01X1365598D02*
X1365008D01*
G01X1367291D02*
X1366701D01*
G01X1369535D02*
X1368945D01*
G01X1371228D02*
X1370638D01*
G01X1373472D02*
X1372882D01*
G01X1375165D02*
X1374575D01*
G01X1377409D02*
X1376819D01*
G01X1379102D02*
X1378512D01*
G01X1381346D02*
X1380756D01*
G01X1383039D02*
X1382449D01*
G01X1385283D02*
X1384693D01*
G01X1386976D02*
X1386386D01*
G01X1326228Y587839D02*
X1323394D01*
G01X1330165D02*
X1327331D01*
G01X1334102D02*
X1331268D01*
G01X1338039D02*
X1335205D01*
G01X1341976D02*
X1339142D01*
G01X1345913D02*
X1343079D01*
G01X1349850D02*
X1347016D01*
G01X1353787D02*
X1350953D01*
G01X1357724D02*
X1354890D01*
G01X1361661D02*
X1358827D01*
G01X1365598D02*
X1362764D01*
G01X1369535D02*
X1366701D01*
G01X1373472D02*
X1370638D01*
G01X1377409D02*
X1374575D01*
G01X1381346D02*
X1378512D01*
G01X1385283D02*
X1382449D01*
G01X1389220D02*
X1386386D01*
G01X1325638Y587740D02*
X1323984D01*
G01X1333512D02*
X1331858D01*
G01X1341386D02*
X1339732D01*
G01X1349260D02*
X1347606D01*
G01X1357134D02*
X1355480D01*
G01X1365008D02*
X1363354D01*
G01X1372882D02*
X1371228D01*
G01X1380756D02*
X1379102D01*
G01X1388630D02*
X1386976D01*
G01Y587248D02*
X1388630D01*
G01X1379102D02*
X1380756D01*
G01X1371228D02*
X1372882D01*
G01X1363354D02*
X1365008D01*
G01X1355480D02*
X1357134D01*
G01X1347606D02*
X1349260D01*
G01X1339732D02*
X1341386D01*
G01X1331858D02*
X1333512D01*
G01X1323984D02*
X1325638D01*
G01X1386386Y586343D02*
X1389220D01*
G01X1382449D02*
X1385283D01*
G01X1378512D02*
X1381346D01*
G01X1374575D02*
X1377409D01*
G01X1370638D02*
X1373472D01*
G01X1366701D02*
X1369535D01*
G01X1362764D02*
X1365598D01*
G01X1358827D02*
X1361661D01*
G01X1354890D02*
X1357724D01*
G01X1350953D02*
X1353787D01*
G01X1347016D02*
X1349850D01*
G01X1343079D02*
X1345913D01*
G01X1339142D02*
X1341976D01*
G01X1335205D02*
X1338039D01*
G01X1331268D02*
X1334102D01*
G01X1327331D02*
X1330165D01*
G01X1323394D02*
X1326228D01*
G01X1386976Y585476D02*
X1388630D01*
G01X1379102D02*
X1380756D01*
G01X1371228D02*
X1372882D01*
G01X1363354D02*
X1365008D01*
G01X1355480D02*
X1357134D01*
G01X1347606D02*
X1349260D01*
G01X1339732D02*
X1341386D01*
G01X1331858D02*
X1333512D01*
G01X1323984D02*
X1325638D01*
G01X1378748Y585083D02*
X1381110D01*
G01X1374811D02*
X1377173D01*
G01X1370874D02*
X1373236D01*
G01X1366937D02*
X1369299D01*
G01X1325992D02*
X1323630D01*
G01X1329929D02*
X1327567D01*
G01X1333866D02*
X1331504D01*
G01X1337803D02*
X1335441D01*
G01X1341740D02*
X1339378D01*
G01X1345677D02*
X1343315D01*
G01X1349614D02*
X1347252D01*
G01X1353551D02*
X1351189D01*
G01X1357488D02*
X1355126D01*
G01X1361425D02*
X1359063D01*
G01X1365362D02*
X1363000D01*
G01X1385047D02*
X1382685D01*
G01X1388984D02*
X1386622D01*
G01X1325638Y584984D02*
X1323984D01*
G01X1333512D02*
X1331858D01*
G01X1341386D02*
X1339732D01*
G01X1349260D02*
X1347606D01*
G01X1357134D02*
X1355480D01*
G01X1365008D02*
X1363354D01*
G01X1372882D02*
X1371228D01*
G01X1380756D02*
X1379102D01*
G01X1388630D02*
X1386976D01*
G01X1325480Y584886D02*
X1324142D01*
G01X1333354D02*
X1332016D01*
G01X1341228D02*
X1339890D01*
G01X1349102D02*
X1347764D01*
G01X1356976D02*
X1355638D01*
G01X1364850D02*
X1363512D01*
G01X1372724D02*
X1371386D01*
G01X1380598D02*
X1379260D01*
G01X1388472D02*
X1387134D01*
G01X1387275Y604441D02*
X1387284Y604394D01*
G01X1383343Y604441D02*
X1383352Y604394D01*
G01X1384390Y589937D02*
X1384380Y589984D01*
G01X1379410Y604394D02*
X1379401Y604441D01*
G01X1355571Y605738D02*
X1355824Y605368D01*
G01X1355779Y604441D02*
X1355557Y604763D01*
G01X1364709Y589937D02*
X1364931Y589615D01*
G01X1364918Y588640D02*
X1364664Y589010D01*
G01X1351638Y605738D02*
X1351892Y605368D01*
G01X1351846Y604441D02*
X1351625Y604763D01*
G01X1360768Y589937D02*
X1360989Y589615D01*
G01X1360976Y588640D02*
X1360722Y589010D01*
G01X1347697Y605738D02*
X1347950Y605368D01*
G01X1347905Y604441D02*
X1347683Y604763D01*
G01X1356835Y589937D02*
X1357057Y589615D01*
G01X1357044Y588640D02*
X1356790Y589010D01*
G01X1343764Y605738D02*
X1344018Y605368D01*
G01X1343972Y604441D02*
X1343751Y604763D01*
G01X1352894Y589937D02*
X1353115Y589615D01*
G01X1353102Y588640D02*
X1352848Y589010D01*
G01X1339823Y605738D02*
X1340076Y605368D01*
G01X1340031Y604441D02*
X1339809Y604763D01*
G01X1348961Y589937D02*
X1349183Y589615D01*
G01X1349170Y588640D02*
X1348916Y589010D01*
G01X1335890Y605738D02*
X1336144Y605368D01*
G01X1336098Y604441D02*
X1335877Y604763D01*
G01X1345020Y589937D02*
X1345241Y589615D01*
G01X1345228Y588640D02*
X1344974Y589010D01*
G01X1331949Y605738D02*
X1332202Y605368D01*
G01X1332157Y604441D02*
X1331935Y604763D01*
G01X1341087Y589937D02*
X1341309Y589615D01*
G01X1341296Y588640D02*
X1341042Y589010D01*
G01X1328016Y605738D02*
X1328270Y605368D01*
G01X1328224Y604441D02*
X1328003Y604763D01*
G01X1386622Y583902D02*
X1388984D01*
G01X1382685D02*
X1385047D01*
G01X1378748D02*
X1381110D01*
G01X1374811D02*
X1377173D01*
G01X1370874D02*
X1373236D01*
G01X1366937D02*
X1369299D01*
G01X1363000D02*
X1365362D01*
G01X1359063D02*
X1361425D01*
G01X1355126D02*
X1357488D01*
G01X1351189D02*
X1353551D01*
G01X1347252D02*
X1349614D01*
G01X1343315D02*
X1345677D01*
G01X1339378D02*
X1341740D01*
G01X1335441D02*
X1337803D01*
G01X1331504D02*
X1333866D01*
G01X1327567D02*
X1329929D01*
G01X1323630D02*
X1325992D01*
G01X1380448Y589984D02*
X1380457Y589937D01*
G01X1375469Y604441D02*
X1375478Y604394D01*
G01X1376516Y589937D02*
X1376506Y589984D01*
G01X1371536Y604394D02*
X1371527Y604441D01*
G01X1372574Y589984D02*
X1372583Y589937D01*
G01X1367594Y604441D02*
X1367604Y604394D01*
G01X1368642Y589937D02*
X1368632Y589984D01*
G01X1363653Y604441D02*
X1363662Y604394D01*
G01X1364709Y589937D02*
X1364700Y589984D01*
G01X1359720Y604441D02*
X1359730Y604394D01*
G01X1360768Y589937D02*
X1360758Y589984D01*
G01X1355779Y604441D02*
X1355788Y604394D01*
G01X1337146Y589937D02*
X1337367Y589615D01*
G01X1337354Y588640D02*
X1337100Y589010D01*
G01X1324075Y605738D02*
X1324328Y605368D01*
G01X1324283Y604441D02*
X1324061Y604763D01*
G01X1333213Y589937D02*
X1333435Y589615D01*
G01X1333422Y588640D02*
X1333168Y589010D01*
G01X1329272Y589937D02*
X1329493Y589615D01*
G01X1329480Y588640D02*
X1329226Y589010D01*
G01X1325339Y589937D02*
X1325561Y589615D01*
G01X1325548Y588640D02*
X1325294Y589010D01*
G01X1321398Y589937D02*
X1321619Y589615D01*
G01X1321606Y588640D02*
X1321352Y589010D01*
G01X1386798Y588231D02*
X1386934Y594139D01*
G01X1386929Y595025D02*
X1386793Y589117D01*
G01X1387307Y604394D02*
X1387320Y605368D01*
G01X1384357Y589984D02*
X1384344Y589010D01*
G01X1387409Y609492D02*
Y610476D01*
G01Y584886D02*
Y583902D01*
G01X1387134Y584965D02*
Y583902D01*
G01Y610476D02*
Y609413D01*
G01X1387055Y589618D02*
Y588627D01*
G01Y605751D02*
Y604760D01*
G01X1386976Y605555D02*
Y610396D01*
G01Y583982D02*
Y588823D01*
G01X1386780Y605553D02*
Y606538D01*
G01Y587840D02*
Y588825D01*
G01X1386701Y606539D02*
Y587839D01*
G01X1386622Y589984D02*
Y583902D01*
G01Y610476D02*
Y604394D01*
G01X1386425Y588823D02*
Y587839D01*
G01Y606539D02*
Y605555D01*
G01X1386421Y606539D02*
Y605555D01*
G01X1386386Y590516D02*
Y586343D01*
G01Y608035D02*
Y603862D01*
G01X1385283D02*
Y608035D01*
G01Y586343D02*
Y590516D01*
G01X1385249Y606539D02*
Y605555D01*
G01X1385244Y588823D02*
Y587839D01*
G01X1385239Y588823D02*
Y587839D01*
G01X1385047Y589984D02*
Y583902D01*
G01Y610476D02*
Y604394D01*
G01X1384968Y587839D02*
Y606539D01*
G01X1384894Y606538D02*
Y605553D01*
G01X1384885Y588825D02*
Y587840D01*
G01X1384693Y601698D02*
Y606539D01*
G01Y587839D02*
Y592680D01*
G01X1384619Y604760D02*
Y605751D01*
G01X1384610Y588627D02*
Y589618D01*
G01X1384535Y592760D02*
Y591696D01*
G01Y602681D02*
Y601618D01*
G01X1384260D02*
Y602602D01*
G01Y592760D02*
Y591776D01*
G01X1383472Y601618D02*
Y602602D01*
G01Y591776D02*
Y592760D01*
G01X1383197D02*
Y591696D01*
G01Y602682D02*
Y601618D01*
G01X1383123Y605751D02*
Y604760D01*
G01X1383113Y589618D02*
Y588627D01*
G01X1383039Y601698D02*
Y606539D01*
G01Y587839D02*
Y592680D01*
G01X1382847Y605553D02*
Y606538D01*
G01X1382838Y587840D02*
Y588825D01*
G01X1382764Y606539D02*
Y587839D01*
G01X1382685Y589984D02*
Y583902D01*
G01Y610476D02*
Y604394D01*
G01X1382493Y606539D02*
Y605555D01*
G01X1382488Y606539D02*
Y605555D01*
G01X1382484Y588823D02*
Y587839D01*
G01X1382449Y590516D02*
Y586343D01*
G01Y608035D02*
Y603862D01*
G01X1387320Y589010D02*
X1387307Y589984D01*
G01X1384353Y605368D02*
X1384367Y604394D01*
G01X1383379Y589010D02*
X1383366Y589984D01*
G01X1380412Y605368D02*
X1380425Y604394D01*
G01X1386934Y600239D02*
X1386798Y606147D01*
G01X1386793Y605261D02*
X1386929Y599353D01*
G01X1384872Y589117D02*
X1384736Y595025D01*
G01X1384731Y594139D02*
X1384867Y588231D01*
G01X1383001Y600239D02*
X1382865Y606147D01*
G01X1382860Y605261D02*
X1382997Y599353D01*
G01X1380940Y589117D02*
X1380803Y595025D01*
G01X1380799Y594139D02*
X1380935Y588231D01*
G01X1379060Y600239D02*
X1378924Y606147D01*
G01X1378919Y605261D02*
X1379055Y599353D01*
G01X1387008Y594341D02*
X1386957Y595327D01*
G01X1386955Y594365D02*
X1387006Y593379D01*
G01X1384719Y600013D02*
X1384668Y600999D01*
G01X1384666Y600037D02*
X1384717Y599051D01*
G01X1383066Y594341D02*
X1383016Y595327D01*
G01X1383013Y594365D02*
X1383064Y593379D01*
G01X1380777Y600013D02*
X1380727Y600999D01*
G01X1380724Y600037D02*
X1380775Y599051D01*
G01X1379134Y594341D02*
X1379083Y595327D01*
G01X1379081Y594365D02*
X1379132Y593379D01*
G01X1376845Y600013D02*
X1376794Y600999D01*
G01X1376792Y600037D02*
X1376843Y599051D01*
G01X1356835Y589937D02*
X1356826Y589984D01*
G01X1351846Y604441D02*
X1351856Y604394D01*
G01X1352894Y589937D02*
X1352884Y589984D01*
G01X1347905Y604441D02*
X1347914Y604394D01*
G01X1348961Y589937D02*
X1348952Y589984D01*
G01X1343972Y604441D02*
X1343982Y604394D01*
G01X1345020Y589937D02*
X1345010Y589984D01*
G01X1340031Y604441D02*
X1340040Y604394D01*
G01X1341087Y589937D02*
X1341078Y589984D01*
G01X1336098Y604441D02*
X1336108Y604394D01*
G01X1337146Y589937D02*
X1337136Y589984D01*
G01X1332157Y604441D02*
X1332166Y604394D01*
G01X1333213Y589937D02*
X1333204Y589984D01*
G01X1387284D02*
X1387275Y589937D01*
G01X1386957Y599051D02*
X1387008Y600037D01*
G01X1387006Y600999D02*
X1386955Y600013D01*
G01X1384659Y593379D02*
X1384710Y594365D01*
G01X1384707Y595327D02*
X1384657Y594341D01*
G01X1383025Y599051D02*
X1383076Y600037D01*
G01X1383073Y600999D02*
X1383023Y600013D01*
G01X1380727Y593379D02*
X1380777Y594365D01*
G01X1380775Y595327D02*
X1380724Y594341D01*
G01X1379083Y599051D02*
X1379134Y600037D01*
G01X1379132Y600999D02*
X1379081Y600013D01*
G01X1376785Y593379D02*
X1376836Y594365D01*
G01X1376833Y595327D02*
X1376783Y594341D01*
G01X1375151Y599051D02*
X1375202Y600037D01*
G01X1375199Y600999D02*
X1375149Y600013D01*
G01X1372853Y593379D02*
X1372903Y594365D01*
G01X1372901Y595327D02*
X1372850Y594341D01*
G01X1371209Y599051D02*
X1371260Y600037D01*
G01X1371258Y600999D02*
X1371207Y600013D01*
G01X1368911Y593379D02*
X1368962Y594365D01*
G01X1368959Y595327D02*
X1368909Y594341D01*
G01X1367277Y599051D02*
X1367328Y600037D01*
G01X1367325Y600999D02*
X1367275Y600013D01*
G01X1364979Y593379D02*
X1365029Y594365D01*
G01X1365027Y595327D02*
X1364976Y594341D01*
G01X1384745Y599353D02*
X1384881Y605261D01*
G01X1384876Y606147D02*
X1384740Y600239D01*
G01X1382856Y588231D02*
X1382992Y594139D01*
G01X1382987Y595025D02*
X1382851Y589117D01*
G01X1380803Y599353D02*
X1380940Y605261D01*
G01X1380935Y606147D02*
X1380799Y600239D01*
G01X1378924Y588231D02*
X1379060Y594139D01*
G01X1379055Y595025D02*
X1378919Y589117D01*
G01X1376871Y599353D02*
X1377007Y605261D01*
G01X1377002Y606147D02*
X1376866Y600239D01*
G01X1374982Y588231D02*
X1375118Y594139D01*
G01X1375113Y595025D02*
X1374977Y589117D01*
G01X1372929Y599353D02*
X1373066Y605261D01*
G01X1373061Y606147D02*
X1372925Y600239D01*
G01X1371049Y588231D02*
X1371186Y594139D01*
G01X1371181Y595025D02*
X1371045Y589117D01*
G01X1368997Y599353D02*
X1369133Y605261D01*
G01X1369128Y606147D02*
X1368992Y600239D01*
G01X1367108Y588231D02*
X1367244Y594139D01*
G01X1367239Y595025D02*
X1367103Y589117D01*
G01X1365055Y599353D02*
X1365192Y605261D01*
G01X1365187Y606147D02*
X1365051Y600239D01*
G01X1363175Y588231D02*
X1363312Y594139D01*
G01X1363307Y595025D02*
X1363171Y589117D01*
G01X1361123Y599353D02*
X1361259Y605261D01*
G01X1361254Y606147D02*
X1361118Y600239D01*
G01X1383375Y604394D02*
X1383388Y605368D01*
G01X1380425Y589984D02*
X1380412Y589010D01*
G01X1379433Y604394D02*
X1379446Y605368D01*
G01X1376483Y589984D02*
X1376470Y589010D01*
G01X1375501Y604394D02*
X1375514Y605368D01*
G01X1372551Y589984D02*
X1372538Y589010D01*
G01X1371559Y604394D02*
X1371572Y605368D01*
G01X1368609Y589984D02*
X1368596Y589010D01*
G01X1367627Y604394D02*
X1367640Y605368D01*
G01X1364677Y589984D02*
X1364664Y589010D01*
G01X1363685Y604394D02*
X1363698Y605368D01*
G01X1360735Y589984D02*
X1360722Y589010D01*
G01X1359753Y604394D02*
X1359766Y605368D01*
G01X1381346Y603862D02*
Y608035D01*
G01Y586343D02*
Y590516D01*
G01X1381312Y588823D02*
Y587839D01*
G01X1381307Y588823D02*
Y587839D01*
G01Y606539D02*
Y605555D01*
G01X1381110Y589984D02*
Y583902D01*
G01Y610476D02*
Y604394D01*
G01X1381031Y587839D02*
Y606539D01*
G01X1380953Y588825D02*
Y587840D01*
G01Y606538D02*
Y605553D01*
G01X1380756Y605555D02*
Y610396D01*
G01Y583982D02*
Y588823D01*
G01X1380677Y604760D02*
Y605751D01*
G01Y588627D02*
Y589618D01*
G01X1380598Y584965D02*
Y583902D01*
G01Y610476D02*
Y609413D01*
G01X1380323Y583902D02*
Y584886D01*
G01Y610476D02*
Y609492D01*
G01X1379535Y584886D02*
Y583902D01*
G01Y610476D02*
Y609492D01*
G01X1379260Y584965D02*
Y583902D01*
G01Y610476D02*
Y609413D01*
G01X1379181Y589618D02*
Y588627D01*
G01Y605751D02*
Y604760D01*
G01X1379102Y605555D02*
Y610396D01*
G01Y583982D02*
Y588823D01*
G01X1378906Y587840D02*
Y588825D01*
G01Y605553D02*
Y606538D01*
G01X1378827Y606539D02*
Y587839D01*
G01X1378748Y589984D02*
Y583902D01*
G01Y610476D02*
Y604394D01*
G01X1378551Y588823D02*
Y587839D01*
G01Y606539D02*
Y605555D01*
G01X1378547Y606539D02*
Y605555D01*
G01X1378512Y590516D02*
Y586343D01*
G01Y608035D02*
Y603862D01*
G01X1377409D02*
Y608035D01*
G01Y586343D02*
Y590516D01*
G01X1377375Y606539D02*
Y605555D01*
G01X1377370Y588823D02*
Y587839D01*
G01X1377365Y588823D02*
Y587839D01*
G01X1377173Y589984D02*
Y583902D01*
G01Y610476D02*
Y604394D01*
G01X1377094Y587839D02*
Y606539D01*
G01X1377020Y606538D02*
Y605553D01*
G01X1377011Y588825D02*
Y587840D01*
G01X1376819Y601698D02*
Y606539D01*
G01Y587839D02*
Y592680D01*
G01X1376745Y604760D02*
Y605751D01*
G01X1376735Y588627D02*
Y589618D01*
G01X1376661Y592760D02*
Y591696D01*
G01Y602681D02*
Y601618D01*
G01X1376386D02*
Y602602D01*
G01Y592760D02*
Y591776D01*
G01X1375598Y601618D02*
Y602602D01*
G01Y592760D02*
Y591776D01*
G01X1375323Y592760D02*
Y591696D01*
G01Y602682D02*
Y601618D01*
G01X1375249Y605751D02*
Y604760D01*
G01X1375239Y589618D02*
Y588627D01*
G01X1375165Y601698D02*
Y606539D01*
G01Y587839D02*
Y592680D01*
G01X1374973Y605553D02*
Y606538D01*
G01X1374964Y587840D02*
Y588825D01*
G01X1374890Y606539D02*
Y587839D01*
G01X1374811Y589984D02*
Y583902D01*
G01Y610476D02*
Y604394D01*
G01X1374619Y606539D02*
Y605555D01*
G01X1374614Y606539D02*
Y605555D01*
G01X1374610Y588823D02*
Y587839D01*
G01X1374575Y590516D02*
Y586343D01*
G01Y608035D02*
Y603862D01*
G01X1373472D02*
Y608035D01*
G01Y586343D02*
Y590516D01*
G01X1373438Y588823D02*
Y587839D01*
G01X1373433Y588823D02*
Y587839D01*
G01Y606539D02*
Y605555D01*
G01X1373236Y589984D02*
Y583902D01*
G01Y610476D02*
Y604394D01*
G01X1373157Y587839D02*
Y606539D01*
G01X1373079Y588825D02*
Y587840D01*
G01Y606538D02*
Y605553D01*
G01X1372882Y605555D02*
Y610396D01*
G01Y583982D02*
Y588823D01*
G01X1372803Y604760D02*
Y605751D01*
G01Y588627D02*
Y589618D01*
G01X1372724Y584965D02*
Y583902D01*
G01Y610476D02*
Y609413D01*
G01X1372449Y583902D02*
Y584886D01*
G01Y610476D02*
Y609492D01*
G01X1371661Y584886D02*
Y583902D01*
G01Y610476D02*
Y609492D01*
G01X1371386Y584965D02*
Y583902D01*
G01Y610476D02*
Y609413D01*
G01X1371307Y589618D02*
Y588627D01*
G01Y605751D02*
Y604760D01*
G01X1371228Y605555D02*
Y610396D01*
G01Y583982D02*
Y588823D01*
G01X1371031Y587840D02*
Y588825D01*
G01Y605553D02*
Y606538D01*
G01X1370953Y606539D02*
Y587839D01*
G01X1370874Y589984D02*
Y583902D01*
G01Y610476D02*
Y604394D01*
G01X1370677Y588823D02*
Y587839D01*
G01Y606539D02*
Y605555D01*
G01X1370672Y606539D02*
Y605555D01*
G01X1370638Y590516D02*
Y586343D01*
G01Y608035D02*
Y603862D01*
G01X1369535D02*
Y608035D01*
G01Y586343D02*
Y590516D01*
G01X1369501Y606539D02*
Y605555D01*
G01X1369496Y588823D02*
Y587839D01*
G01X1369491Y588823D02*
Y587839D01*
G01X1369299Y589984D02*
Y583902D01*
G01Y610476D02*
Y604394D01*
G01X1369220Y587839D02*
Y606539D01*
G01X1369146Y606538D02*
Y605553D01*
G01X1369137Y588825D02*
Y587840D01*
G01X1368945Y601698D02*
Y606539D01*
G01Y587839D02*
Y592680D01*
G01X1368871Y604760D02*
Y605751D01*
G01X1368861Y588627D02*
Y589618D01*
G01X1368787Y592760D02*
Y591696D01*
G01Y602681D02*
Y601618D01*
G01X1368512D02*
Y602602D01*
G01Y592760D02*
Y591776D01*
G01X1367724Y601618D02*
Y602602D01*
G01Y592760D02*
Y591776D01*
G01X1367449Y592760D02*
Y591696D01*
G01Y602682D02*
Y601618D01*
G01X1367375Y605751D02*
Y604760D01*
G01X1367365Y589618D02*
Y588627D01*
G01X1367291Y601698D02*
Y606539D01*
G01Y587839D02*
Y592680D01*
G01X1367099Y605553D02*
Y606538D01*
G01X1367090Y587840D02*
Y588825D01*
G01X1367016Y606539D02*
Y587839D01*
G01X1366937Y589984D02*
Y583902D01*
G01Y610476D02*
Y604394D01*
G01X1366745Y606539D02*
Y605555D01*
G01X1366740Y606539D02*
Y605555D01*
G01X1366735Y588823D02*
Y587839D01*
G01X1366701Y590516D02*
Y586343D01*
G01Y608035D02*
Y603862D01*
G01X1365598D02*
Y608035D01*
G01Y586343D02*
Y590516D01*
G01X1365564Y588823D02*
Y587839D01*
G01X1365559Y588823D02*
Y587839D01*
G01Y606539D02*
Y605555D01*
G01X1365362Y589984D02*
Y583902D01*
G01Y610476D02*
Y604394D01*
G01X1365283Y587839D02*
Y606539D01*
G01X1365205Y588825D02*
Y587840D01*
G01Y606538D02*
Y605553D01*
G01X1365008Y605555D02*
Y610396D01*
G01Y583982D02*
Y588823D01*
G01X1364929Y604760D02*
Y605751D01*
G01Y588627D02*
Y589618D01*
G01X1364850Y584965D02*
Y583902D01*
G01Y610476D02*
Y609413D01*
G01X1364575Y584886D02*
Y583902D01*
G01Y610476D02*
Y609492D01*
G01X1363787D02*
Y610476D01*
G01Y584886D02*
Y583902D01*
G01X1363512Y584965D02*
Y583902D01*
G01Y610476D02*
Y609413D01*
G01X1363433Y589618D02*
Y588627D01*
G01Y605751D02*
Y604760D01*
G01X1363354Y605555D02*
Y610396D01*
G01Y583982D02*
Y588823D01*
G01X1363157Y605553D02*
Y606538D01*
G01Y587840D02*
Y588825D01*
G01X1363079Y606539D02*
Y587839D01*
G01X1363000Y589984D02*
Y583902D01*
G01Y610476D02*
Y604394D01*
G01X1362803Y588823D02*
Y587839D01*
G01Y606539D02*
Y605555D01*
G01X1362798Y606539D02*
Y605555D01*
G01X1362764Y590516D02*
Y586343D01*
G01Y608035D02*
Y603862D01*
G01X1361661D02*
Y608035D01*
G01Y586343D02*
Y590516D01*
G01X1361627Y606539D02*
Y605555D01*
G01X1361622Y588823D02*
Y587839D01*
G01X1361617Y588823D02*
Y587839D01*
G01X1361425Y589984D02*
Y583902D01*
G01Y610476D02*
Y604394D01*
G01X1361346Y587839D02*
Y606539D01*
G01X1361272Y606538D02*
Y605553D01*
G01X1361263Y588825D02*
Y587840D01*
G01X1361071Y601698D02*
Y606539D01*
G01Y587839D02*
Y592680D01*
G01X1360997Y604760D02*
Y605751D01*
G01X1360987Y588627D02*
Y589618D01*
G01X1360913Y592760D02*
Y591696D01*
G01Y602681D02*
Y601618D01*
G01X1360638Y592760D02*
Y591776D01*
G01Y602602D02*
Y601618D01*
G01X1359850Y592760D02*
Y591776D01*
G01Y602602D02*
Y601618D01*
G01X1359575Y592760D02*
Y591696D01*
G01Y602682D02*
Y601618D01*
G01X1359501Y605751D02*
Y604760D01*
G01X1359491Y589618D02*
Y588627D01*
G01X1359417Y601698D02*
Y606539D01*
G01Y587839D02*
Y592680D01*
G01X1359225Y605553D02*
Y606538D01*
G01X1359216Y587840D02*
Y588825D01*
G01X1359142Y606539D02*
Y587839D01*
G01X1359063Y589984D02*
Y583902D01*
G01Y610476D02*
Y604394D01*
G01X1358871Y606539D02*
Y605555D01*
G01X1358866Y606539D02*
Y605555D01*
G01X1358861Y588823D02*
Y587839D01*
G01X1358827Y590516D02*
Y586343D01*
G01Y608035D02*
Y603862D01*
G01X1357724D02*
Y608035D01*
G01Y586343D02*
Y590516D01*
G01X1357690Y588823D02*
Y587839D01*
G01X1357685Y588823D02*
Y587839D01*
G01Y606539D02*
Y605555D01*
G01X1379446Y589010D02*
X1379433Y589984D01*
G01X1376479Y605368D02*
X1376493Y604394D01*
G01X1375505Y589010D02*
X1375492Y589984D01*
G01X1372538Y605368D02*
X1372551Y604394D01*
G01X1371572Y589010D02*
X1371559Y589984D01*
G01X1368605Y605368D02*
X1368619Y604394D01*
G01X1367631Y589010D02*
X1367618Y589984D01*
G01X1364664Y605368D02*
X1364677Y604394D01*
G01X1363698Y589010D02*
X1363685Y589984D01*
G01X1360731Y605368D02*
X1360745Y604394D01*
G01X1359757Y589010D02*
X1359744Y589984D01*
G01X1356790Y605368D02*
X1356803Y604394D01*
G01X1376998Y589117D02*
X1376862Y595025D01*
G01X1376857Y594139D02*
X1376993Y588231D01*
G01X1375127Y600239D02*
X1374991Y606147D01*
G01X1374986Y605261D02*
X1375123Y599353D01*
G01X1373066Y589117D02*
X1372929Y595025D01*
G01X1372925Y594139D02*
X1373061Y588231D01*
G01X1371186Y600239D02*
X1371049Y606147D01*
G01X1371045Y605261D02*
X1371181Y599353D01*
G01X1369124Y589117D02*
X1368988Y595025D01*
G01X1368983Y594139D02*
X1369119Y588231D01*
G01X1367253Y600239D02*
X1367117Y606147D01*
G01X1367112Y605261D02*
X1367249Y599353D01*
G01X1365192Y589117D02*
X1365055Y595025D01*
G01X1365051Y594139D02*
X1365187Y588231D01*
G01X1363312Y600239D02*
X1363175Y606147D01*
G01X1363171Y605261D02*
X1363307Y599353D01*
G01X1361250Y589117D02*
X1361114Y595025D01*
G01X1361109Y594139D02*
X1361245Y588231D01*
G01X1359379Y600239D02*
X1359243Y606147D01*
G01X1359238Y605261D02*
X1359375Y599353D01*
G01X1357317Y589117D02*
X1357181Y595025D01*
G01X1357176Y594139D02*
X1357313Y588231D01*
G01X1355438Y600239D02*
X1355301Y606147D01*
G01X1355297Y605261D02*
X1355433Y599353D01*
G01X1375192Y594341D02*
X1375142Y595327D01*
G01X1375139Y594365D02*
X1375190Y593379D01*
G01X1372903Y600013D02*
X1372853Y600999D01*
G01X1372850Y600037D02*
X1372901Y599051D01*
G01X1371260Y594341D02*
X1371209Y595327D01*
G01X1371207Y594365D02*
X1371258Y593379D01*
G01X1368971Y600013D02*
X1368920Y600999D01*
G01X1368918Y600037D02*
X1368969Y599051D01*
G01X1367318Y594341D02*
X1367268Y595327D01*
G01X1367265Y594365D02*
X1367316Y593379D01*
G01X1365029Y600013D02*
X1364979Y600999D01*
G01X1364976Y600037D02*
X1365027Y599051D01*
G01X1363386Y594341D02*
X1363335Y595327D01*
G01X1363333Y594365D02*
X1363384Y593379D01*
G01X1361097Y600013D02*
X1361046Y600999D01*
G01X1361044Y600037D02*
X1361094Y599051D01*
G01X1359444Y594341D02*
X1359394Y595327D01*
G01X1359391Y594365D02*
X1359442Y593379D01*
G01X1357155Y600013D02*
X1357105Y600999D01*
G01X1357102Y600037D02*
X1357153Y599051D01*
G01X1355512Y594341D02*
X1355461Y595327D01*
G01X1355459Y594365D02*
X1355510Y593379D01*
G01X1353223Y600013D02*
X1353172Y600999D01*
G01X1353170Y600037D02*
X1353220Y599051D01*
G01X1351570Y594341D02*
X1351520Y595327D01*
G01X1351517Y594365D02*
X1351568Y593379D01*
G01X1328224Y604441D02*
X1328234Y604394D01*
G01X1329272Y589937D02*
X1329262Y589984D01*
G01X1324283Y604441D02*
X1324292Y604394D01*
G01X1325339Y589937D02*
X1325330Y589984D01*
G01X1320350Y604441D02*
X1320360Y604394D01*
G01X1321398Y589937D02*
X1321388Y589984D01*
G01X1383343D02*
X1383333Y589937D01*
G01X1384390Y604394D02*
X1384399Y604441D01*
G01X1379401Y589937D02*
X1379410Y589984D01*
G01X1380457Y604441D02*
X1380448Y604394D01*
G01X1375469Y589984D02*
X1375459Y589937D01*
G01X1376515Y604394D02*
X1376525Y604441D01*
G01X1371527Y589937D02*
X1371536Y589984D01*
G01X1372583Y604441D02*
X1372574Y604394D01*
G01X1367595Y589984D02*
X1367585Y589937D01*
G01X1368641Y604394D02*
X1368651Y604441D01*
G01X1363662Y589984D02*
X1363653Y589937D01*
G01X1364700Y604394D02*
X1364709Y604441D01*
G01X1363335Y599051D02*
X1363386Y600037D01*
G01X1363384Y600999D02*
X1363333Y600013D01*
G01X1361037Y593379D02*
X1361087Y594365D01*
G01X1361085Y595327D02*
X1361035Y594341D01*
G01X1359403Y599051D02*
X1359454Y600037D01*
G01X1359451Y600999D02*
X1359401Y600013D01*
G01X1357105Y593379D02*
X1357155Y594365D01*
G01X1357153Y595327D02*
X1357102Y594341D01*
G01X1355461Y599051D02*
X1355512Y600037D01*
G01X1355510Y600999D02*
X1355459Y600013D01*
G01X1353163Y593379D02*
X1353213Y594365D01*
G01X1353211Y595327D02*
X1353161Y594341D01*
G01X1351529Y599051D02*
X1351579Y600037D01*
G01X1351577Y600999D02*
X1351527Y600013D01*
G01X1349231Y593379D02*
X1349281Y594365D01*
G01X1349279Y595327D02*
X1349228Y594341D01*
G01X1347587Y599051D02*
X1347638Y600037D01*
G01X1347635Y600999D02*
X1347585Y600013D01*
G01X1345289Y593379D02*
X1345339Y594365D01*
G01X1345337Y595327D02*
X1345287Y594341D01*
G01X1343655Y599051D02*
X1343705Y600037D01*
G01X1343703Y600999D02*
X1343653Y600013D01*
G01X1341357Y593379D02*
X1341407Y594365D01*
G01X1341405Y595327D02*
X1341354Y594341D01*
G01X1359234Y588231D02*
X1359370Y594139D01*
G01X1359365Y595025D02*
X1359229Y589117D01*
G01X1357181Y599353D02*
X1357317Y605261D01*
G01X1357313Y606147D02*
X1357176Y600239D01*
G01X1355301Y588231D02*
X1355438Y594139D01*
G01X1355433Y595025D02*
X1355297Y589117D01*
G01X1353249Y599353D02*
X1353385Y605261D01*
G01X1353380Y606147D02*
X1353244Y600239D01*
G01X1351360Y588231D02*
X1351496Y594139D01*
G01X1351491Y595025D02*
X1351355Y589117D01*
G01X1349307Y599353D02*
X1349443Y605261D01*
G01X1349439Y606147D02*
X1349302Y600239D01*
G01X1347427Y588231D02*
X1347564Y594139D01*
G01X1347559Y595025D02*
X1347423Y589117D01*
G01X1345375Y599353D02*
X1345511Y605261D01*
G01X1345506Y606147D02*
X1345370Y600239D01*
G01X1343486Y588231D02*
X1343622Y594139D01*
G01X1343617Y595025D02*
X1343481Y589117D01*
G01X1341433Y599353D02*
X1341569Y605261D01*
G01X1341565Y606147D02*
X1341428Y600239D01*
G01X1339553Y588231D02*
X1339690Y594139D01*
G01X1339685Y595025D02*
X1339549Y589117D01*
G01X1337501Y599353D02*
X1337637Y605261D01*
G01X1337632Y606147D02*
X1337496Y600239D01*
G01X1356803Y589984D02*
X1356790Y589010D01*
G01X1355811Y604394D02*
X1355824Y605368D01*
G01X1352861Y589984D02*
X1352848Y589010D01*
G01X1351879Y604394D02*
X1351892Y605368D01*
G01X1348929Y589984D02*
X1348916Y589010D01*
G01X1347937Y604394D02*
X1347950Y605368D01*
G01X1344987Y589984D02*
X1344974Y589010D01*
G01X1344005Y604394D02*
X1344018Y605368D01*
G01X1341055Y589984D02*
X1341042Y589010D01*
G01X1340063Y604394D02*
X1340076Y605368D01*
G01X1337113Y589984D02*
X1337100Y589010D01*
G01X1336131Y604394D02*
X1336144Y605368D01*
G01X1357488Y589984D02*
Y583902D01*
G01Y610476D02*
Y604394D01*
G01X1357409Y587839D02*
Y606539D01*
G01X1357331Y588825D02*
Y587840D01*
G01Y606538D02*
Y605553D01*
G01X1357134Y605555D02*
Y610396D01*
G01Y583982D02*
Y588823D01*
G01X1357055Y604760D02*
Y605751D01*
G01Y588627D02*
Y589618D01*
G01X1356976Y584965D02*
Y583902D01*
G01Y610476D02*
Y609413D01*
G01X1356701Y584886D02*
Y583902D01*
G01Y610476D02*
Y609492D01*
G01X1355913D02*
Y610476D01*
G01Y584886D02*
Y583902D01*
G01X1355638Y584965D02*
Y583902D01*
G01Y610476D02*
Y609413D01*
G01X1355559Y589618D02*
Y588627D01*
G01Y605751D02*
Y604760D01*
G01X1355480Y605555D02*
Y610396D01*
G01Y583982D02*
Y588823D01*
G01X1355283Y605553D02*
Y606538D01*
G01Y587840D02*
Y588825D01*
G01X1355205Y606539D02*
Y587839D01*
G01X1355126Y589984D02*
Y583902D01*
G01Y610476D02*
Y604394D01*
G01X1354929Y588823D02*
Y587839D01*
G01Y606539D02*
Y605555D01*
G01X1354924Y606539D02*
Y605555D01*
G01X1354890Y590516D02*
Y586343D01*
G01Y608035D02*
Y603862D01*
G01X1353787D02*
Y608035D01*
G01Y586343D02*
Y590516D01*
G01X1353753Y606539D02*
Y605555D01*
G01X1353748Y588823D02*
Y587839D01*
G01X1353743Y588823D02*
Y587839D01*
G01X1353551Y589984D02*
Y583902D01*
G01Y610476D02*
Y604394D01*
G01X1353472Y587839D02*
Y606539D01*
G01X1353398Y606538D02*
Y605553D01*
G01X1353389Y588825D02*
Y587840D01*
G01X1353197Y601698D02*
Y606539D01*
G01Y587839D02*
Y592680D01*
G01X1353123Y604760D02*
Y605751D01*
G01X1353113Y588627D02*
Y589618D01*
G01X1353039Y592760D02*
Y591696D01*
G01Y602681D02*
Y601618D01*
G01X1352764D02*
Y602602D01*
G01Y592760D02*
Y591776D01*
G01X1351976Y601618D02*
Y602602D01*
G01Y591776D02*
Y592760D01*
G01X1351701D02*
Y591696D01*
G01Y602682D02*
Y601618D01*
G01X1351627Y605751D02*
Y604760D01*
G01X1351617Y589618D02*
Y588627D01*
G01X1351543Y601698D02*
Y606539D01*
G01Y587839D02*
Y592680D01*
G01X1351351Y605553D02*
Y606538D01*
G01X1351342Y587840D02*
Y588825D01*
G01X1351268Y606539D02*
Y587839D01*
G01X1351189Y589984D02*
Y583902D01*
G01Y610476D02*
Y604394D01*
G01X1350997Y606539D02*
Y605555D01*
G01X1350992Y606539D02*
Y605555D01*
G01X1350987Y588823D02*
Y587839D01*
G01X1350953Y590516D02*
Y586343D01*
G01Y608035D02*
Y603862D01*
G01X1349850D02*
Y608035D01*
G01Y586343D02*
Y590516D01*
G01X1349816Y588823D02*
Y587839D01*
G01X1349811Y588823D02*
Y587839D01*
G01Y606539D02*
Y605555D01*
G01X1349614Y589984D02*
Y583902D01*
G01Y610476D02*
Y604394D01*
G01X1349535Y587839D02*
Y606539D01*
G01X1349457Y588825D02*
Y587840D01*
G01Y606538D02*
Y605553D01*
G01X1349260Y605555D02*
Y610396D01*
G01Y583982D02*
Y588823D01*
G01X1349181Y604760D02*
Y605751D01*
G01Y588627D02*
Y589618D01*
G01X1349102Y584965D02*
Y583902D01*
G01Y610476D02*
Y609413D01*
G01X1348827Y584886D02*
Y583902D01*
G01Y610476D02*
Y609492D01*
G01X1348039D02*
Y610476D01*
G01Y584886D02*
Y583902D01*
G01X1347764Y584965D02*
Y583902D01*
G01Y610476D02*
Y609413D01*
G01X1347685Y589618D02*
Y588627D01*
G01Y605751D02*
Y604760D01*
G01X1347606Y605555D02*
Y610396D01*
G01Y583982D02*
Y588823D01*
G01X1347409Y605553D02*
Y606538D01*
G01Y587840D02*
Y588825D01*
G01X1347331Y606539D02*
Y587839D01*
G01X1347252Y589984D02*
Y583902D01*
G01Y610476D02*
Y604394D01*
G01X1347055Y588823D02*
Y587839D01*
G01Y606539D02*
Y605555D01*
G01X1347050Y606539D02*
Y605555D01*
G01X1347016Y590516D02*
Y586343D01*
G01Y608035D02*
Y603862D01*
G01X1345913D02*
Y608035D01*
G01Y586343D02*
Y590516D01*
G01X1345879Y606539D02*
Y605555D01*
G01X1345874Y588823D02*
Y587839D01*
G01X1345869Y588823D02*
Y587839D01*
G01X1345677Y589984D02*
Y583902D01*
G01Y610476D02*
Y604394D01*
G01X1345598Y587839D02*
Y606539D01*
G01X1345524Y606538D02*
Y605553D01*
G01X1345515Y588825D02*
Y587840D01*
G01X1345323Y601698D02*
Y606539D01*
G01Y587839D02*
Y592680D01*
G01X1345249Y604760D02*
Y605751D01*
G01X1345239Y588627D02*
Y589618D01*
G01X1345165Y592760D02*
Y591696D01*
G01Y602681D02*
Y601618D01*
G01X1344890D02*
Y602602D01*
G01Y592760D02*
Y591776D01*
G01X1344102Y601618D02*
Y602602D01*
G01Y591776D02*
Y592760D01*
G01X1343827D02*
Y591696D01*
G01Y602682D02*
Y601618D01*
G01X1343753Y605751D02*
Y604760D01*
G01X1343743Y589618D02*
Y588627D01*
G01X1343669Y601698D02*
Y606539D01*
G01Y587839D02*
Y592680D01*
G01X1343477Y605553D02*
Y606538D01*
G01X1343468Y587840D02*
Y588825D01*
G01X1343394Y606539D02*
Y587839D01*
G01X1343315Y589984D02*
Y583902D01*
G01Y610476D02*
Y604394D01*
G01X1343123Y606539D02*
Y605555D01*
G01X1343118Y606539D02*
Y605555D01*
G01X1343113Y588823D02*
Y587839D01*
G01X1343079Y590516D02*
Y586343D01*
G01Y608035D02*
Y603862D01*
G01X1341976D02*
Y608035D01*
G01Y586343D02*
Y590516D01*
G01X1341942Y588823D02*
Y587839D01*
G01X1341937Y588823D02*
Y587839D01*
G01Y606539D02*
Y605555D01*
G01X1341740Y589984D02*
Y583902D01*
G01Y610476D02*
Y604394D01*
G01X1341661Y587839D02*
Y606539D01*
G01X1341583Y588825D02*
Y587840D01*
G01Y606538D02*
Y605553D01*
G01X1341386Y605555D02*
Y610396D01*
G01Y583982D02*
Y588823D01*
G01X1341307Y604760D02*
Y605751D01*
G01Y588627D02*
Y589618D01*
G01X1341228Y584965D02*
Y583902D01*
G01Y610476D02*
Y609413D01*
G01X1340953Y584886D02*
Y583902D01*
G01Y610476D02*
Y609492D01*
G01X1340165D02*
Y610476D01*
G01Y584886D02*
Y583902D01*
G01X1339890Y584965D02*
Y583902D01*
G01Y610476D02*
Y609413D01*
G01X1339811Y589618D02*
Y588627D01*
G01Y605751D02*
Y604760D01*
G01X1339732Y605555D02*
Y610396D01*
G01Y583982D02*
Y588823D01*
G01X1339535Y587840D02*
Y588825D01*
G01Y605553D02*
Y606538D01*
G01X1339457Y606539D02*
Y587839D01*
G01X1339378Y589984D02*
Y583902D01*
G01Y610476D02*
Y604394D01*
G01X1339181Y588823D02*
Y587839D01*
G01Y606539D02*
Y605555D01*
G01X1339176Y606539D02*
Y605555D01*
G01X1339142Y590516D02*
Y586343D01*
G01Y608035D02*
Y603862D01*
G01X1338039D02*
Y608035D01*
G01Y586343D02*
Y590516D01*
G01X1338005Y606539D02*
Y605555D01*
G01X1338000Y588823D02*
Y587839D01*
G01X1337995Y588823D02*
Y587839D01*
G01X1337803Y589984D02*
Y583902D01*
G01Y610476D02*
Y604394D01*
G01X1337724Y587839D02*
Y606539D01*
G01X1337650Y606538D02*
Y605553D01*
G01X1337641Y588825D02*
Y587840D01*
G01X1337449Y601698D02*
Y606539D01*
G01Y587839D02*
Y592680D01*
G01X1337375Y604760D02*
Y605751D01*
G01X1337365Y588627D02*
Y589618D01*
G01X1337291Y592760D02*
Y591696D01*
G01Y602681D02*
Y601618D01*
G01X1337016Y592760D02*
Y591776D01*
G01Y602602D02*
Y601618D01*
G01X1336228Y592760D02*
Y591776D01*
G01Y602602D02*
Y601618D01*
G01X1335953Y592760D02*
Y591696D01*
G01Y602682D02*
Y601618D01*
G01X1335879Y605751D02*
Y604760D01*
G01X1335869Y589618D02*
Y588627D01*
G01X1335795Y601698D02*
Y606539D01*
G01Y587839D02*
Y592680D01*
G01X1335603Y605553D02*
Y606538D01*
G01X1335594Y587840D02*
Y588825D01*
G01X1335520Y606539D02*
Y587839D01*
G01X1335441Y589984D02*
Y583902D01*
G01Y610476D02*
Y604394D01*
G01X1335249Y606539D02*
Y605555D01*
G01X1335244Y606539D02*
Y605555D01*
G01X1335239Y588823D02*
Y587839D01*
G01X1335205Y590516D02*
Y586343D01*
G01Y608035D02*
Y603862D01*
G01X1334102D02*
Y608035D01*
G01Y586343D02*
Y590516D01*
G01X1334068Y588823D02*
Y587839D01*
G01X1334063Y588823D02*
Y587839D01*
G01Y606539D02*
Y605555D01*
G01X1333866Y589984D02*
Y583902D01*
G01Y610476D02*
Y604394D01*
G01X1333787Y587839D02*
Y606539D01*
G01X1333709Y588825D02*
Y587840D01*
G01Y606538D02*
Y605553D01*
G01X1333512Y605555D02*
Y610396D01*
G01Y583982D02*
Y588823D01*
G01X1333433Y604760D02*
Y605751D01*
G01Y588627D02*
Y589618D01*
G01X1333354Y584965D02*
Y583902D01*
G01Y610476D02*
Y609413D01*
G01X1355824Y589010D02*
X1355811Y589984D01*
G01X1352857Y605368D02*
X1352871Y604394D01*
G01X1351883Y589010D02*
X1351870Y589984D01*
G01X1348916Y605368D02*
X1348929Y604394D01*
G01X1347950Y589010D02*
X1347937Y589984D01*
G01X1344983Y605368D02*
X1344997Y604394D01*
G01X1344009Y589010D02*
X1343996Y589984D01*
G01X1341042Y605368D02*
X1341055Y604394D01*
G01X1340076Y589010D02*
X1340063Y589984D01*
G01X1337109Y605368D02*
X1337123Y604394D01*
G01X1336135Y589010D02*
X1336122Y589984D01*
G01X1333168Y605368D02*
X1333181Y604394D01*
G01X1332202Y589010D02*
X1332189Y589984D01*
G01X1353376Y589117D02*
X1353240Y595025D01*
G01X1353235Y594139D02*
X1353371Y588231D01*
G01X1351505Y600239D02*
X1351369Y606147D01*
G01X1351364Y605261D02*
X1351501Y599353D01*
G01X1349443Y589117D02*
X1349307Y595025D01*
G01X1349302Y594139D02*
X1349439Y588231D01*
G01X1347564Y600239D02*
X1347427Y606147D01*
G01X1347423Y605261D02*
X1347559Y599353D01*
G01X1345502Y589117D02*
X1345366Y595025D01*
G01X1345361Y594139D02*
X1345497Y588231D01*
G01X1343631Y600239D02*
X1343495Y606147D01*
G01X1343490Y605261D02*
X1343627Y599353D01*
G01X1341569Y589117D02*
X1341433Y595025D01*
G01X1341428Y594139D02*
X1341565Y588231D01*
G01X1339690Y600239D02*
X1339553Y606147D01*
G01X1339549Y605261D02*
X1339685Y599353D01*
G01X1337628Y589117D02*
X1337492Y595025D01*
G01X1337487Y594139D02*
X1337623Y588231D01*
G01X1335757Y600239D02*
X1335621Y606147D01*
G01X1335616Y605261D02*
X1335753Y599353D01*
G01X1333695Y589117D02*
X1333559Y595025D01*
G01X1333554Y594139D02*
X1333691Y588231D01*
G01X1331816Y600239D02*
X1331679Y606147D01*
G01X1331675Y605261D02*
X1331811Y599353D01*
G01X1349281Y600013D02*
X1349231Y600999D01*
G01X1349228Y600037D02*
X1349279Y599051D01*
G01X1347638Y594341D02*
X1347587Y595327D01*
G01X1347585Y594365D02*
X1347635Y593379D01*
G01X1345349Y600013D02*
X1345298Y600999D01*
G01X1345296Y600037D02*
X1345346Y599051D01*
G01X1343696Y594341D02*
X1343646Y595327D01*
G01X1343643Y594365D02*
X1343694Y593379D01*
G01X1341407Y600013D02*
X1341357Y600999D01*
G01X1341354Y600037D02*
X1341405Y599051D01*
G01X1339764Y594341D02*
X1339713Y595327D01*
G01X1339711Y594365D02*
X1339761Y593379D01*
G01X1337475Y600013D02*
X1337424Y600999D01*
G01X1337422Y600037D02*
X1337472Y599051D01*
G01X1335822Y594341D02*
X1335772Y595327D01*
G01X1335769Y594365D02*
X1335820Y593379D01*
G01X1333533Y600013D02*
X1333483Y600999D01*
G01X1333480Y600037D02*
X1333531Y599051D01*
G01X1331890Y594341D02*
X1331839Y595327D01*
G01X1331837Y594365D02*
X1331887Y593379D01*
G01X1329601Y600013D02*
X1329550Y600999D01*
G01X1329548Y600037D02*
X1329598Y599051D01*
G01X1327948Y594341D02*
X1327898Y595327D01*
G01X1327895Y594365D02*
X1327946Y593379D01*
G01X1359721Y589984D02*
X1359711Y589937D01*
G01X1360767Y604394D02*
X1360777Y604441D01*
G01X1355788Y589984D02*
X1355779Y589937D01*
G01X1356826Y604394D02*
X1356835Y604441D01*
G01X1351847Y589984D02*
X1351837Y589937D01*
G01X1352893Y604394D02*
X1352903Y604441D01*
G01X1347914Y589984D02*
X1347905Y589937D01*
G01X1348952Y604394D02*
X1348961Y604441D01*
G01X1343973Y589984D02*
X1343963Y589937D01*
G01X1345019Y604394D02*
X1345029Y604441D01*
G01X1340040Y589984D02*
X1340031Y589937D01*
G01X1341078Y604394D02*
X1341087Y604441D01*
G01X1336099Y589984D02*
X1336089Y589937D01*
G01X1339713Y599051D02*
X1339764Y600037D01*
G01X1339761Y600999D02*
X1339711Y600013D01*
G01X1337415Y593379D02*
X1337465Y594365D01*
G01X1337463Y595327D02*
X1337413Y594341D01*
G01X1335781Y599051D02*
X1335831Y600037D01*
G01X1335829Y600999D02*
X1335779Y600013D01*
G01X1333483Y593379D02*
X1333533Y594365D01*
G01X1333531Y595327D02*
X1333480Y594341D01*
G01X1331839Y599051D02*
X1331890Y600037D01*
G01X1331887Y600999D02*
X1331837Y600013D01*
G01X1329541Y593379D02*
X1329591Y594365D01*
G01X1329589Y595327D02*
X1329539Y594341D01*
G01X1327907Y599051D02*
X1327957Y600037D01*
G01X1327955Y600999D02*
X1327905Y600013D01*
G01X1325609Y593379D02*
X1325659Y594365D01*
G01X1325657Y595327D02*
X1325606Y594341D01*
G01X1323965Y599051D02*
X1324016Y600037D01*
G01X1324013Y600999D02*
X1323963Y600013D01*
G01X1321667Y593379D02*
X1321717Y594365D01*
G01X1321715Y595327D02*
X1321665Y594341D01*
G01X1335612Y588231D02*
X1335748Y594139D01*
G01X1335743Y595025D02*
X1335607Y589117D01*
G01X1333559Y599353D02*
X1333695Y605261D01*
G01X1333691Y606147D02*
X1333554Y600239D01*
G01X1331679Y588231D02*
X1331816Y594139D01*
G01X1331811Y595025D02*
X1331675Y589117D01*
G01X1329627Y599353D02*
X1329763Y605261D01*
G01X1329758Y606147D02*
X1329622Y600239D01*
G01X1327738Y588231D02*
X1327874Y594139D01*
G01X1327869Y595025D02*
X1327733Y589117D01*
G01X1325685Y599353D02*
X1325821Y605261D01*
G01X1325817Y606147D02*
X1325680Y600239D01*
G01X1323805Y588231D02*
X1323942Y594139D01*
G01X1323937Y595025D02*
X1323801Y589117D01*
G01X1321753Y599353D02*
X1321889Y605261D01*
G01X1321884Y606147D02*
X1321748Y600239D01*
G01X1333181Y589984D02*
X1333168Y589010D01*
G01X1332189Y604394D02*
X1332202Y605368D01*
G01X1329239Y589984D02*
X1329226Y589010D01*
G01X1328257Y604394D02*
X1328270Y605368D01*
G01X1325307Y589984D02*
X1325294Y589010D01*
G01X1324315Y604394D02*
X1324328Y605368D01*
G01X1321365Y589984D02*
X1321352Y589010D01*
G01X1320383Y604394D02*
X1320396Y605368D01*
G01X1333079Y584886D02*
Y583902D01*
G01Y610476D02*
Y609492D01*
G01X1332291D02*
Y610476D01*
G01Y584886D02*
Y583902D01*
G01X1332016Y584965D02*
Y583902D01*
G01Y610476D02*
Y609413D01*
G01X1331937Y589618D02*
Y588627D01*
G01Y605751D02*
Y604760D01*
G01X1331858Y605555D02*
Y610396D01*
G01Y583982D02*
Y588823D01*
G01X1331661Y587840D02*
Y588825D01*
G01Y605553D02*
Y606538D01*
G01X1331583Y606539D02*
Y587839D01*
G01X1331504Y589984D02*
Y583902D01*
G01Y610476D02*
Y604394D01*
G01X1331307Y588823D02*
Y587839D01*
G01Y606539D02*
Y605555D01*
G01X1331302Y606539D02*
Y605555D01*
G01X1331268Y590516D02*
Y586343D01*
G01Y608035D02*
Y603862D01*
G01X1330165D02*
Y608035D01*
G01Y586343D02*
Y590516D01*
G01X1330131Y606539D02*
Y605555D01*
G01X1330126Y588823D02*
Y587839D01*
G01X1330121Y588823D02*
Y587839D01*
G01X1329929Y589984D02*
Y583902D01*
G01Y610476D02*
Y604394D01*
G01X1329850Y587839D02*
Y606539D01*
G01X1329776Y606538D02*
Y605553D01*
G01X1329767Y588825D02*
Y587840D01*
G01X1329575Y601698D02*
Y606539D01*
G01Y587839D02*
Y592680D01*
G01X1329501Y604760D02*
Y605751D01*
G01X1329491Y588627D02*
Y589618D01*
G01X1329417Y592760D02*
Y591696D01*
G01Y602681D02*
Y601618D01*
G01X1329142Y592760D02*
Y591776D01*
G01Y602602D02*
Y601618D01*
G01X1328354Y592760D02*
Y591776D01*
G01Y602602D02*
Y601618D01*
G01X1328079Y592760D02*
Y591696D01*
G01Y602682D02*
Y601618D01*
G01X1328005Y605751D02*
Y604760D01*
G01X1327995Y589618D02*
Y588627D01*
G01X1327921Y601698D02*
Y606539D01*
G01Y587839D02*
Y592680D01*
G01X1327729Y605553D02*
Y606538D01*
G01X1327720Y587840D02*
Y588825D01*
G01X1327646Y606539D02*
Y587839D01*
G01X1327567Y589984D02*
Y583902D01*
G01Y610476D02*
Y604394D01*
G01X1327375Y606539D02*
Y605555D01*
G01X1327370Y606539D02*
Y605555D01*
G01X1327365Y588823D02*
Y587839D01*
G01X1327331Y590516D02*
Y586343D01*
G01Y608035D02*
Y603862D01*
G01X1326228D02*
Y608035D01*
G01Y586343D02*
Y590516D01*
G01X1326194Y588823D02*
Y587839D01*
G01X1326189Y588823D02*
Y587839D01*
G01Y606539D02*
Y605555D01*
G01X1325992Y589984D02*
Y583902D01*
G01Y610476D02*
Y604394D01*
G01X1325913Y587839D02*
Y606539D01*
G01X1325835Y588825D02*
Y587840D01*
G01Y606538D02*
Y605553D01*
G01X1325638Y605555D02*
Y610396D01*
G01Y583982D02*
Y588823D01*
G01X1325559Y604760D02*
Y605751D01*
G01Y588627D02*
Y589618D01*
G01X1325480Y584965D02*
Y583902D01*
G01Y610476D02*
Y609413D01*
G01X1325205Y584886D02*
Y583902D01*
G01Y610476D02*
Y609492D01*
G01X1324417D02*
Y610476D01*
G01Y584886D02*
Y583902D01*
G01X1324142Y584965D02*
Y583902D01*
G01Y610476D02*
Y609413D01*
G01X1324063Y589618D02*
Y588627D01*
G01Y605751D02*
Y604760D01*
G01X1323984Y605555D02*
Y610396D01*
G01Y583982D02*
Y588823D01*
G01X1323787Y587840D02*
Y588825D01*
G01Y605553D02*
Y606538D01*
G01X1323709Y606539D02*
Y587839D01*
G01X1323630Y589984D02*
Y583902D01*
G01Y610476D02*
Y604394D01*
G01X1323433Y588823D02*
Y587839D01*
G01Y606539D02*
Y605555D01*
G01X1323428Y606539D02*
Y605555D01*
G01X1323394Y590516D02*
Y586343D01*
G01Y608035D02*
Y603862D01*
G01X1322291D02*
Y608035D01*
G01Y586343D02*
Y590516D01*
G01X1322257Y606539D02*
Y605555D01*
G01X1322252Y588823D02*
Y587839D01*
G01X1322247Y588823D02*
Y587839D01*
G01X1322055Y589984D02*
Y583902D01*
G01Y610476D02*
Y604394D01*
G01X1321976Y587839D02*
Y606539D01*
G01X1321902Y606538D02*
Y605553D01*
G01X1321893Y588825D02*
Y587840D01*
G01X1321701Y601698D02*
Y606539D01*
G01Y587839D02*
Y592680D01*
G01X1321627Y604760D02*
Y605751D01*
G01X1321617Y588627D02*
Y589618D01*
G01X1321543Y592760D02*
Y591696D01*
G01Y602681D02*
Y601618D01*
G01X1321268D02*
Y602602D01*
G01Y592760D02*
Y591776D01*
G01X1320480Y601618D02*
Y602602D01*
G01Y591776D02*
Y592760D01*
G01X1329235Y605368D02*
X1329249Y604394D01*
G01X1328261Y589010D02*
X1328248Y589984D01*
G01X1325294Y605368D02*
X1325307Y604394D01*
G01X1324328Y589010D02*
X1324315Y589984D01*
G01X1321361Y605368D02*
X1321374Y604394D01*
G01X1320387Y589010D02*
X1320374Y589984D01*
G01X1329754Y589117D02*
X1329618Y595025D01*
G01X1329613Y594139D02*
X1329749Y588231D01*
G01X1327883Y600239D02*
X1327747Y606147D01*
G01X1327742Y605261D02*
X1327879Y599353D01*
G01X1325821Y589117D02*
X1325685Y595025D01*
G01X1325680Y594139D02*
X1325817Y588231D01*
G01X1323942Y600239D02*
X1323805Y606147D01*
G01X1323801Y605261D02*
X1323937Y599353D01*
G01X1321880Y589117D02*
X1321744Y595025D01*
G01X1321739Y594139D02*
X1321875Y588231D01*
G01X1325659Y600013D02*
X1325609Y600999D01*
G01X1325606Y600037D02*
X1325657Y599051D01*
G01X1324016Y594341D02*
X1323965Y595327D01*
G01X1323963Y594365D02*
X1324013Y593379D01*
G01X1321727Y600013D02*
X1321676Y600999D01*
G01X1321674Y600037D02*
X1321724Y599051D01*
G01X1387067Y588640D02*
X1387320Y589010D01*
G01X1387054Y589615D02*
X1387275Y589937D01*
G01X1383125Y588640D02*
X1383379Y589010D01*
G01X1383112Y589615D02*
X1383333Y589937D01*
G01X1379193Y588640D02*
X1379446Y589010D01*
G01X1379401Y589937D02*
X1379181Y589618D01*
G01X1375251Y588640D02*
X1375505Y589010D01*
G01X1375238Y589615D02*
X1375459Y589937D01*
G01X1384620Y604763D02*
X1384399Y604441D01*
G01X1384607Y605738D02*
X1384353Y605368D01*
G01X1371319Y588640D02*
X1371572Y589010D01*
G01X1371527Y589937D02*
X1371307Y589618D01*
G01X1380457Y604441D02*
X1380677Y604760D01*
G01X1380666Y605738D02*
X1380412Y605368D01*
G01X1337145Y604394D02*
X1337155Y604441D01*
G01X1332166Y589984D02*
X1332157Y589937D01*
G01X1333204Y604394D02*
X1333213Y604441D01*
G01X1328225Y589984D02*
X1328215Y589937D01*
G01X1329271Y604394D02*
X1329281Y604441D01*
G01X1324292Y589984D02*
X1324283Y589937D01*
G01X1325330Y604394D02*
X1325339Y604441D01*
G01X1320351Y589984D02*
X1320341Y589937D01*
G01X1321397Y604394D02*
X1321407Y604441D01*
G01X1367377Y588640D02*
X1367631Y589010D01*
G01X1367364Y589615D02*
X1367585Y589937D01*
G01X1376746Y604763D02*
X1376525Y604441D01*
G01X1376733Y605738D02*
X1376479Y605368D01*
G01X1363445Y588640D02*
X1363698Y589010D01*
G01X1363431Y589615D02*
X1363653Y589937D01*
G01X1372583Y604441D02*
X1372803Y604760D01*
G01X1372792Y605738D02*
X1372538Y605368D01*
G01X1359503Y588640D02*
X1359757Y589010D01*
G01X1359490Y589615D02*
X1359711Y589937D01*
G01X1368872Y604763D02*
X1368651Y604441D01*
G01X1368859Y605738D02*
X1368605Y605368D01*
G01X1355571Y588640D02*
X1355824Y589010D01*
G01X1355557Y589615D02*
X1355779Y589937D01*
G01X1364931Y604763D02*
X1364709Y604441D01*
G01X1364918Y605738D02*
X1364664Y605368D01*
G01X1351629Y588640D02*
X1351883Y589010D01*
G01X1351616Y589615D02*
X1351837Y589937D01*
G01X1360998Y604763D02*
X1360777Y604441D01*
G01X1360985Y605738D02*
X1360731Y605368D01*
G01X1347697Y588640D02*
X1347950Y589010D01*
G01X1347683Y589615D02*
X1347905Y589937D01*
G01X1357057Y604763D02*
X1356835Y604441D01*
G01X1357044Y605738D02*
X1356790Y605368D01*
G01X1343755Y588640D02*
X1344009Y589010D01*
G01X1343742Y589615D02*
X1343963Y589937D01*
G01X1353124Y604763D02*
X1352903Y604441D01*
G01X1353111Y605738D02*
X1352857Y605368D01*
G01X1339823Y588640D02*
X1340076Y589010D01*
G01X1339809Y589615D02*
X1340031Y589937D01*
G01X1349183Y604763D02*
X1348961Y604441D01*
G01X1349170Y605738D02*
X1348916Y605368D01*
G01X1335881Y588640D02*
X1336135Y589010D01*
G01X1335868Y589615D02*
X1336089Y589937D01*
G01X1345250Y604763D02*
X1345029Y604441D01*
G01X1345237Y605738D02*
X1344983Y605368D01*
G01X1331949Y588640D02*
X1332202Y589010D01*
G01X1331935Y589615D02*
X1332157Y589937D01*
G01X1341309Y604763D02*
X1341087Y604441D01*
G01X1341296Y605738D02*
X1341042Y605368D01*
G01X1328007Y588640D02*
X1328261Y589010D01*
G01X1327994Y589615D02*
X1328215Y589937D01*
G01X1337376Y604763D02*
X1337155Y604441D01*
G01X1337363Y605738D02*
X1337109Y605368D01*
G01X1324075Y588640D02*
X1324328Y589010D01*
G01X1324061Y589615D02*
X1324283Y589937D01*
G01X1333435Y604763D02*
X1333213Y604441D01*
G01X1333422Y605738D02*
X1333168Y605368D01*
G01X1329502Y604763D02*
X1329281Y604441D01*
G01X1329489Y605738D02*
X1329235Y605368D01*
G01X1325561Y604763D02*
X1325339Y604441D01*
G01X1325548Y605738D02*
X1325294Y605368D01*
G01X1321628Y604763D02*
X1321407Y604441D01*
G01X1321615Y605738D02*
X1321361Y605368D01*
G01X1327444Y782204D02*
Y764881D01*
G01X1421408Y-589495D02*
Y-583195D01*
X1420468Y-584455D01*
G01Y-589495D02*
X1422348D01*
G01X1427708Y-583195D02*
X1427081Y-583405D01*
X1426611Y-583930D01*
X1426298Y-584560D01*
X1426063Y-585400D01*
X1425985Y-586345D01*
X1426063Y-587290D01*
X1426298Y-588130D01*
X1426611Y-588760D01*
X1427081Y-589285D01*
X1427708Y-589495D01*
X1428335Y-589285D01*
X1428805Y-588760D01*
X1429118Y-588130D01*
X1429353Y-587290D01*
X1429431Y-586345D01*
X1429353Y-585400D01*
X1429118Y-584560D01*
X1428805Y-583930D01*
X1428335Y-583405D01*
X1427708Y-583195D01*
G01X1467375Y-153821D02*
Y-164057D01*
G01X1466391Y-153821D02*
Y-164057D01*
G01X1464225Y-153821D02*
Y-164057D01*
G01X1463241Y-153821D02*
Y-164057D01*
G01X1461076Y-153821D02*
Y-164057D01*
G01X1460091Y-153821D02*
Y-164057D01*
G01X1457926Y-153821D02*
Y-164057D01*
G01X1456942Y-153821D02*
Y-164057D01*
G01X1454777Y-153821D02*
Y-164057D01*
G01X1453792Y-153821D02*
Y-164057D01*
G01X1451627Y-153821D02*
Y-164057D01*
G01X1450643Y-153821D02*
Y-164057D01*
G01X1448477Y-153821D02*
Y-164057D01*
G01X1447493Y-153821D02*
Y-164057D01*
G01X1445328Y-153821D02*
Y-164057D01*
G01X1444343Y-153821D02*
Y-164057D01*
G01X1442178Y-153821D02*
Y-164057D01*
G01X1441194Y-153821D02*
Y-164057D01*
G01X1439028Y-153821D02*
Y-164057D01*
G01X1438044Y-153821D02*
Y-164057D01*
G01X1435879Y-153821D02*
Y-164057D01*
G01X1434895Y-153821D02*
Y-164057D01*
G01X1432729Y-153821D02*
Y-164057D01*
G01X1431745Y-153821D02*
Y-164057D01*
G01X1429580Y-153821D02*
Y-164057D01*
G01X1428595Y-153821D02*
Y-164057D01*
G01X1426430Y-153821D02*
Y-164057D01*
G01X1425446Y-153821D02*
Y-164057D01*
G01X1423280Y-153821D02*
Y-164057D01*
G01X1422296Y-153821D02*
Y-164057D01*
G01X1420131Y-153821D02*
Y-164057D01*
G01X1417178Y-166026D02*
Y-137285D01*
G01D02*
Y-166026D01*
G01D02*
X1419147Y-167994D01*
G01D02*
X1417178Y-166026D01*
G01X1422296Y-164057D02*
X1420131D01*
G01X1425446D02*
X1423280D01*
G01X1428595D02*
X1426430D01*
G01X1431745D02*
X1429580D01*
G01X1434895D02*
X1432729D01*
G01X1438044D02*
X1435879D01*
G01X1441194D02*
X1439028D01*
G01X1444343D02*
X1442178D01*
G01X1447493D02*
X1445328D01*
G01X1450643D02*
X1448477D01*
G01X1453792D02*
X1451627D01*
G01X1456942D02*
X1454777D01*
G01X1460091D02*
X1457926D01*
G01X1463241D02*
X1461076D01*
G01X1466391D02*
X1464225D01*
G01X1469540D02*
X1467375D01*
G01X1419147Y-167994D02*
X1514619D01*
G01X1419147D02*
X1514619D01*
G01X1421489Y-152484D02*
X1421594Y-152430D01*
G01X1421620Y-152564D02*
X1421542Y-152618D01*
G01X1421017Y-152993D02*
X1420912Y-153074D01*
G01X1422198Y-152940D02*
X1421542Y-153529D01*
G01X1421332D02*
X1422067Y-152859D01*
G01X1421384Y-152591D02*
X1421489Y-152484D01*
G01X1420885Y-152913D02*
X1420938Y-152859D01*
G01X1421095Y-152886D02*
X1421017Y-152993D01*
G01X1422250Y-152859D02*
X1422198Y-152940D01*
G01X1421542Y-152618D02*
X1421489Y-152698D01*
G01X1420807Y-152940D02*
X1420885Y-152913D01*
G01X1422067Y-152859D02*
X1422119Y-152752D01*
G01X1421122Y-152806D02*
X1421095Y-152886D01*
G01X1420938Y-152859D02*
X1420964Y-152779D01*
G01X1422277Y-152752D02*
X1422250Y-152859D01*
G01X1421358Y-152698D02*
X1421384Y-152591D01*
G01X1422277Y-152698D02*
Y-152752D01*
G01Y-153529D02*
Y-153663D01*
G01X1422119Y-152752D02*
Y-152698D01*
G01X1421332Y-153663D02*
Y-153529D01*
G01X1421122Y-152698D02*
Y-152806D01*
G01X1420964Y-152779D02*
Y-152698D01*
G01X1420308Y-153100D02*
Y-153663D01*
G01Y-152538D02*
Y-152940D01*
G01X1420151Y-153663D02*
Y-152404D01*
G01X1422250Y-152591D02*
X1422277Y-152698D01*
G01X1421095Y-152618D02*
X1421122Y-152698D01*
G01X1420964D02*
X1420938Y-152618D01*
G01X1422119Y-152698D02*
X1422067Y-152618D01*
G01X1421017Y-152511D02*
X1421095Y-152618D01*
G01X1422145Y-152484D02*
X1422250Y-152591D01*
G01X1420938Y-152618D02*
X1420885Y-152564D01*
G01X1420912Y-152430D02*
X1421017Y-152511D01*
G01X1422067Y-152618D02*
X1421988Y-152564D01*
G01X1422040Y-152430D02*
X1422145Y-152484D01*
G01X1420885Y-152564D02*
X1420807Y-152538D01*
G01X1421988Y-152564D02*
X1421857Y-152538D01*
G01X1420780Y-152404D02*
X1420912Y-152430D01*
G01X1421883Y-152404D02*
X1422040Y-152430D01*
G01X1421778Y-152404D02*
X1421883D01*
G01X1420151D02*
X1420780D01*
G01X1420807Y-152538D02*
X1420308D01*
G01X1421857D02*
X1421752D01*
G01X1421489Y-152698D02*
X1421358D01*
G01X1420308Y-152940D02*
X1420807D01*
G01X1420780Y-153100D02*
X1420308D01*
G01X1421542Y-153529D02*
X1422277D01*
G01Y-153663D02*
X1421332D01*
G01X1420308D02*
X1420151D01*
G01X1422296Y-153821D02*
X1420131D01*
G01X1425446D02*
X1423280D01*
G01X1428595D02*
X1426430D01*
G01X1431745D02*
X1429580D01*
G01X1434895D02*
X1432729D01*
G01X1438044D02*
X1435879D01*
G01X1441194D02*
X1439028D01*
G01X1444343D02*
X1442178D01*
G01X1447493D02*
X1445328D01*
G01X1450643D02*
X1448477D01*
G01X1453792D02*
X1451627D01*
G01X1456942D02*
X1454777D01*
G01X1460091D02*
X1457926D01*
G01X1463241D02*
X1461076D01*
G01X1466391D02*
X1464225D01*
G01X1469540D02*
X1467375D01*
G01X1421594Y-152430D02*
X1421778Y-152404D01*
G01X1421752Y-152538D02*
X1421620Y-152564D01*
G01X1420912Y-153074D02*
X1420780Y-153100D01*
G01X1417178Y-137285D02*
G03X1416391Y-136498I-787J0D01*
G01X1417178Y-137285D02*
G03X1416391Y-136498I-787J0D01*
G01X1467168Y13817D02*
Y2006D01*
G01X1465200D02*
Y3262D01*
G01X1463969D02*
Y2006D01*
G01X1451174D02*
Y10047D01*
G01X1449944Y8288D02*
Y2006D01*
G01X1447237D02*
Y8037D01*
G01X1446007D02*
Y2006D01*
G01X1443300D02*
Y8037D01*
G01X1442070D02*
Y2006D01*
G01X1440101D02*
Y10047D01*
G01X1438871Y8288D02*
Y2006D01*
G01X1436164D02*
Y8037D01*
G01X1434934D02*
Y2006D01*
G01X1432227D02*
Y8037D01*
G01X1430997D02*
Y2006D01*
G01X1427690Y-15868D02*
Y42911D01*
G01X1427692Y-15888D02*
X1403814Y-39766D01*
G01X1427692Y-15868D02*
X1403814Y-39746D01*
G01X1456834Y2006D02*
X1455603Y2257D01*
G01X1467168Y2006D02*
X1468645D01*
G01X1463969D02*
X1465200D01*
G01X1449944D02*
X1451174D01*
G01X1446007D02*
X1447237D01*
G01X1442070D02*
X1443300D01*
G01X1438871D02*
X1440101D01*
G01X1434934D02*
X1436164D01*
G01X1430997D02*
X1432227D01*
G01X1458310D02*
X1456834D01*
G01X1427690Y-15868D02*
X1517009D01*
G01X1427692Y-15888D02*
X1516935D01*
G01X1459540Y2257D02*
X1458310Y2006D01*
G01X1454373Y5524D02*
X1454619Y4770D01*
G01X1462001Y13817D02*
Y7283D01*
G01X1460771Y8540D02*
Y12560D01*
G01X1454373Y6027D02*
Y5524D01*
G01X1453635Y12560D02*
Y13817D01*
G01X1453143Y5273D02*
Y6278D01*
G01X1449944Y10047D02*
Y9294D01*
G01X1453635Y4016D02*
X1453143Y5273D01*
G01X1445761Y8540D02*
X1446007Y8037D01*
G01X1434688Y8540D02*
X1434934Y8037D01*
G01X1454619Y4770D02*
X1455111Y4016D01*
G01X1454373Y3011D02*
X1453635Y4016D01*
G01X1462001Y5021D02*
X1461509Y4016D01*
G01X1460032D02*
X1460525Y5021D01*
G01X1453143Y6278D02*
X1453635Y7534D01*
G01X1454619Y6781D02*
X1454373Y6027D01*
G01X1438871Y10047D02*
Y9294D01*
G01X1449944D02*
X1449452Y9796D01*
G01Y8791D02*
X1449944Y8288D01*
G01X1446253Y9042D02*
X1445515Y9796D01*
G01Y8791D02*
X1445761Y8540D01*
G01X1438871Y9294D02*
X1438379Y9796D01*
G01Y8791D02*
X1438871Y8288D01*
G01X1435180Y9042D02*
X1434442Y9796D01*
G01Y8791D02*
X1434688Y8540D01*
G01X1460278Y7283D02*
X1459294Y8037D01*
G01X1461509Y4016D02*
X1460771Y3011D01*
G01X1453635Y7534D02*
X1454373Y8540D01*
G01X1455111Y7534D02*
X1454619Y6781D01*
G01X1447237Y8037D02*
X1447483Y8540D01*
G01X1443300Y8037D02*
X1443546Y8540D01*
G01X1436164Y8037D02*
X1436410Y8540D01*
G01X1432227Y8037D02*
X1432473Y8540D01*
G01X1442562Y9294D02*
X1442070Y8037D01*
G01X1431489Y9294D02*
X1430997Y8037D01*
G01X1455111Y4016D02*
X1455849Y3514D01*
G01X1459540Y9294D02*
X1460771Y8540D01*
G01X1455603Y2257D02*
X1454373Y3011D01*
G01X1447483Y8540D02*
X1447729Y8791D01*
G01X1446991Y9796D02*
X1446253Y9042D01*
G01X1443546Y8540D02*
X1443792Y8791D01*
G01X1443054Y9796D02*
X1442562Y9294D01*
G01X1436410Y8540D02*
X1436656Y8791D01*
G01X1445023Y9042D02*
X1445515Y8791D01*
G01X1433950Y9042D02*
X1434442Y8791D01*
G01X1449452Y9796D02*
X1448714Y10047D01*
G01X1460771Y3011D02*
X1459540Y2257D01*
G01X1454373Y8540D02*
X1455603Y9294D01*
G01X1459294Y3514D02*
X1460032Y4016D01*
G01X1455849Y8037D02*
X1455111Y7534D01*
G01X1435918Y9796D02*
X1435180Y9042D01*
G01X1432473Y8540D02*
X1432719Y8791D01*
G01X1431981Y9796D02*
X1431489Y9294D01*
G01X1448714Y9042D02*
X1449452Y8791D01*
G01X1445515Y9796D02*
X1444777Y10047D01*
G01X1438379Y9796D02*
X1437641Y10047D01*
G01Y9042D02*
X1438379Y8791D01*
G01X1434442Y9796D02*
X1433704Y10047D01*
G01X1459294Y8037D02*
X1458310Y8288D01*
G01X1455849Y3514D02*
X1456834Y3262D01*
G01X1458310Y9545D02*
X1459540Y9294D01*
G01X1447729Y8791D02*
X1448221Y9042D01*
G01X1443792Y8791D02*
X1444284Y9042D01*
G01X1436656Y8791D02*
X1437149Y9042D01*
G01X1432719Y8791D02*
X1433212Y9042D01*
G01X1447729Y10047D02*
X1446991Y9796D01*
G01X1443792Y10047D02*
X1443054Y9796D01*
G01X1436656Y10047D02*
X1435918Y9796D01*
G01X1432719Y10047D02*
X1431981Y9796D01*
G01X1453635Y13817D02*
X1462001D01*
G01X1468645D02*
X1467168D01*
G01X1460771Y12560D02*
X1453635D01*
G01X1433704Y10047D02*
X1432719D01*
G01X1437641D02*
X1436656D01*
G01X1440101D02*
X1438871D01*
G01X1444777D02*
X1443792D01*
G01X1448714D02*
X1447729D01*
G01X1451174D02*
X1449944D01*
G01X1456834Y9545D02*
X1458310D01*
G01X1448221Y9042D02*
X1448714D01*
G01X1444284D02*
X1445023D01*
G01X1437149D02*
X1437641D01*
G01X1433212D02*
X1433950D01*
G01X1458310Y8288D02*
X1456834D01*
G01X1462001Y7283D02*
X1460278D01*
G01X1460525Y5021D02*
X1462001D01*
G01X1456834Y3262D02*
X1458310D01*
G01X1465200D02*
X1463969D01*
G01X1455603Y9294D02*
X1456834Y9545D01*
G01Y8288D02*
X1455849Y8037D01*
G01X1458310Y3262D02*
X1459294Y3514D01*
G01X1454693Y81168D02*
X1454857Y80498D01*
G01X1461911Y79325D02*
X1462239Y78487D01*
G01X1466176D02*
X1466012Y78823D01*
G01X1461419Y78487D02*
X1461255Y78823D01*
G01X1458794Y78487D02*
X1458630Y78823D01*
G01X1453873Y80498D02*
X1453545Y81000D01*
G01X1466340Y79660D02*
X1466832Y79158D01*
G01X1466012Y78823D02*
X1465848Y78990D01*
G01X1461583Y79660D02*
X1461911Y79325D01*
G01X1461255Y78823D02*
X1461091Y78990D01*
G01X1458958Y79660D02*
X1459450Y79158D01*
G01X1444687Y78990D02*
X1444523Y79995D01*
G01X1440422Y77817D02*
X1440586Y76812D01*
G01X1445507Y79158D02*
X1445343Y79995D01*
G01X1439601Y77650D02*
X1439765Y76812D01*
G01X1445343Y79995D02*
X1445179Y80498D01*
G01X1439765Y76812D02*
X1439930Y76310D01*
G01X1445179Y80498D02*
X1444851Y81168D01*
G01X1439930Y76310D02*
X1440258Y75639D01*
G01X1444523Y79995D02*
X1443867Y81000D01*
G01X1440586Y76812D02*
X1441242Y75807D01*
G01X1437961Y80163D02*
X1438289Y79660D01*
G01X1458630Y78823D02*
X1458466Y78990D01*
G01X1454037Y81838D02*
X1454693Y81168D01*
G01X1444851D02*
X1444359Y81671D01*
G01X1440258Y75639D02*
X1440750Y75137D01*
G01X1453545Y81000D02*
X1453053Y81336D01*
G01X1443867Y81000D02*
X1443374Y81336D01*
G01X1466996Y78487D02*
Y74467D01*
G01X1466176D02*
Y78487D01*
G01X1464372Y78655D02*
Y74467D01*
G01Y79828D02*
Y79325D01*
G01X1463552Y74467D02*
Y79828D01*
G01X1462239Y78487D02*
Y74467D01*
G01X1461419D02*
Y78487D01*
G01X1459615D02*
Y74467D01*
G01X1458794D02*
Y78487D01*
G01X1456990Y78655D02*
Y74467D01*
G01Y79828D02*
Y79325D01*
G01X1456170Y74467D02*
Y79828D01*
G01X1454857Y75304D02*
Y74467D01*
G01Y80498D02*
Y80163D01*
G01X1453873D02*
Y80498D01*
G01X1448952Y74467D02*
Y75304D01*
G01X1441242Y75807D02*
X1441734Y75472D01*
G01X1444359Y81671D02*
X1443538Y82173D01*
G01X1440750Y75137D02*
X1441570Y74634D01*
G01X1437961Y76812D02*
X1434844Y78487D01*
G01X1465848Y78990D02*
X1465520Y79158D01*
G01X1461091Y78990D02*
X1460763Y79158D01*
G01X1453381Y82173D02*
X1454037Y81838D01*
G01X1458466Y78990D02*
X1458138Y79158D01*
G01X1435992Y78487D02*
X1438289Y77315D01*
G01X1465848Y79828D02*
X1466340Y79660D01*
G01X1461091Y79828D02*
X1461583Y79660D01*
G01X1454857Y80163D02*
X1454693Y79493D01*
G01X1445343Y76812D02*
X1445507Y77650D01*
G01X1444523Y76812D02*
X1444687Y77817D01*
G01X1447639Y75304D02*
Y74467D01*
G01X1446819D02*
Y75304D01*
G01X1445507Y77650D02*
Y79158D01*
G01X1444687Y77817D02*
Y78990D01*
G01X1440422D02*
Y77817D01*
G01X1439601Y79158D02*
Y77650D01*
G01X1433532Y82341D02*
Y74467D01*
G01X1432548Y79158D02*
Y82341D01*
G01Y74467D02*
Y78152D01*
G01X1427954D02*
Y74467D01*
G01Y82341D02*
Y79158D01*
G01X1426970Y74467D02*
Y82341D01*
G01X1458466Y79828D02*
X1458958Y79660D01*
G01X1453053Y81336D02*
X1452233Y81503D01*
G01X1443374Y81336D02*
X1442554Y81503D01*
G01X1452397Y82341D02*
X1453381Y82173D01*
G01X1467160Y78823D02*
X1466996Y78487D01*
G01X1459779Y78823D02*
X1459615Y78487D01*
G01X1445179Y76310D02*
X1445343Y76812D01*
G01X1439930Y80498D02*
X1439765Y79995D01*
G01X1449116Y80498D02*
X1449280Y81168D01*
G01X1439765Y79995D02*
X1439601Y79158D01*
G01X1440586Y79995D02*
X1440422Y78990D01*
G01X1441734Y75472D02*
X1442554Y75304D01*
G01X1443538Y82173D02*
X1442554Y82341D01*
G01X1441570Y74634D02*
X1442554Y74467D01*
G01X1453545Y79493D02*
X1453873Y80163D01*
G01X1444851Y75639D02*
X1445179Y76310D01*
G01X1440258Y81168D02*
X1439930Y80498D01*
G01X1451741Y82341D02*
X1452397D01*
G01X1432548D02*
X1433532D01*
G01X1426970D02*
X1427954D01*
G01X1452233Y81503D02*
X1451576D01*
G01X1449936Y80498D02*
X1449116D01*
G01X1467817Y79828D02*
X1468473D01*
G01X1465192D02*
X1465848D01*
G01X1463552D02*
X1464372D01*
G01X1460435D02*
X1461091D01*
G01X1457810D02*
X1458466D01*
G01X1456170D02*
X1456990D01*
G01X1427954Y79158D02*
X1432548D01*
G01X1458138D02*
X1457810D01*
G01X1460763D02*
X1460271D01*
G01X1465520D02*
X1465192D01*
G01X1468145D02*
X1467653D01*
G01X1432548Y78152D02*
X1427954D01*
G01X1450264Y75304D02*
X1454857D01*
G01X1446819D02*
X1447639D01*
G01X1427954Y74467D02*
X1426970D01*
G01X1433532D02*
X1432548D01*
G01X1447639D02*
X1446819D01*
G01X1454857D02*
X1448952D01*
G01X1456990D02*
X1456170D01*
G01X1459615D02*
X1458794D01*
G01X1462239D02*
X1461419D01*
G01X1464372D02*
X1463552D01*
G01X1466996D02*
X1466176D01*
G01X1454693Y79493D02*
X1454365Y78990D01*
G01X1450264Y81000D02*
X1449936Y80498D01*
G01X1443867Y75807D02*
X1444523Y76812D01*
G01X1441242Y81000D02*
X1440586Y79995D01*
G01X1438289Y77315D02*
X1437961Y76812D01*
G01X1450592Y82173D02*
X1451741Y82341D01*
G01X1442554D02*
X1441570Y82173D01*
G01X1442554Y74467D02*
X1443538Y74634D01*
G01X1442554Y81503D02*
X1441734Y81336D01*
G01X1451576Y81503D02*
X1450756Y81336D01*
G01X1442554Y75304D02*
X1443374Y75472D01*
G01X1467325Y78990D02*
X1467160Y78823D01*
G01X1466832Y79158D02*
X1467325Y79660D01*
G01X1464700Y78990D02*
X1464372Y78655D01*
G01Y79325D02*
X1464700Y79660D01*
G01X1459943Y78990D02*
X1459779Y78823D01*
G01X1459450Y79158D02*
X1459943Y79660D01*
G01X1457318Y78990D02*
X1456990Y78655D01*
G01Y79325D02*
X1457318Y79660D01*
G01X1444359Y75137D02*
X1444851Y75639D01*
G01X1449280Y81168D02*
X1449936Y81838D01*
G01X1454365Y78990D02*
X1450264Y75304D01*
G01X1448952D02*
X1453545Y79493D01*
G01X1440750Y81671D02*
X1440258Y81168D01*
G01X1467653Y79158D02*
X1467325Y78990D01*
G01X1443538Y74634D02*
X1444359Y75137D01*
G01X1441570Y82173D02*
X1440750Y81671D01*
G01X1443374Y75472D02*
X1443867Y75807D01*
G01X1450756Y81336D02*
X1450264Y81000D01*
G01X1441734Y81336D02*
X1441242Y81000D01*
G01X1460271Y79158D02*
X1459943Y78990D01*
G01X1449936Y81838D02*
X1450592Y82173D01*
G01X1438289Y79660D02*
X1435992Y78487D01*
G01X1434844D02*
X1437961Y80163D01*
G01X1467325Y79660D02*
X1467817Y79828D01*
G01X1465192Y79158D02*
X1464700Y78990D01*
G01Y79660D02*
X1465192Y79828D01*
G01X1459943Y79660D02*
X1460435Y79828D01*
G01X1457810Y79158D02*
X1457318Y78990D01*
G01Y79660D02*
X1457810Y79828D01*
G01X1407843Y223456D02*
X1416504D01*
G01X1407843Y215660D02*
X1416504D01*
G01X1415782Y245867D02*
X1415060Y245380D01*
G01X1416504Y246841D02*
X1415782Y245867D01*
G01Y247816D02*
X1416504Y246841D01*
G01X1415060Y248303D02*
X1415782Y247816D01*
G01X1413617Y248790D02*
X1415060Y248303D01*
G01X1410730Y248790D02*
X1413617D01*
G01X1409286Y248303D02*
X1410730Y248790D01*
G01X1408564Y247816D02*
X1409286Y248303D01*
G01X1407843Y246841D02*
X1408564Y247816D01*
G01Y245867D02*
X1407843Y246841D01*
G01X1409286Y245380D02*
X1408564Y245867D01*
G01X1410730Y244893D02*
X1409286Y245380D01*
G01X1412173D02*
X1410730Y244893D01*
G01X1412895Y246841D02*
X1412173Y245380D01*
G01Y248303D02*
X1412895Y246841D01*
G01X1410730Y248790D02*
X1412173Y248303D01*
G01X1415782Y253175D02*
X1415060Y252688D01*
G01X1416504Y254150D02*
X1415782Y253175D01*
G01X1416504Y255124D02*
Y254150D01*
G01X1415782Y256098D02*
X1416504Y255124D01*
G01X1414339Y257073D02*
X1415782Y256098D01*
G01X1411451Y255124D02*
X1412173Y256098D01*
G01X1410730D02*
X1411451Y255124D01*
G01X1410008Y256586D02*
X1410730Y256098D01*
G01X1409286Y256586D02*
X1410008D01*
G01X1408564Y256098D02*
X1409286Y256586D01*
G01X1407843Y255124D02*
X1408564Y256098D01*
G01X1407843Y254150D02*
Y255124D01*
G01X1408564Y253175D02*
X1407843Y254150D01*
G01X1415782Y238559D02*
X1416504Y239046D01*
G01Y238559D02*
X1415782D01*
G01X1416504Y239046D02*
Y238559D01*
G01X1413617Y257073D02*
X1414339D01*
G01X1412173Y256098D02*
X1413617Y257073D01*
G01X1411451Y254150D02*
Y255124D01*
G01X1407843Y231251D02*
X1416504D01*
G01X1418669Y299785D02*
Y262865D01*
G01X1465717Y314827D02*
Y304591D01*
G01X1464732Y314827D02*
Y304591D01*
G01X1462567Y314827D02*
Y304591D01*
G01X1461583Y314827D02*
Y304591D01*
G01X1459417Y314827D02*
Y304591D01*
G01X1458433Y314827D02*
Y304591D01*
G01X1456268Y314827D02*
Y304591D01*
G01X1455283Y314827D02*
Y304591D01*
G01X1453118Y314827D02*
Y304591D01*
G01X1452134Y314827D02*
Y304591D01*
G01X1449968Y314827D02*
Y304591D01*
G01X1448984Y314827D02*
Y304591D01*
G01X1446819Y314827D02*
Y304591D01*
G01X1445835Y314827D02*
Y304591D01*
G01X1443669Y314827D02*
Y304591D01*
G01X1442685Y314827D02*
Y304591D01*
G01X1440520Y314827D02*
Y304591D01*
G01X1439535Y314827D02*
Y304591D01*
G01X1437370Y314827D02*
Y304591D01*
G01X1436386Y314827D02*
Y304591D01*
G01X1434220Y314827D02*
Y304591D01*
G01X1433236Y314827D02*
Y304591D01*
G01X1431071Y314827D02*
Y304591D01*
G01X1430087Y314827D02*
Y304591D01*
G01X1427921Y314827D02*
Y304591D01*
G01X1426937Y314827D02*
Y304591D01*
G01X1424772Y314827D02*
Y304591D01*
G01X1423787Y314827D02*
Y304591D01*
G01X1421622Y314827D02*
Y304591D01*
G01X1418669Y302622D02*
Y331362D01*
G01D02*
Y302622D01*
G01X1420638Y300654D02*
X1418669Y302622D01*
G01D02*
X1420638Y300654D01*
G01X1423787Y304591D02*
X1421622D01*
G01X1426937D02*
X1424772D01*
G01X1430087D02*
X1427921D01*
G01X1433236D02*
X1431071D01*
G01X1436386D02*
X1434220D01*
G01X1439535D02*
X1437370D01*
G01X1442685D02*
X1440520D01*
G01X1445835D02*
X1443669D01*
G01X1448984D02*
X1446819D01*
G01X1452134D02*
X1449968D01*
G01X1455283D02*
X1453118D01*
G01X1458433D02*
X1456268D01*
G01X1461583D02*
X1459417D01*
G01X1464732D02*
X1462567D01*
G01X1467882D02*
X1465717D01*
G01X1420638Y300654D02*
X1516110D01*
G01X1420638D02*
X1516110D01*
G01X1422884Y315845D02*
X1422743Y315737D01*
G01X1422708Y315953D02*
X1422779Y316025D01*
G01X1423519Y316350D02*
X1423308Y316098D01*
G01Y316386D02*
X1423519Y316638D01*
G01X1422990Y315989D02*
X1422884Y315845D01*
G01X1422602Y315917D02*
X1422708Y315953D01*
G01X1423025Y316098D02*
X1422990Y315989D01*
G01X1422779Y316025D02*
X1422814Y316134D01*
G01X1423731Y316638D02*
Y314945D01*
G01X1423519D02*
Y316350D01*
G01X1423308Y316098D02*
Y316386D01*
G01X1423025Y316242D02*
Y316098D01*
G01X1422814Y316134D02*
Y316242D01*
G01X1421932Y316458D02*
Y315917D01*
G01Y315701D02*
Y314945D01*
G01X1421720D02*
Y316638D01*
G01X1422990Y316350D02*
X1423025Y316242D01*
G01X1422814D02*
X1422779Y316350D01*
G01X1422884Y316494D02*
X1422990Y316350D01*
G01X1422779D02*
X1422708Y316422D01*
G01X1422743Y316602D02*
X1422884Y316494D01*
G01X1422708Y316422D02*
X1422602Y316458D01*
G01X1422567Y316638D02*
X1422743Y316602D01*
G01X1423519Y316638D02*
X1423731D01*
G01X1421720D02*
X1422567D01*
G01X1422602Y316458D02*
X1421932D01*
G01Y315917D02*
X1422602D01*
G01X1422567Y315701D02*
X1421932D01*
G01Y314945D02*
X1421720D01*
G01X1423731D02*
X1423519D01*
G01X1423787Y314827D02*
X1421622D01*
G01X1426937D02*
X1424772D01*
G01X1430087D02*
X1427921D01*
G01X1433236D02*
X1431071D01*
G01X1436386D02*
X1434220D01*
G01X1439535D02*
X1437370D01*
G01X1442685D02*
X1440520D01*
G01X1445835D02*
X1443669D01*
G01X1448984D02*
X1446819D01*
G01X1452134D02*
X1449968D01*
G01X1455283D02*
X1453118D01*
G01X1458433D02*
X1456268D01*
G01X1461583D02*
X1459417D01*
G01X1464732D02*
X1462567D01*
G01X1467882D02*
X1465717D01*
G01X1422743Y315737D02*
X1422567Y315701D01*
G01X1422606Y332150D02*
X1470023D01*
G01X1418669Y331362D02*
G03X1417882Y332150I-787J1D01*
G01X1418669Y331362D02*
G03X1417882Y332150I-787J1D01*
G01X1446858Y493075D02*
Y535791D01*
G01X1438984Y531854D02*
Y497012D01*
G01X1435835Y502524D02*
Y497012D01*
G01X1422449Y502524D02*
Y497012D01*
G01X1419299Y502524D02*
Y497012D01*
G01D02*
X1438984D01*
G01X1398827Y502524D02*
Y497012D01*
G01X1395677Y502524D02*
Y497012D01*
G01X1391740Y502524D02*
Y497012D01*
G01X1388591Y502524D02*
Y497012D01*
G01X1395677D02*
X1415362D01*
G01Y502524D02*
Y497012D01*
G01X1412213Y502524D02*
Y497012D01*
G01X1420048Y525754D02*
X1420047Y525751D01*
G01X1420048Y525756D02*
Y525754D01*
G01X1420049Y525757D02*
X1420048Y525756D01*
G01X1427922Y525754D02*
X1427921Y525751D01*
G01X1427922Y525756D02*
Y525754D01*
G01X1427923Y525757D02*
X1427922Y525756D01*
G01X1426120Y508823D02*
X1426105D01*
G01X1426135Y508824D02*
X1426120Y508823D01*
G01X1426150Y508825D02*
X1426135Y508824D01*
G01X1422178Y508823D02*
X1422163D01*
G01X1422193Y508824D02*
X1422178Y508823D01*
G01X1422208Y508825D02*
X1422193Y508824D01*
G01X1418246Y508823D02*
X1418231D01*
G01X1418261Y508824D02*
X1418246Y508823D01*
G01X1418276Y508825D02*
X1418261Y508824D01*
G01X1426120Y507839D02*
X1426105D01*
G01X1426135D02*
X1426120D01*
G01X1426150Y507840D02*
X1426135Y507839D01*
G01X1422178D02*
X1422163D01*
G01X1422193D02*
X1422178D01*
G01X1422208Y507840D02*
X1422193Y507839D01*
G01X1418246D02*
X1418231D01*
G01X1418261D02*
X1418246D01*
G01X1418276Y507840D02*
X1418261Y507839D01*
G01X1416411D02*
X1416396D01*
G01X1416426D02*
X1416411D01*
G01X1420338D02*
X1420323Y507840D01*
G01X1420353Y507839D02*
X1420338D01*
G01X1420368D02*
X1420353D01*
G01X1424270D02*
X1424255Y507840D01*
G01X1424285Y507839D02*
X1424270D01*
G01X1424300D02*
X1424285D01*
G01X1428212D02*
X1428197Y507840D01*
G01X1428227Y507839D02*
X1428212D01*
G01X1428242D02*
X1428227D01*
G01X1416411Y508823D02*
X1416396Y508824D01*
G01X1416426Y508823D02*
X1416411D01*
G01X1420338Y508824D02*
X1420323Y508825D01*
G01X1420353Y508823D02*
X1420338Y508824D01*
G01X1420368Y508823D02*
X1420353D01*
G01X1424270Y508824D02*
X1424255Y508825D01*
G01X1424285Y508823D02*
X1424270Y508824D01*
G01X1424300Y508823D02*
X1424285D01*
G01X1420048Y524768D02*
X1420047Y524763D01*
G01X1420048Y524771D02*
Y524768D01*
G01X1420049Y524772D02*
X1420048Y524771D01*
G01X1418551Y508624D02*
Y508627D01*
G01X1418550Y508622D02*
X1418551Y508624D01*
G01X1418549Y508621D02*
X1418550Y508622D01*
G01X1426425Y508624D02*
Y508627D01*
G01X1426424Y508622D02*
X1426425Y508624D01*
G01X1426423Y508621D02*
X1426424Y508622D01*
G01X1428227Y525555D02*
X1428242D01*
G01X1428212Y525554D02*
X1428227Y525555D01*
G01X1428197Y525553D02*
X1428212Y525554D01*
G01X1420353Y525555D02*
X1420368D01*
G01X1420338Y525554D02*
X1420353Y525555D01*
G01X1420323Y525553D02*
X1420338Y525554D01*
G01X1428227Y526539D02*
X1428242D01*
G01X1428212D02*
X1428227D01*
G01X1428197Y526538D02*
X1428212Y526539D01*
G01X1424295D02*
X1424310D01*
G01X1424280D02*
X1424295D01*
G01X1424265Y526538D02*
X1424280Y526539D01*
G01X1420353D02*
X1420368D01*
G01X1420338D02*
X1420353D01*
G01X1420323Y526538D02*
X1420338Y526539D01*
G01X1416421D02*
X1416436D01*
G01X1416406D02*
X1416421D01*
G01X1416390Y526538D02*
X1416406Y526539D01*
G01X1418261D02*
X1418276Y526538D01*
G01X1418246Y526539D02*
X1418261D01*
G01X1418231D02*
X1418246D01*
G01X1422202D02*
X1422217Y526538D01*
G01X1422187Y526539D02*
X1422202D01*
G01X1422172D02*
X1422187D01*
G01X1426135D02*
X1426150Y526538D01*
G01X1426120Y526539D02*
X1426135D01*
G01X1426105D02*
X1426120D01*
G01X1418261Y525554D02*
X1418276Y525553D01*
G01X1418246Y525555D02*
X1418261Y525554D01*
G01X1418231Y525555D02*
X1418246D01*
G01X1422202Y525554D02*
X1422217Y525553D01*
G01X1422187Y525555D02*
X1422202Y525554D01*
G01X1422172Y525555D02*
X1422187D01*
G01X1426135Y525554D02*
X1426150Y525553D01*
G01X1426120Y525555D02*
X1426135Y525554D01*
G01X1426105Y525555D02*
X1426120D01*
G01X1428227Y508823D02*
X1428242D01*
G01X1428212Y508824D02*
X1428227Y508823D01*
G01X1428197Y508825D02*
X1428212Y508824D01*
G01X1418550Y509610D02*
X1418551Y509615D01*
G01X1418550Y509607D02*
Y509610D01*
G01X1418549Y509606D02*
X1418550Y509607D01*
G01X1427922Y524768D02*
X1427921Y524763D01*
G01X1427922Y524771D02*
Y524768D01*
G01X1427923Y524772D02*
X1427922Y524771D01*
G01X1426424Y509610D02*
X1426425Y509615D01*
G01X1426424Y509607D02*
Y509610D01*
G01X1426423Y509606D02*
X1426424Y509607D01*
G01X1418550Y524771D02*
X1418549Y524772D01*
G01X1418550Y524768D02*
Y524771D01*
G01X1418551Y524763D02*
X1418550Y524768D01*
G01X1420048Y509607D02*
X1420049Y509606D01*
G01X1420048Y509610D02*
Y509607D01*
G01X1420047Y509615D02*
X1420048Y509610D01*
G01X1418282Y526485D02*
X1418276Y526538D01*
G01X1418288Y526353D02*
X1418282Y526485D01*
G01X1418294Y526147D02*
X1418288Y526353D01*
G01X1420317Y507893D02*
X1420323Y507840D01*
G01X1420311Y508025D02*
X1420317Y507893D01*
G01X1420305Y508231D02*
X1420311Y508025D01*
G01X1422223Y526485D02*
X1422217Y526538D01*
G01X1422229Y526353D02*
X1422223Y526485D01*
G01X1422235Y526147D02*
X1422229Y526353D01*
G01X1424249Y507893D02*
X1424255Y507840D01*
G01X1424243Y508025D02*
X1424249Y507893D01*
G01X1424237Y508231D02*
X1424243Y508025D01*
G01X1426156Y526485D02*
X1426150Y526538D01*
G01X1426162Y526353D02*
X1426156Y526485D01*
G01X1426168Y526147D02*
X1426162Y526353D01*
G01X1428191Y507893D02*
X1428197Y507840D01*
G01X1428185Y508025D02*
X1428191Y507893D01*
G01X1428179Y508231D02*
X1428185Y508025D01*
G01X1418280Y525511D02*
X1418276Y525553D01*
G01X1418285Y525413D02*
X1418280Y525511D01*
G01X1418289Y525261D02*
X1418285Y525413D01*
G01X1420318Y508867D02*
X1420323Y508825D01*
G01X1420314Y508965D02*
X1420318Y508867D01*
G01X1420310Y509117D02*
X1420314Y508965D01*
G01X1422222Y525511D02*
X1422217Y525553D01*
G01X1422226Y525413D02*
X1422222Y525511D01*
G01X1422230Y525261D02*
X1422226Y525413D01*
G01X1424251Y508867D02*
X1424255Y508825D01*
G01X1424246Y508965D02*
X1424251Y508867D01*
G01X1424242Y509117D02*
X1424246Y508965D01*
G01X1426154Y525511D02*
X1426150Y525553D01*
G01X1426159Y525413D02*
X1426154Y525511D01*
G01X1426163Y525261D02*
X1426159Y525413D01*
G01X1428192Y508867D02*
X1428197Y508825D01*
G01X1428188Y508965D02*
X1428192Y508867D01*
G01X1428184Y509117D02*
X1428188Y508965D01*
G01X1422479Y509645D02*
X1422483Y509615D01*
G01X1422475Y509841D02*
X1422479Y509645D01*
G01X1422472Y510169D02*
X1422475Y509841D01*
G01X1422471Y510571D02*
X1422472Y510169D01*
G01X1423994Y524733D02*
X1423989Y524763D01*
G01X1423998Y524537D02*
X1423994Y524733D01*
G01X1424001Y524209D02*
X1423998Y524537D01*
G01X1424002Y523807D02*
X1424001Y524209D01*
G01X1418541Y508770D02*
X1418549Y508621D01*
G01X1418534Y509184D02*
X1418541Y508770D01*
G01X1418529Y509804D02*
X1418534Y509184D01*
G01X1418528Y510552D02*
X1418529Y509804D01*
G01X1418545Y509679D02*
X1418549Y509606D01*
G01X1418542Y509887D02*
X1418545Y509679D01*
G01X1418539Y510200D02*
X1418542Y509887D01*
G01X1418538Y510571D02*
X1418539Y510200D01*
G01X1420053Y524699D02*
X1420049Y524772D01*
G01X1420057Y524491D02*
X1420053Y524699D01*
G01X1420059Y524178D02*
X1420057Y524491D01*
G01X1420060Y523807D02*
X1420059Y524178D01*
G01X1420057Y525608D02*
X1420049Y525757D01*
G01X1420064Y525193D02*
X1420057Y525608D01*
G01X1420069Y524573D02*
X1420064Y525193D01*
G01X1420071Y523826D02*
X1420069Y524573D01*
G01X1426415Y508770D02*
X1426423Y508621D01*
G01X1426408Y509184D02*
X1426415Y508770D01*
G01X1426403Y509804D02*
X1426408Y509184D01*
G01X1426402Y510552D02*
X1426403Y509804D01*
G01X1426419Y509679D02*
X1426423Y509606D01*
G01X1426416Y509887D02*
X1426419Y509679D01*
G01X1426413Y510200D02*
X1426416Y509887D01*
G01X1426413Y510571D02*
Y510200D01*
G01X1427927Y524699D02*
X1427923Y524772D01*
G01X1427931Y524491D02*
X1427927Y524699D01*
G01X1427933Y524178D02*
X1427931Y524491D01*
G01X1427934Y523807D02*
X1427933Y524178D01*
G01X1427931Y525608D02*
X1427923Y525757D01*
G01X1427938Y525193D02*
X1427931Y525608D01*
G01X1427943Y524573D02*
X1427938Y525193D01*
G01X1427945Y523826D02*
X1427943Y524573D01*
G01X1418529D02*
X1418528Y523826D01*
G01X1418534Y525193D02*
X1418529Y524573D01*
G01X1418541Y525608D02*
X1418534Y525193D01*
G01X1418549Y525757D02*
X1418541Y525608D01*
G01X1420069Y509804D02*
X1420071Y510552D01*
G01X1420064Y509184D02*
X1420069Y509804D01*
G01X1420057Y508770D02*
X1420064Y509184D01*
G01X1420049Y508621D02*
X1420057Y508770D01*
G01X1426403Y524573D02*
X1426402Y523826D01*
G01X1426408Y525193D02*
X1426403Y524573D01*
G01X1426415Y525608D02*
X1426408Y525193D01*
G01X1426423Y525757D02*
X1426415Y525608D01*
G01X1427943Y509804D02*
X1427945Y510552D01*
G01X1427938Y509184D02*
X1427943Y509804D01*
G01X1427931Y508770D02*
X1427938Y509184D01*
G01X1427923Y508621D02*
X1427931Y508770D01*
G01X1418539Y524178D02*
X1418538Y523807D01*
G01X1418542Y524491D02*
X1418539Y524178D01*
G01X1418545Y524699D02*
X1418542Y524491D01*
G01X1418549Y524772D02*
X1418545Y524699D01*
G01X1420059Y510200D02*
X1420060Y510571D01*
G01X1420057Y509887D02*
X1420059Y510200D01*
G01X1420053Y509679D02*
X1420057Y509887D01*
G01X1420049Y509606D02*
X1420053Y509679D01*
G01X1426413Y524178D02*
Y523807D01*
G01X1426416Y524491D02*
X1426413Y524178D01*
G01X1426419Y524699D02*
X1426416Y524491D01*
G01X1426423Y524772D02*
X1426419Y524699D01*
G01X1427933Y510200D02*
X1427934Y510571D01*
G01X1427931Y509887D02*
X1427933Y510200D01*
G01X1427927Y509679D02*
X1427931Y509887D01*
G01X1427923Y509606D02*
X1427927Y509679D01*
G01X1418285Y508965D02*
X1418289Y509117D01*
G01X1418280Y508867D02*
X1418285Y508965D01*
G01X1418276Y508825D02*
X1418280Y508867D01*
G01X1420314Y525413D02*
X1420310Y525261D01*
G01X1420318Y525511D02*
X1420314Y525413D01*
G01X1420323Y525553D02*
X1420318Y525511D01*
G01X1422217Y508965D02*
X1422221Y509117D01*
G01X1422212Y508867D02*
X1422217Y508965D01*
G01X1422208Y508825D02*
X1422212Y508867D01*
G01X1424256Y525413D02*
X1424251Y525261D01*
G01X1424260Y525511D02*
X1424256Y525413D01*
G01X1424265Y525553D02*
X1424260Y525511D01*
G01X1426159Y508965D02*
X1426163Y509117D01*
G01X1426154Y508867D02*
X1426159Y508965D01*
G01X1426150Y508825D02*
X1426154Y508867D01*
G01X1428188Y525413D02*
X1428184Y525261D01*
G01X1428192Y525511D02*
X1428188Y525413D01*
G01X1428197Y525553D02*
X1428192Y525511D01*
G01X1420311Y526353D02*
X1420305Y526147D01*
G01X1420317Y526485D02*
X1420311Y526353D01*
G01X1420323Y526538D02*
X1420317Y526485D01*
G01X1418288Y508025D02*
X1418294Y508231D01*
G01X1418282Y507893D02*
X1418288Y508025D01*
G01X1418276Y507840D02*
X1418282Y507893D01*
G01X1424252Y526353D02*
X1424247Y526147D01*
G01X1424258Y526485D02*
X1424252Y526353D01*
G01X1424265Y526538D02*
X1424258Y526485D01*
G01X1422220Y508025D02*
X1422226Y508231D01*
G01X1422214Y507893D02*
X1422220Y508025D01*
G01X1422208Y507840D02*
X1422214Y507893D01*
G01X1428185Y526353D02*
X1428179Y526147D01*
G01X1428191Y526485D02*
X1428185Y526353D01*
G01X1428197Y526538D02*
X1428191Y526485D01*
G01X1426162Y508025D02*
X1426168Y508231D01*
G01X1426156Y507893D02*
X1426162Y508025D01*
G01X1426150Y507840D02*
X1426156Y507893D01*
G01X1422481Y524209D02*
X1422480Y523807D01*
G01X1422484Y524537D02*
X1422481Y524209D01*
G01X1422488Y524733D02*
X1422484Y524537D01*
G01X1422493Y524763D02*
X1422488Y524733D01*
G01X1423991Y510169D02*
X1423992Y510571D01*
G01X1423988Y509841D02*
X1423991Y510169D01*
G01X1423984Y509645D02*
X1423988Y509841D01*
G01X1423980Y509615D02*
X1423984Y509645D01*
G01X1420048Y508622D02*
X1420049Y508621D01*
G01X1420048Y508624D02*
Y508622D01*
G01X1420047Y508627D02*
X1420048Y508624D01*
G01X1418550Y525756D02*
X1418549Y525757D01*
G01X1418551Y525754D02*
X1418550Y525756D01*
G01X1418551Y525751D02*
Y525754D01*
G01X1426424Y524771D02*
X1426423Y524772D01*
G01X1426424Y524768D02*
Y524771D01*
G01X1426425Y524763D02*
X1426424Y524768D01*
G01X1427922Y509607D02*
X1427923Y509606D01*
G01X1427922Y509610D02*
Y509607D01*
G01X1427921Y509615D02*
X1427922Y509610D01*
G01Y508622D02*
X1427923Y508621D01*
G01X1427922Y508624D02*
Y508622D01*
G01X1427921Y508627D02*
X1427922Y508624D01*
G01X1426424Y525756D02*
X1426423Y525757D01*
G01X1426425Y525754D02*
X1426424Y525756D01*
G01X1426425Y525751D02*
Y525754D01*
G01X1437390Y517189D02*
G03I-3130J0D01*
G01X1438492D02*
G03I-4232J0D01*
G01X1438886D02*
G03I-4626J0D01*
G01X1463588Y519749D02*
X1463849Y519349D01*
G01X1467500Y515220D02*
Y515886D01*
G01X1466457Y521480D02*
Y515220D01*
G01X1465675D02*
Y520415D01*
G01X1464892Y519482D02*
Y520548D01*
G01X1460067Y521480D02*
Y515220D01*
G01X1459284Y518950D02*
Y521480D01*
G01Y515220D02*
Y518151D01*
G01X1455633D02*
Y515220D01*
G01Y521480D02*
Y518950D01*
G01X1426645Y524441D02*
X1426655Y524394D01*
G01X1427702Y509937D02*
X1427692Y509984D01*
G01X1422713Y524441D02*
X1422722Y524394D01*
G01X1423760Y509937D02*
X1423750Y509984D01*
G01X1432617Y513646D02*
X1434575Y510693D01*
G01X1426437Y525738D02*
X1426691Y525368D01*
G01X1426645Y524441D02*
X1426424Y524763D01*
G01X1422504Y525738D02*
X1422758Y525368D01*
G01X1422713Y524441D02*
X1422491Y524763D01*
G01X1418563Y525738D02*
X1418817Y525368D01*
G01X1418771Y524441D02*
X1418550Y524763D01*
G01X1427702Y509937D02*
X1427923Y509615D01*
G01X1427910Y508640D02*
X1427656Y509010D01*
G01X1423760Y509937D02*
X1423981Y509615D01*
G01X1423968Y508640D02*
X1423714Y509010D01*
G01X1463588Y517085D02*
X1461110Y518417D01*
G01X1454850Y515220D02*
Y521480D01*
G01X1438256Y518583D02*
Y529295D01*
G01Y505083D02*
Y515795D01*
G01X1435047Y508626D02*
Y504886D01*
G01Y529492D02*
Y525752D01*
G01X1434575Y510693D02*
Y523685D01*
G01X1433531Y513020D02*
Y505083D01*
G01Y529295D02*
Y521358D01*
G01X1431169Y520732D02*
Y513646D01*
G01X1431110Y525752D02*
Y529492D01*
G01Y504886D02*
Y508626D01*
G01X1418771Y524441D02*
X1418781Y524394D01*
G01X1419828Y509937D02*
X1419818Y509984D01*
G01X1419828Y509937D02*
X1420049Y509615D01*
G01X1420036Y508640D02*
X1419782Y509010D01*
G01X1462023Y518417D02*
X1463849Y517485D01*
G01X1426655Y509984D02*
X1426645Y509937D01*
G01X1427692Y524394D02*
X1427702Y524441D01*
G01X1422713Y509984D02*
X1422703Y509937D01*
G01X1423760Y524394D02*
X1423769Y524441D01*
G01X1427971Y513379D02*
X1428021Y514365D01*
G01X1428019Y515327D02*
X1427968Y514341D01*
G01X1426327Y519051D02*
X1426378Y520037D01*
G01X1426376Y520999D02*
X1426325Y520013D01*
G01X1424029Y513379D02*
X1424080Y514365D01*
G01X1424077Y515327D02*
X1424027Y514341D01*
G01X1422395Y519051D02*
X1422446Y520037D01*
G01X1422443Y520999D02*
X1422393Y520013D01*
G01X1420097Y513379D02*
X1420147Y514365D01*
G01X1420145Y515327D02*
X1420094Y514341D01*
G01X1418453Y519051D02*
X1418504Y520037D01*
G01X1418502Y520999D02*
X1418451Y520013D01*
G01X1428047Y519353D02*
X1428184Y525261D01*
G01X1428179Y526147D02*
X1428043Y520239D01*
G01X1426168Y508231D02*
X1426304Y514139D01*
G01X1426299Y515025D02*
X1426163Y509117D01*
G01X1424115Y519353D02*
X1424251Y525261D01*
G01X1424247Y526147D02*
X1424110Y520239D01*
G01X1422226Y508231D02*
X1422362Y514139D01*
G01X1422357Y515025D02*
X1422221Y509117D01*
G01X1420173Y519353D02*
X1420310Y525261D01*
G01X1420305Y526147D02*
X1420169Y520239D01*
G01X1418294Y508231D02*
X1418430Y514139D01*
G01X1418425Y515025D02*
X1418289Y509117D01*
G01X1427669Y509984D02*
X1427656Y509010D01*
G01X1426677Y524394D02*
X1426691Y525368D01*
G01X1423727Y509984D02*
X1423714Y509010D01*
G01X1422745Y524394D02*
X1422758Y525368D01*
G01X1419795Y509984D02*
X1419782Y509010D01*
G01X1418803Y524394D02*
X1418817Y525368D01*
G01X1428591Y523862D02*
Y528035D01*
G01Y506343D02*
Y510516D01*
G01X1428556Y508823D02*
Y507839D01*
G01X1428551Y508823D02*
Y507839D01*
G01Y526539D02*
Y525555D01*
G01X1428354Y509984D02*
Y503902D01*
G01Y530476D02*
Y524394D01*
G01X1428276Y507839D02*
Y526539D01*
G01X1428197Y508825D02*
Y507840D01*
G01Y526538D02*
Y525553D01*
G01X1428000Y525555D02*
Y530396D01*
G01Y503982D02*
Y508823D01*
G01X1427921Y524760D02*
Y525751D01*
G01Y508627D02*
Y509618D01*
G01X1427843Y504965D02*
Y503902D01*
G01Y530476D02*
Y529413D01*
G01X1427567Y503902D02*
Y504886D01*
G01Y530476D02*
Y529492D01*
G01X1426780D02*
Y530476D01*
G01Y503902D02*
Y504886D01*
G01X1426504Y504965D02*
Y503902D01*
G01Y530476D02*
Y529413D01*
G01X1426425Y509618D02*
Y508627D01*
G01Y525751D02*
Y524760D01*
G01X1426346Y525555D02*
Y530396D01*
G01Y503982D02*
Y508823D01*
G01X1426150Y525553D02*
Y526538D01*
G01Y507840D02*
Y508825D01*
G01X1426071Y526539D02*
Y507839D01*
G01X1425992Y509984D02*
Y503902D01*
G01Y530476D02*
Y524394D01*
G01X1425795Y508823D02*
Y507839D01*
G01Y526539D02*
Y525555D01*
G01X1425791Y526539D02*
Y525555D01*
G01X1425756Y510516D02*
Y506343D01*
G01Y528035D02*
Y523862D01*
G01X1424654D02*
Y528035D01*
G01Y506343D02*
Y510516D01*
G01X1424619Y526539D02*
Y525555D01*
G01X1424614Y508823D02*
Y507839D01*
G01X1424610Y508823D02*
Y507839D01*
G01X1424417Y509984D02*
Y503902D01*
G01Y530476D02*
Y524394D01*
G01X1424339Y507839D02*
Y526539D01*
G01X1424265Y526538D02*
Y525553D01*
G01X1424255Y508825D02*
Y507840D01*
G01X1424063Y521698D02*
Y526539D01*
G01Y507839D02*
Y512680D01*
G01X1423989Y524760D02*
Y525751D01*
G01X1423980Y508627D02*
Y509618D01*
G01X1423906Y512760D02*
Y511696D01*
G01Y522681D02*
Y521618D01*
G01X1423630D02*
Y522602D01*
G01Y512760D02*
Y511776D01*
G01X1422843Y521618D02*
Y522602D01*
G01Y511776D02*
Y512760D01*
G01X1422567D02*
Y511696D01*
G01Y522682D02*
Y521618D01*
G01X1422493Y525751D02*
Y524760D01*
G01X1422484Y509618D02*
Y508627D01*
G01X1422409Y521698D02*
Y526539D01*
G01Y507839D02*
Y512680D01*
G01X1422217Y525553D02*
Y526538D01*
G01X1422208Y507840D02*
Y508825D01*
G01X1422134Y526539D02*
Y507839D01*
G01X1422055Y509984D02*
Y503902D01*
G01Y530476D02*
Y524394D01*
G01X1421863Y526539D02*
Y525555D01*
G01X1421858Y526539D02*
Y525555D01*
G01X1421854Y508823D02*
Y507839D01*
G01X1421819Y510516D02*
Y506343D01*
G01Y528035D02*
Y523862D01*
G01X1420717D02*
Y528035D01*
G01Y506343D02*
Y510516D01*
G01X1420682Y508823D02*
Y507839D01*
G01X1420677Y508823D02*
Y507839D01*
G01Y526539D02*
Y525555D01*
G01X1420480Y509984D02*
Y503902D01*
G01Y530476D02*
Y524394D01*
G01X1420402Y507839D02*
Y526539D01*
G01X1420323Y508825D02*
Y507840D01*
G01Y526538D02*
Y525553D01*
G01X1420126Y525555D02*
Y530396D01*
G01Y503982D02*
Y508823D01*
G01X1420047Y524760D02*
Y525751D01*
G01Y508627D02*
Y509618D01*
G01X1419968Y504965D02*
Y503902D01*
G01Y530476D02*
Y529413D01*
G01X1419693Y504886D02*
Y503902D01*
G01Y530476D02*
Y529492D01*
G01X1418906D02*
Y530476D01*
G01Y504886D02*
Y503902D01*
G01X1418630Y504965D02*
Y503902D01*
G01Y530476D02*
Y529413D01*
G01X1418551Y509618D02*
Y508627D01*
G01Y525751D02*
Y524760D01*
G01X1418472Y525555D02*
Y530396D01*
G01Y503982D02*
Y508823D01*
G01X1418276Y525553D02*
Y526538D01*
G01Y507840D02*
Y508825D01*
G01X1418197Y526539D02*
Y507839D01*
G01X1418118Y509984D02*
Y503902D01*
G01Y530476D02*
Y524394D01*
G01X1417921Y508823D02*
Y507839D01*
G01Y526539D02*
Y525555D01*
G01X1417917Y526539D02*
Y525555D01*
G01X1417882Y510516D02*
Y506343D01*
G01Y528035D02*
Y523862D01*
G01X1416780D02*
Y528035D01*
G01Y506343D02*
Y510516D01*
G01X1416745Y526539D02*
Y525555D01*
G01X1416740Y508823D02*
Y507839D01*
G01X1416735Y508823D02*
Y507839D01*
G01X1416543Y509984D02*
Y503902D01*
G01Y530476D02*
Y524394D01*
G01X1416465Y507839D02*
Y526539D01*
G01X1427656Y525368D02*
X1427669Y524394D01*
G01X1426691Y509010D02*
X1426677Y509984D01*
G01X1423724Y525368D02*
X1423737Y524394D01*
G01X1422749Y509010D02*
X1422736Y509984D01*
G01X1419782Y525368D02*
X1419795Y524394D01*
G01X1418817Y509010D02*
X1418803Y509984D01*
G01X1428184Y509117D02*
X1428047Y515025D01*
G01X1428043Y514139D02*
X1428179Y508231D01*
G01X1426304Y520239D02*
X1426168Y526147D01*
G01X1426163Y525261D02*
X1426299Y519353D01*
G01X1424242Y509117D02*
X1424106Y515025D01*
G01X1424101Y514139D02*
X1424237Y508231D01*
G01X1422371Y520239D02*
X1422235Y526147D01*
G01X1422230Y525261D02*
X1422367Y519353D01*
G01X1420310Y509117D02*
X1420173Y515025D01*
G01X1420169Y514139D02*
X1420305Y508231D01*
G01X1418430Y520239D02*
X1418294Y526147D01*
G01X1418289Y525261D02*
X1418425Y519353D01*
G01X1428021Y520013D02*
X1427971Y520999D01*
G01X1427968Y520037D02*
X1428019Y519051D01*
G01X1426378Y514341D02*
X1426327Y515327D01*
G01X1426325Y514365D02*
X1426376Y513379D01*
G01X1424089Y520013D02*
X1424038Y520999D01*
G01X1424036Y520037D02*
X1424087Y519051D01*
G01X1422436Y514341D02*
X1422386Y515327D01*
G01X1422383Y514365D02*
X1422434Y513379D01*
G01X1420147Y520013D02*
X1420097Y520999D01*
G01X1420094Y520037D02*
X1420145Y519051D01*
G01X1418504Y514341D02*
X1418453Y515327D01*
G01X1418451Y514365D02*
X1418502Y513379D01*
G01X1465675Y520415D02*
X1464892Y519482D01*
G01Y520548D02*
X1465675Y521480D01*
G01X1463849Y517485D02*
X1463588Y517085D01*
G01X1418781Y509984D02*
X1418771Y509937D01*
G01X1419818Y524394D02*
X1419828Y524441D01*
G01X1416543Y530476D02*
X1414181D01*
G01X1420480D02*
X1418118D01*
G01X1424417D02*
X1422055D01*
G01X1428354D02*
X1425992D01*
G01X1431110Y529492D02*
X1435047D01*
G01X1419968D02*
X1418630D01*
G01X1427843D02*
X1426504D01*
G01X1426346Y529394D02*
X1428000D01*
G01X1418472D02*
X1420126D01*
G01X1416543Y529295D02*
X1414181D01*
G01X1420480D02*
X1418118D01*
G01X1424417D02*
X1422055D01*
G01X1428354D02*
X1425992D01*
G01X1438256D02*
X1433531D01*
G01X1420126Y528902D02*
X1418472D01*
G01X1428000D02*
X1426346D01*
G01X1446858Y528409D02*
X1498433D01*
G01X1416780Y528035D02*
X1413945D01*
G01X1420717D02*
X1417882D01*
G01X1424654D02*
X1421819D01*
G01X1428591D02*
X1425756D01*
G01X1420126Y527130D02*
X1418472D01*
G01X1428000D02*
X1426346D01*
G01Y526638D02*
X1428000D01*
G01X1418472D02*
X1420126D01*
G01X1416780Y526539D02*
X1413945D01*
G01X1420717D02*
X1417882D01*
G01X1424654D02*
X1421819D01*
G01X1428591D02*
X1425756D01*
G01X1428000Y526382D02*
X1428591D01*
G01X1425756D02*
X1426346D01*
G01X1424063D02*
X1424654D01*
G01X1421819D02*
X1422409D01*
G01X1420126D02*
X1420717D01*
G01X1417882D02*
X1418472D01*
G01X1416189D02*
X1416780D01*
G01X1426168Y526147D02*
X1428179D01*
G01X1422235D02*
X1424247D01*
G01X1418294D02*
X1420305D01*
G01X1420049Y525757D02*
X1418549D01*
G01X1423991D02*
X1422491D01*
G01X1427923D02*
X1426423D01*
G01X1435047Y525752D02*
X1431110D01*
G01X1426437Y525738D02*
X1427910D01*
G01X1422504D02*
X1423977D01*
G01X1418563D02*
X1420036D01*
G01X1416780Y525713D02*
X1416189D01*
G01X1418472D02*
X1417882D01*
G01X1420717D02*
X1420126D01*
G01X1422409D02*
X1421819D01*
G01X1424654D02*
X1424063D01*
G01X1426346D02*
X1425756D01*
G01X1428591D02*
X1428000D01*
G01X1425756Y525555D02*
X1428591D01*
G01X1421819D02*
X1424654D01*
G01X1417882D02*
X1420717D01*
G01X1413945D02*
X1416780D01*
G01X1424063Y525457D02*
X1422409D01*
G01X1419782Y525368D02*
X1418817D01*
G01X1423724D02*
X1422758D01*
G01X1427656D02*
X1426691D01*
G01X1425756Y525358D02*
X1426071D01*
G01X1421819D02*
X1422134D01*
G01X1417882D02*
X1418197D01*
G01X1416780D02*
X1416465D01*
G01X1420717D02*
X1420402D01*
G01X1424654D02*
X1424339D01*
G01X1428591D02*
X1428276D01*
G01X1420310Y525261D02*
X1418289D01*
G01X1424251D02*
X1422230D01*
G01X1428184D02*
X1426163D01*
G01X1422409Y524965D02*
X1424063D01*
G01X1420049Y524772D02*
X1418549D01*
G01X1423991D02*
X1422491D01*
G01X1427923D02*
X1426423D01*
G01X1438256Y524768D02*
X1433531D01*
G01X1420047Y524763D02*
X1418551D01*
G01X1423989D02*
X1422493D01*
G01X1427921D02*
X1426425D01*
G01X1426645Y524441D02*
X1427702D01*
G01X1422713D02*
X1423769D01*
G01X1418771D02*
X1419828D01*
G01X1416543Y524394D02*
X1414181D01*
G01X1420480D02*
X1418118D01*
G01X1424417D02*
X1422055D01*
G01X1428354D02*
X1425992D01*
G01X1428276Y523862D02*
X1428591D01*
G01X1425756D02*
X1426071D01*
G01X1424339D02*
X1424654D01*
G01X1421819D02*
X1422134D01*
G01X1420402D02*
X1420717D01*
G01X1417882D02*
X1418197D01*
G01X1416465D02*
X1416780D01*
G01X1426402Y523826D02*
X1427945D01*
G01X1422469D02*
X1424013D01*
G01X1418528D02*
X1420071D01*
G01X1426413Y523807D02*
X1427934D01*
G01X1422480D02*
X1424002D01*
G01X1418538D02*
X1420060D01*
G01X1422409Y523193D02*
X1424063D01*
G01Y522701D02*
X1422409D01*
G01X1423906Y522602D02*
X1422567D01*
G01Y521618D02*
X1423906D01*
G01X1465675Y521480D02*
X1466457D01*
G01X1459284D02*
X1460067D01*
G01X1454850D02*
X1455633D01*
G01X1420097Y520999D02*
X1418502D01*
G01X1424038D02*
X1422443D01*
G01X1427971D02*
X1426376D01*
G01X1416465Y520890D02*
X1414260D01*
G01X1420402D02*
X1418197D01*
G01X1424339D02*
X1422134D01*
G01X1428276D02*
X1426071D01*
G01X1420169Y520239D02*
X1418430D01*
G01X1424110D02*
X1422371D01*
G01X1428043D02*
X1426304D01*
G01X1426378Y520037D02*
X1427968D01*
G01X1422446D02*
X1424036D01*
G01X1418504D02*
X1420094D01*
G01X1426325Y520013D02*
X1428021D01*
G01X1422393D02*
X1424089D01*
G01X1418451D02*
X1420147D01*
G01X1420154Y519945D02*
X1418444D01*
G01X1424096D02*
X1422386D01*
G01X1428028D02*
X1426318D01*
G01X1426299Y519353D02*
X1428047D01*
G01X1422367D02*
X1424115D01*
G01X1418425D02*
X1420173D01*
G01X1420145Y519051D02*
X1418453D01*
G01X1424087D02*
X1422395D01*
G01X1428019D02*
X1426327D01*
G01X1420154Y518961D02*
X1418444D01*
G01X1424096D02*
X1422386D01*
G01X1428028D02*
X1426318D01*
G01X1455633Y518950D02*
X1459284D01*
G01X1426071Y518635D02*
X1428276D01*
G01X1422134D02*
X1424339D01*
G01X1418197D02*
X1420402D01*
G01X1414260D02*
X1416465D01*
G01X1426071Y518468D02*
X1428276D01*
G01X1422134D02*
X1424339D01*
G01X1418197D02*
X1420402D01*
G01X1414260D02*
X1416465D01*
G01X1459284Y518151D02*
X1455633D01*
G01X1416465Y515910D02*
X1414260D01*
G01X1420402D02*
X1418197D01*
G01X1424339D02*
X1422134D01*
G01X1428276D02*
X1426071D01*
G01X1467500Y515886D02*
X1468153D01*
G01X1416465Y515743D02*
X1414260D01*
G01X1420402D02*
X1418197D01*
G01X1424339D02*
X1422134D01*
G01X1428276D02*
X1426071D01*
G01X1426318Y515417D02*
X1428028D01*
G01X1422376D02*
X1424087D01*
G01X1418444D02*
X1420154D01*
G01X1426327Y515327D02*
X1428019D01*
G01X1422386D02*
X1424077D01*
G01X1418453D02*
X1420145D01*
G01X1455633Y515220D02*
X1454850D01*
G01X1460067D02*
X1459284D01*
G01X1466457D02*
X1465675D01*
G01X1468153D02*
X1467500D01*
G01X1420173Y515025D02*
X1418425D01*
G01X1424106D02*
X1422357D01*
G01X1428047D02*
X1426299D01*
G01X1426318Y514433D02*
X1428028D01*
G01X1422376D02*
X1424087D01*
G01X1418444D02*
X1420154D01*
G01X1420147Y514365D02*
X1418451D01*
G01X1424080D02*
X1422383D01*
G01X1428021D02*
X1426325D01*
G01X1420094Y514341D02*
X1418504D01*
G01X1424027D02*
X1422436D01*
G01X1427968D02*
X1426378D01*
G01X1426304Y514139D02*
X1428043D01*
G01X1422362D02*
X1424101D01*
G01X1418430D02*
X1420169D01*
G01X1426071Y513488D02*
X1428276D01*
G01X1422134D02*
X1424339D01*
G01X1418197D02*
X1420402D01*
G01X1414260D02*
X1416465D01*
G01X1426376Y513379D02*
X1427971D01*
G01X1422434D02*
X1424029D01*
G01X1418502D02*
X1420097D01*
G01X1423906Y512760D02*
X1422567D01*
G01X1423906Y511776D02*
X1422567D01*
G01X1422409Y511677D02*
X1424063D01*
G01Y511185D02*
X1422409D01*
G01X1426437Y508640D02*
X1426691Y509010D01*
G01X1426424Y509615D02*
X1426645Y509937D01*
G01X1422495Y508640D02*
X1422749Y509010D01*
G01X1422482Y509615D02*
X1422703Y509937D01*
G01X1418563Y508640D02*
X1418817Y509010D01*
G01X1418550Y509615D02*
X1418771Y509937D01*
G01X1427923Y524763D02*
X1427702Y524441D01*
G01X1427910Y525738D02*
X1427656Y525368D01*
G01X1423991Y524763D02*
X1423769Y524441D01*
G01X1423977Y525738D02*
X1423724Y525368D01*
G01X1420049Y524763D02*
X1419828Y524441D01*
G01X1420036Y525738D02*
X1419782Y525368D01*
G01X1434575Y523685D02*
X1432617Y520732D01*
G01X1420060Y510571D02*
X1418538D01*
G01X1423992D02*
X1422471D01*
G01X1427934D02*
X1426413D01*
G01X1420071Y510552D02*
X1418528D01*
G01X1424003D02*
X1422460D01*
G01X1427945D02*
X1426402D01*
G01X1416780Y510516D02*
X1416465D01*
G01X1418197D02*
X1417882D01*
G01X1422134D02*
X1421819D01*
G01X1420717D02*
X1420402D01*
G01X1424654D02*
X1424339D01*
G01X1426071D02*
X1425756D01*
G01X1428591D02*
X1428276D01*
G01X1416543Y509984D02*
X1414181D01*
G01X1420480D02*
X1418118D01*
G01X1424417D02*
X1422055D01*
G01X1428354D02*
X1425992D01*
G01X1419828Y509937D02*
X1418771D01*
G01X1423760D02*
X1422703D01*
G01X1427702D02*
X1426645D01*
G01X1426425Y509615D02*
X1427921D01*
G01X1422483D02*
X1423980D01*
G01X1418551D02*
X1420047D01*
G01X1438256Y509610D02*
X1433531D01*
G01X1426423Y509606D02*
X1427923D01*
G01X1422482D02*
X1423981D01*
G01X1418549D02*
X1420049D01*
G01X1424063Y509413D02*
X1422409D01*
G01X1426163Y509117D02*
X1428184D01*
G01X1422221D02*
X1424242D01*
G01X1418289D02*
X1420310D01*
G01X1428276Y509020D02*
X1428591D01*
G01X1424339D02*
X1424654D01*
G01X1420402D02*
X1420717D01*
G01X1416465D02*
X1416780D01*
G01X1418197D02*
X1417882D01*
G01X1422134D02*
X1421819D01*
G01X1426071D02*
X1425756D01*
G01X1426691Y509010D02*
X1427656D01*
G01X1422749D02*
X1423714D01*
G01X1418817D02*
X1419782D01*
G01X1422409Y508921D02*
X1424063D01*
G01X1425756Y508823D02*
X1428591D01*
G01X1421819D02*
X1424654D01*
G01X1417882D02*
X1420717D01*
G01X1413945D02*
X1416780D01*
G01X1428000Y508665D02*
X1428591D01*
G01X1425756D02*
X1426346D01*
G01X1424063D02*
X1424654D01*
G01X1421819D02*
X1422409D01*
G01X1420126D02*
X1420717D01*
G01X1417882D02*
X1418472D01*
G01X1416189D02*
X1416780D01*
G01X1420036Y508640D02*
X1418563D01*
G01X1423968D02*
X1422495D01*
G01X1427910D02*
X1426437D01*
G01X1431110Y508626D02*
X1435047D01*
G01X1426423Y508621D02*
X1427923D01*
G01X1422482D02*
X1423981D01*
G01X1418549D02*
X1420049D01*
G01X1420305Y508231D02*
X1418294D01*
G01X1424237D02*
X1422226D01*
G01X1428179D02*
X1426168D01*
G01X1416780Y507996D02*
X1416189D01*
G01X1418472D02*
X1417882D01*
G01X1420717D02*
X1420126D01*
G01X1422409D02*
X1421819D01*
G01X1424654D02*
X1424063D01*
G01X1426346D02*
X1425756D01*
G01X1428591D02*
X1428000D01*
G01X1416780Y507839D02*
X1413945D01*
G01X1420717D02*
X1417882D01*
G01X1424654D02*
X1421819D01*
G01X1428591D02*
X1425756D01*
G01X1420126Y507740D02*
X1418472D01*
G01X1428000D02*
X1426346D01*
G01Y507248D02*
X1428000D01*
G01X1418472D02*
X1420126D01*
G01X1491688Y506362D02*
X1446858D01*
G01X1425756Y506343D02*
X1428591D01*
G01X1421819D02*
X1424654D01*
G01X1417882D02*
X1420717D01*
G01X1413945D02*
X1416780D01*
G01X1426346Y505476D02*
X1428000D01*
G01X1418472D02*
X1420126D01*
G01X1433531Y505083D02*
X1438256D01*
G01X1425992D02*
X1428354D01*
G01X1416543D02*
X1414181D01*
G01X1420480D02*
X1418118D01*
G01X1424417D02*
X1422055D01*
G01X1420126Y504984D02*
X1418472D01*
G01X1428000D02*
X1426346D01*
G01X1419968Y504886D02*
X1418630D01*
G01X1427843D02*
X1426504D01*
G01X1435047D02*
X1431110D01*
G01X1425992Y503902D02*
X1428354D01*
G01X1422055D02*
X1424417D01*
G01X1418118D02*
X1420480D01*
G01X1414181D02*
X1416543D01*
G01X1463849Y519349D02*
X1462023Y518417D01*
G01X1461110D02*
X1463588Y519749D01*
G01X1446858Y573055D02*
Y616008D01*
G01X1438984Y611854D02*
Y577012D01*
G01X1435835Y582524D02*
Y577012D01*
G01X1419299D02*
X1438984D01*
G01X1422449Y582524D02*
Y577012D01*
G01X1419299Y582524D02*
Y577012D01*
G01X1388552Y525754D02*
X1388551Y525751D01*
G01X1388552Y525756D02*
Y525754D01*
G01X1388553Y525757D02*
X1388552Y525756D01*
G01X1396426Y525754D02*
X1396425Y525751D01*
G01X1396426Y525756D02*
Y525754D01*
G01X1396427Y525757D02*
X1396426Y525756D01*
G01X1388552Y524768D02*
X1388551Y524763D01*
G01X1388552Y524771D02*
Y524768D01*
G01X1388553Y524772D02*
X1388552Y524771D01*
G01X1394929Y508624D02*
Y508627D01*
G01X1394928Y508622D02*
X1394929Y508624D01*
G01X1394927Y508621D02*
X1394928Y508622D01*
G01X1398556Y508823D02*
X1398541D01*
G01X1398571Y508824D02*
X1398556Y508823D01*
G01X1398586Y508825D02*
X1398571Y508824D01*
G01X1394624Y508823D02*
X1394609D01*
G01X1394639Y508824D02*
X1394624Y508823D01*
G01X1394654Y508825D02*
X1394639Y508824D01*
G01X1390682Y508823D02*
X1390667D01*
G01X1390697Y508824D02*
X1390682Y508823D01*
G01X1390712Y508825D02*
X1390697Y508824D01*
G01X1398556Y507839D02*
X1398541D01*
G01X1398571D02*
X1398556D01*
G01X1398586Y507840D02*
X1398571Y507839D01*
G01X1394624D02*
X1394609D01*
G01X1394639D02*
X1394624D01*
G01X1394654Y507840D02*
X1394639Y507839D01*
G01X1390682D02*
X1390667D01*
G01X1390697D02*
X1390682D01*
G01X1390712Y507840D02*
X1390697Y507839D01*
G01X1388842D02*
X1388827Y507840D01*
G01X1388857Y507839D02*
X1388842D01*
G01X1388872D02*
X1388857D01*
G01X1392774D02*
X1392759Y507840D01*
G01X1392789Y507839D02*
X1392774D01*
G01X1392804D02*
X1392789D01*
G01X1396716D02*
X1396701Y507840D01*
G01X1396731Y507839D02*
X1396716D01*
G01X1396746D02*
X1396731D01*
G01X1400648D02*
X1400633Y507840D01*
G01X1400663Y507839D02*
X1400648D01*
G01X1400678D02*
X1400663D01*
G01X1388842Y508824D02*
X1388827Y508825D01*
G01X1388857Y508823D02*
X1388842Y508824D01*
G01X1388872Y508823D02*
X1388857D01*
G01X1392774Y508824D02*
X1392759Y508825D01*
G01X1392789Y508823D02*
X1392774Y508824D01*
G01X1392804Y508823D02*
X1392789D01*
G01X1396716Y508824D02*
X1396701Y508825D01*
G01X1396731Y508823D02*
X1396716Y508824D01*
G01X1396746Y508823D02*
X1396731D01*
G01X1400648Y508824D02*
X1400633Y508825D01*
G01X1400663Y508823D02*
X1400648Y508824D01*
G01X1400678Y508823D02*
X1400663D01*
G01X1388818Y525413D02*
X1388814Y525261D01*
G01X1388822Y525511D02*
X1388818Y525413D01*
G01X1388827Y525553D02*
X1388822Y525511D01*
G01X1388815Y526353D02*
X1388809Y526147D01*
G01X1388821Y526485D02*
X1388815Y526353D01*
G01X1388827Y526538D02*
X1388821Y526485D01*
G01X1390985Y524209D02*
X1390984Y523807D01*
G01X1390988Y524537D02*
X1390985Y524209D01*
G01X1390992Y524733D02*
X1390988Y524537D01*
G01X1390997Y524763D02*
X1390992Y524733D01*
G01X1396426Y524768D02*
X1396425Y524763D01*
G01X1396426Y524771D02*
Y524768D01*
G01X1396427Y524772D02*
X1396426Y524771D01*
G01X1394928Y509610D02*
X1394929Y509615D01*
G01X1394928Y509607D02*
Y509610D01*
G01X1394927Y509606D02*
X1394928Y509607D01*
G01X1400672Y525555D02*
X1400687D01*
G01X1400657Y525554D02*
X1400672Y525555D01*
G01X1400642Y525553D02*
X1400657Y525554D01*
G01X1396731Y525555D02*
X1396746D01*
G01X1396716Y525554D02*
X1396731Y525555D01*
G01X1396701Y525553D02*
X1396716Y525554D01*
G01X1388857Y525555D02*
X1388872D01*
G01X1388842Y525554D02*
X1388857Y525555D01*
G01X1388827Y525553D02*
X1388842Y525554D01*
G01X1400672Y526539D02*
X1400687D01*
G01X1400657D02*
X1400672D01*
G01X1400642Y526538D02*
X1400657Y526539D01*
G01X1396731D02*
X1396746D01*
G01X1396716D02*
X1396731D01*
G01X1396701Y526538D02*
X1396716Y526539D01*
G01X1392798D02*
X1392813D01*
G01X1392783D02*
X1392798D01*
G01X1392768Y526538D02*
X1392783Y526539D01*
G01X1388857D02*
X1388872D01*
G01X1388842D02*
X1388857D01*
G01X1388827Y526538D02*
X1388842Y526539D01*
G01X1390706D02*
X1390721Y526538D01*
G01X1390691Y526539D02*
X1390706D01*
G01X1390676D02*
X1390691D01*
G01X1394639D02*
X1394654Y526538D01*
G01X1394624Y526539D02*
X1394639D01*
G01X1394609D02*
X1394624D01*
G01X1398580D02*
X1398595Y526538D01*
G01X1398565Y526539D02*
X1398580D01*
G01X1398550D02*
X1398565D01*
G01X1390706Y525554D02*
X1390721Y525553D01*
G01X1390691Y525555D02*
X1390706Y525554D01*
G01X1390676Y525555D02*
X1390691D01*
G01X1394639Y525554D02*
X1394654Y525553D01*
G01X1394624Y525555D02*
X1394639Y525554D01*
G01X1394609Y525555D02*
X1394624D01*
G01X1398565D02*
X1398550D01*
G01X1398580Y525554D02*
X1398565Y525555D01*
G01X1398595Y525553D02*
X1398580Y525554D01*
G01X1388552Y509607D02*
X1388553Y509606D01*
G01X1388552Y509610D02*
Y509607D01*
G01X1388551Y509615D02*
X1388552Y509610D01*
G01X1394928Y524771D02*
X1394927Y524772D01*
G01X1394928Y524768D02*
Y524771D01*
G01X1394929Y524763D02*
X1394928Y524768D01*
G01X1396426Y509607D02*
X1396427Y509606D01*
G01X1396426Y509610D02*
Y509607D01*
G01X1396425Y509615D02*
X1396426Y509610D01*
G01X1388821Y507893D02*
X1388827Y507840D01*
G01X1388815Y508025D02*
X1388821Y507893D01*
G01X1388809Y508231D02*
X1388815Y508025D01*
G01X1390727Y526485D02*
X1390721Y526538D01*
G01X1390733Y526353D02*
X1390727Y526485D01*
G01X1390739Y526147D02*
X1390733Y526353D01*
G01X1392753Y507893D02*
X1392759Y507840D01*
G01X1392747Y508025D02*
X1392753Y507893D01*
G01X1392741Y508231D02*
X1392747Y508025D01*
G01X1394660Y526485D02*
X1394654Y526538D01*
G01X1394666Y526353D02*
X1394660Y526485D01*
G01X1394672Y526147D02*
X1394666Y526353D01*
G01X1396695Y507893D02*
X1396701Y507840D01*
G01X1396689Y508025D02*
X1396695Y507893D01*
G01X1396683Y508231D02*
X1396689Y508025D01*
G01X1398601Y526485D02*
X1398595Y526538D01*
G01X1398607Y526353D02*
X1398601Y526485D01*
G01X1398613Y526147D02*
X1398607Y526353D01*
G01X1400627Y507893D02*
X1400633Y507840D01*
G01X1400621Y508025D02*
X1400627Y507893D01*
G01X1400615Y508231D02*
X1400621Y508025D01*
G01X1388822Y508867D02*
X1388827Y508825D01*
G01X1388818Y508965D02*
X1388822Y508867D01*
G01X1388814Y509117D02*
X1388818Y508965D01*
G01X1390726Y525511D02*
X1390721Y525553D01*
G01X1390730Y525413D02*
X1390726Y525511D01*
G01X1390734Y525261D02*
X1390730Y525413D01*
G01X1392755Y508867D02*
X1392759Y508825D01*
G01X1392750Y508965D02*
X1392755Y508867D01*
G01X1392746Y509117D02*
X1392750Y508965D01*
G01X1394658Y525511D02*
X1394654Y525553D01*
G01X1394663Y525413D02*
X1394658Y525511D01*
G01X1394667Y525261D02*
X1394663Y525413D01*
G01X1396696Y508867D02*
X1396701Y508825D01*
G01X1396692Y508965D02*
X1396696Y508867D01*
G01X1396688Y509117D02*
X1396692Y508965D01*
G01X1398600Y525511D02*
X1398595Y525553D01*
G01X1398604Y525413D02*
X1398600Y525511D01*
G01X1398608Y525261D02*
X1398604Y525413D01*
G01X1400629Y508867D02*
X1400633Y508825D01*
G01X1400624Y508965D02*
X1400629Y508867D01*
G01X1400620Y509117D02*
X1400624Y508965D01*
G01X1390983Y509645D02*
X1390987Y509615D01*
G01X1390979Y509841D02*
X1390983Y509645D01*
G01X1390976Y510169D02*
X1390979Y509841D01*
G01X1390975Y510571D02*
X1390976Y510169D01*
G01X1392498Y524733D02*
X1392493Y524763D01*
G01X1392502Y524537D02*
X1392498Y524733D01*
G01X1392504Y524209D02*
X1392502Y524537D01*
G01X1392506Y523807D02*
X1392504Y524209D01*
G01X1398857Y509645D02*
X1398861Y509615D01*
G01X1398853Y509841D02*
X1398857Y509645D01*
G01X1398850Y510169D02*
X1398853Y509841D01*
G01X1398849Y510571D02*
X1398850Y510169D01*
G01X1400372Y524733D02*
X1400367Y524763D01*
G01X1400376Y524537D02*
X1400372Y524733D01*
G01X1400378Y524209D02*
X1400376Y524537D01*
G01X1400380Y523807D02*
X1400378Y524209D01*
G01X1388557Y524699D02*
X1388553Y524772D01*
G01X1388561Y524491D02*
X1388557Y524699D01*
G01X1388563Y524178D02*
X1388561Y524491D01*
G01X1388564Y523807D02*
X1388563Y524178D01*
G01X1388561Y525608D02*
X1388553Y525757D01*
G01X1388568Y525193D02*
X1388561Y525608D01*
G01X1388573Y524573D02*
X1388568Y525193D01*
G01X1388575Y523826D02*
X1388573Y524573D01*
G01X1394919Y508770D02*
X1394927Y508621D01*
G01X1394912Y509184D02*
X1394919Y508770D01*
G01X1394907Y509804D02*
X1394912Y509184D01*
G01X1394905Y510552D02*
X1394907Y509804D01*
G01X1394923Y509679D02*
X1394927Y509606D01*
G01X1394920Y509887D02*
X1394923Y509679D01*
G01X1394917Y510200D02*
X1394920Y509887D01*
G01X1394916Y510571D02*
X1394917Y510200D01*
G01X1396431Y524699D02*
X1396427Y524772D01*
G01X1396435Y524491D02*
X1396431Y524699D01*
G01X1396437Y524178D02*
X1396435Y524491D01*
G01X1396438Y523807D02*
X1396437Y524178D01*
G01X1396435Y525608D02*
X1396427Y525757D01*
G01X1396442Y525193D02*
X1396435Y525608D01*
G01X1396447Y524573D02*
X1396442Y525193D01*
G01X1396449Y523826D02*
X1396447Y524573D01*
G01X1388573Y509804D02*
X1388575Y510552D01*
G01X1388568Y509184D02*
X1388573Y509804D01*
G01X1388561Y508770D02*
X1388568Y509184D01*
G01X1388553Y508621D02*
X1388561Y508770D01*
G01X1394907Y524573D02*
X1394905Y523826D01*
G01X1394912Y525193D02*
X1394907Y524573D01*
G01X1394919Y525608D02*
X1394912Y525193D01*
G01X1394927Y525757D02*
X1394919Y525608D01*
G01X1396447Y509804D02*
X1396449Y510552D01*
G01X1396442Y509184D02*
X1396447Y509804D01*
G01X1396435Y508770D02*
X1396442Y509184D01*
G01X1396427Y508621D02*
X1396435Y508770D01*
G01X1388563Y510200D02*
X1388564Y510571D01*
G01X1388561Y509887D02*
X1388563Y510200D01*
G01X1388557Y509679D02*
X1388561Y509887D01*
G01X1388553Y509606D02*
X1388557Y509679D01*
G01X1394917Y524178D02*
X1394916Y523807D01*
G01X1394920Y524491D02*
X1394917Y524178D01*
G01X1394923Y524699D02*
X1394920Y524491D01*
G01X1394927Y524772D02*
X1394923Y524699D01*
G01X1396437Y510200D02*
X1396438Y510571D01*
G01X1396435Y509887D02*
X1396437Y510200D01*
G01X1396431Y509679D02*
X1396435Y509887D01*
G01X1396427Y509606D02*
X1396431Y509679D01*
G01X1390721Y508965D02*
X1390725Y509117D01*
G01X1390716Y508867D02*
X1390721Y508965D01*
G01X1390712Y508825D02*
X1390716Y508867D01*
G01X1392759Y525413D02*
X1392755Y525261D01*
G01X1392764Y525511D02*
X1392759Y525413D01*
G01X1392768Y525553D02*
X1392764Y525511D01*
G01X1394663Y508965D02*
X1394667Y509117D01*
G01X1394658Y508867D02*
X1394663Y508965D01*
G01X1394654Y508825D02*
X1394658Y508867D01*
G01X1396692Y525413D02*
X1396688Y525261D01*
G01X1396696Y525511D02*
X1396692Y525413D01*
G01X1396701Y525553D02*
X1396696Y525511D01*
G01X1398595Y508965D02*
X1398599Y509117D01*
G01X1398590Y508867D02*
X1398595Y508965D01*
G01X1398586Y508825D02*
X1398590Y508867D01*
G01X1400633Y525413D02*
X1400629Y525261D01*
G01X1400638Y525511D02*
X1400633Y525413D01*
G01X1400642Y525553D02*
X1400638Y525511D01*
G01X1392756Y526353D02*
X1392750Y526147D01*
G01X1392762Y526485D02*
X1392756Y526353D01*
G01X1392768Y526538D02*
X1392762Y526485D01*
G01X1390724Y508025D02*
X1390730Y508231D01*
G01X1390718Y507893D02*
X1390724Y508025D01*
G01X1390712Y507840D02*
X1390718Y507893D01*
G01X1396689Y526353D02*
X1396683Y526147D01*
G01X1396695Y526485D02*
X1396689Y526353D01*
G01X1396701Y526538D02*
X1396695Y526485D01*
G01X1394666Y508025D02*
X1394672Y508231D01*
G01X1394660Y507893D02*
X1394666Y508025D01*
G01X1394654Y507840D02*
X1394660Y507893D01*
G01X1400630Y526353D02*
X1400624Y526147D01*
G01X1400636Y526485D02*
X1400630Y526353D01*
G01X1400642Y526538D02*
X1400636Y526485D01*
G01X1398598Y508025D02*
X1398604Y508231D01*
G01X1398592Y507893D02*
X1398598Y508025D01*
G01X1398586Y507840D02*
X1398592Y507893D01*
G01X1392495Y510169D02*
X1392496Y510571D01*
G01X1392492Y509841D02*
X1392495Y510169D01*
G01X1392488Y509645D02*
X1392492Y509841D01*
G01X1392484Y509615D02*
X1392488Y509645D01*
G01X1398859Y524209D02*
X1398858Y523807D01*
G01X1398862Y524537D02*
X1398859Y524209D01*
G01X1398866Y524733D02*
X1398862Y524537D01*
G01X1398871Y524763D02*
X1398866Y524733D01*
G01X1400369Y510169D02*
X1400370Y510571D01*
G01X1400366Y509841D02*
X1400369Y510169D01*
G01X1400362Y509645D02*
X1400366Y509841D01*
G01X1400358Y509615D02*
X1400362Y509645D01*
G01X1388552Y508622D02*
X1388553Y508621D01*
G01X1388552Y508624D02*
Y508622D01*
G01X1388551Y508627D02*
X1388552Y508624D01*
G01X1396426Y508622D02*
X1396427Y508621D01*
G01X1396426Y508624D02*
Y508622D01*
G01X1396425Y508627D02*
X1396426Y508624D01*
G01X1394928Y525756D02*
X1394927Y525757D01*
G01X1394929Y525754D02*
X1394928Y525756D01*
G01X1394929Y525751D02*
Y525754D01*
G01X1399091Y524441D02*
X1399100Y524394D01*
G01X1400138Y509937D02*
X1400128Y509984D01*
G01X1398882Y525738D02*
X1399136Y525368D01*
G01X1399091Y524441D02*
X1398869Y524763D01*
G01X1394941Y525738D02*
X1395194Y525368D01*
G01X1395149Y524441D02*
X1394928Y524763D01*
G01X1391008Y525738D02*
X1391262Y525368D01*
G01X1391217Y524441D02*
X1390995Y524763D01*
G01X1400138Y509937D02*
X1400359Y509615D01*
G01X1400346Y508640D02*
X1400092Y509010D01*
G01X1396205Y509937D02*
X1396427Y509615D01*
G01X1396414Y508640D02*
X1396160Y509010D01*
G01X1395149Y524441D02*
X1395158Y524394D01*
G01X1396205Y509937D02*
X1396196Y509984D01*
G01X1391217Y524441D02*
X1391226Y524394D01*
G01X1392264Y509937D02*
X1392254Y509984D01*
G01X1388331Y509937D02*
X1388322Y509984D01*
G01X1392264Y509937D02*
X1392485Y509615D01*
G01X1392472Y508640D02*
X1392218Y509010D01*
G01X1388331Y509937D02*
X1388553Y509615D01*
G01X1388540Y508640D02*
X1388286Y509010D01*
G01X1389594Y547622D02*
X1388364D01*
G01X1393531D02*
X1392301D01*
G01X1396730D02*
X1395500D01*
G01X1400667D02*
X1399437D01*
G01X1399091Y509984D02*
X1399081Y509937D01*
G01X1400138Y524394D02*
X1400147Y524441D01*
G01X1395158Y509984D02*
X1395149Y509937D01*
G01X1400407Y513379D02*
X1400458Y514365D01*
G01X1400455Y515327D02*
X1400405Y514341D01*
G01X1398773Y519051D02*
X1398824Y520037D01*
G01X1398821Y520999D02*
X1398771Y520013D01*
G01X1396475Y513379D02*
X1396525Y514365D01*
G01X1396523Y515327D02*
X1396472Y514341D01*
G01X1394831Y519051D02*
X1394882Y520037D01*
G01X1394880Y520999D02*
X1394829Y520013D01*
G01X1392533Y513379D02*
X1392584Y514365D01*
G01X1392581Y515327D02*
X1392531Y514341D01*
G01X1390899Y519051D02*
X1390950Y520037D01*
G01X1390947Y520999D02*
X1390897Y520013D01*
G01X1388601Y513379D02*
X1388651Y514365D01*
G01X1388649Y515327D02*
X1388598Y514341D01*
G01X1400493Y519353D02*
X1400629Y525261D01*
G01X1400624Y526147D02*
X1400488Y520239D01*
G01X1398604Y508231D02*
X1398740Y514139D01*
G01X1398735Y515025D02*
X1398599Y509117D01*
G01X1396551Y519353D02*
X1396688Y525261D01*
G01X1396683Y526147D02*
X1396547Y520239D01*
G01X1394672Y508231D02*
X1394808Y514139D01*
G01X1394803Y515025D02*
X1394667Y509117D01*
G01X1392619Y519353D02*
X1392755Y525261D01*
G01X1392750Y526147D02*
X1392614Y520239D01*
G01X1390730Y508231D02*
X1390866Y514139D01*
G01X1390861Y515025D02*
X1390725Y509117D01*
G01X1388677Y519353D02*
X1388814Y525261D01*
G01X1388809Y526147D02*
X1388673Y520239D01*
G01X1400105Y509984D02*
X1400092Y509010D01*
G01X1399123Y524394D02*
X1399136Y525368D01*
G01X1396173Y509984D02*
X1396160Y509010D01*
G01X1395181Y524394D02*
X1395194Y525368D01*
G01X1392231Y509984D02*
X1392218Y509010D01*
G01X1391249Y524394D02*
X1391262Y525368D01*
G01X1388299Y509984D02*
X1388286Y509010D01*
G01X1400795Y509984D02*
Y503902D01*
G01Y530476D02*
Y524394D01*
G01X1400717Y507839D02*
Y526539D01*
G01X1400667Y553653D02*
Y547622D01*
G01X1400642Y526538D02*
Y525553D01*
G01X1400633Y508825D02*
Y507840D01*
G01X1400441Y521698D02*
Y526539D01*
G01Y507839D02*
Y512680D01*
G01X1400367Y524760D02*
Y525751D01*
G01X1400358Y508627D02*
Y509618D01*
G01X1400283Y512760D02*
Y511696D01*
G01Y522681D02*
Y521618D01*
G01X1400008Y512760D02*
Y511776D01*
G01Y522602D02*
Y521618D01*
G01X1399437Y547622D02*
Y553653D01*
G01X1399220Y512760D02*
Y511776D01*
G01Y522602D02*
Y521618D01*
G01X1398945Y512760D02*
Y511696D01*
G01Y522682D02*
Y521618D01*
G01X1398871Y525751D02*
Y524760D01*
G01X1398861Y509618D02*
Y508627D01*
G01X1398787Y521698D02*
Y526539D01*
G01Y507839D02*
Y512680D01*
G01X1398595Y525553D02*
Y526538D01*
G01X1398586Y507840D02*
Y508825D01*
G01X1398512Y526539D02*
Y507839D01*
G01X1398433Y509984D02*
Y503902D01*
G01Y530476D02*
Y524394D01*
G01X1398241Y526539D02*
Y525555D01*
G01X1398236Y526539D02*
Y525555D01*
G01X1398232Y508823D02*
Y507839D01*
G01X1398197Y510516D02*
Y506343D01*
G01Y528035D02*
Y523862D01*
G01X1397094D02*
Y528035D01*
G01Y506343D02*
Y510516D01*
G01X1397060Y508823D02*
Y507839D01*
G01X1397055Y508823D02*
Y507839D01*
G01Y526539D02*
Y525555D01*
G01X1396858Y509984D02*
Y503902D01*
G01Y530476D02*
Y524394D01*
G01X1396780Y507839D02*
Y526539D01*
G01X1396730Y553905D02*
Y547622D01*
G01X1396701Y508825D02*
Y507840D01*
G01Y526538D02*
Y525553D01*
G01X1396504Y525555D02*
Y530396D01*
G01Y503982D02*
Y508823D01*
G01X1396425Y524760D02*
Y525751D01*
G01Y508627D02*
Y509618D01*
G01X1396346Y504965D02*
Y503902D01*
G01Y530476D02*
Y529413D01*
G01X1396071Y504886D02*
Y503902D01*
G01Y530476D02*
Y529492D01*
G01X1395500Y547622D02*
Y555664D01*
G01X1395283Y529492D02*
Y530476D01*
G01Y504886D02*
Y503902D01*
G01X1395008Y504965D02*
Y503902D01*
G01Y530476D02*
Y529413D01*
G01X1394929Y509618D02*
Y508627D01*
G01Y525751D02*
Y524760D01*
G01X1394850Y525555D02*
Y530396D01*
G01Y503982D02*
Y508823D01*
G01X1394654Y525553D02*
Y526538D01*
G01Y507840D02*
Y508825D01*
G01X1394575Y526539D02*
Y507839D01*
G01X1394496Y509984D02*
Y503902D01*
G01Y530476D02*
Y524394D01*
G01X1394299Y508823D02*
Y507839D01*
G01Y526539D02*
Y525555D01*
G01X1394295Y526539D02*
Y525555D01*
G01X1394260Y510516D02*
Y506343D01*
G01Y528035D02*
Y523862D01*
G01X1393531Y553653D02*
Y547622D01*
G01X1393157Y523862D02*
Y528035D01*
G01Y506343D02*
Y510516D01*
G01X1393123Y526539D02*
Y525555D01*
G01X1393118Y508823D02*
Y507839D01*
G01X1393113Y508823D02*
Y507839D01*
G01X1392921Y509984D02*
Y503902D01*
G01Y530476D02*
Y524394D01*
G01X1392843Y507839D02*
Y526539D01*
G01X1392768Y526538D02*
Y525553D01*
G01X1392759Y508825D02*
Y507840D01*
G01X1392567Y521698D02*
Y526539D01*
G01Y507839D02*
Y512680D01*
G01X1392493Y524760D02*
Y525751D01*
G01X1392484Y508627D02*
Y509618D01*
G01X1392409Y512760D02*
Y511696D01*
G01Y522681D02*
Y521618D01*
G01X1392301Y547622D02*
Y553653D01*
G01X1392134Y521618D02*
Y522602D01*
G01Y512760D02*
Y511776D01*
G01X1391346Y521618D02*
Y522602D01*
G01Y511776D02*
Y512760D01*
G01X1391071D02*
Y511696D01*
G01Y522682D02*
Y521618D01*
G01X1390997Y525751D02*
Y524760D01*
G01X1390987Y509618D02*
Y508627D01*
G01X1390913Y521698D02*
Y526539D01*
G01Y507839D02*
Y512680D01*
G01X1390721Y525553D02*
Y526538D01*
G01X1390712Y507840D02*
Y508825D01*
G01X1390638Y526539D02*
Y507839D01*
G01X1390559Y509984D02*
Y503902D01*
G01Y530476D02*
Y524394D01*
G01X1390367Y526539D02*
Y525555D01*
G01X1390362Y526539D02*
Y525555D01*
G01X1390358Y508823D02*
Y507839D01*
G01X1390323Y510516D02*
Y506343D01*
G01Y528035D02*
Y523862D01*
G01X1389594Y553653D02*
Y547622D01*
G01X1389220Y523862D02*
Y528035D01*
G01Y506343D02*
Y510516D01*
G01X1389186Y508823D02*
Y507839D01*
G01X1389181Y508823D02*
Y507839D01*
G01Y526539D02*
Y525555D01*
G01X1388984Y509984D02*
Y503902D01*
G01Y530476D02*
Y524394D01*
G01X1388906Y507839D02*
Y526539D01*
G01X1388827Y508825D02*
Y507840D01*
G01Y526538D02*
Y525553D01*
G01X1388630Y525555D02*
Y530396D01*
G01Y503982D02*
Y508823D01*
G01X1388551Y524760D02*
Y525751D01*
G01Y508627D02*
Y509618D01*
G01X1388472Y504965D02*
Y503902D01*
G01Y530476D02*
Y529413D01*
G01X1388364Y547622D02*
Y553653D01*
G01X1388197Y504886D02*
Y503902D01*
G01Y530476D02*
Y529492D01*
G01X1400102Y525368D02*
X1400115Y524394D01*
G01X1399127Y509010D02*
X1399114Y509984D01*
G01X1396160Y525368D02*
X1396173Y524394D01*
G01X1395194Y509010D02*
X1395181Y509984D01*
G01X1392227Y525368D02*
X1392241Y524394D01*
G01X1391253Y509010D02*
X1391240Y509984D01*
G01X1388286Y525368D02*
X1388299Y524394D01*
G01X1400620Y509117D02*
X1400484Y515025D01*
G01X1400479Y514139D02*
X1400615Y508231D01*
G01X1398749Y520239D02*
X1398613Y526147D01*
G01X1398608Y525261D02*
X1398745Y519353D01*
G01X1396688Y509117D02*
X1396551Y515025D01*
G01X1396547Y514139D02*
X1396683Y508231D01*
G01X1394808Y520239D02*
X1394672Y526147D01*
G01X1394667Y525261D02*
X1394803Y519353D01*
G01X1392746Y509117D02*
X1392610Y515025D01*
G01X1392605Y514139D02*
X1392741Y508231D01*
G01X1390875Y520239D02*
X1390739Y526147D01*
G01X1390734Y525261D02*
X1390871Y519353D01*
G01X1388814Y509117D02*
X1388677Y515025D01*
G01X1388673Y514139D02*
X1388809Y508231D01*
G01X1400467Y520013D02*
X1400416Y520999D01*
G01X1400414Y520037D02*
X1400465Y519051D01*
G01X1398814Y514341D02*
X1398764Y515327D01*
G01X1398761Y514365D02*
X1398812Y513379D01*
G01X1396525Y520013D02*
X1396475Y520999D01*
G01X1396472Y520037D02*
X1396523Y519051D01*
G01X1394882Y514341D02*
X1394831Y515327D01*
G01X1394829Y514365D02*
X1394880Y513379D01*
G01X1392593Y520013D02*
X1392542Y520999D01*
G01X1392540Y520037D02*
X1392591Y519051D01*
G01X1390940Y514341D02*
X1390890Y515327D01*
G01X1390887Y514365D02*
X1390938Y513379D01*
G01X1388651Y520013D02*
X1388601Y520999D01*
G01X1388598Y520037D02*
X1388649Y519051D01*
G01X1392921Y530476D02*
X1390559D01*
G01X1396858D02*
X1394496D01*
G01X1400795D02*
X1398433D01*
G01X1396346Y529492D02*
X1395008D01*
G01X1394850Y529394D02*
X1396504D01*
G01X1392921Y529295D02*
X1390559D01*
G01X1396858D02*
X1394496D01*
G01X1400795D02*
X1398433D01*
G01X1396504Y528902D02*
X1394850D01*
G01X1393157Y528035D02*
X1390323D01*
G01X1397094D02*
X1394260D01*
G01X1401031D02*
X1398197D01*
G01X1396504Y527130D02*
X1394850D01*
G01Y526638D02*
X1396504D01*
G01X1393157Y526539D02*
X1390323D01*
G01X1397094D02*
X1394260D01*
G01X1401031D02*
X1398197D01*
G01X1400441Y526382D02*
X1401031D01*
G01X1398197D02*
X1398787D01*
G01X1396504D02*
X1397094D01*
G01X1394260D02*
X1394850D01*
G01X1392567D02*
X1393157D01*
G01X1390323D02*
X1390913D01*
G01X1388630D02*
X1389220D01*
G01X1398613Y526147D02*
X1400624D01*
G01X1394672D02*
X1396683D01*
G01X1390739D02*
X1392750D01*
G01X1392495Y525757D02*
X1390995D01*
G01X1396427D02*
X1394927D01*
G01X1400369D02*
X1398869D01*
G01X1398882Y525738D02*
X1400355D01*
G01X1394941D02*
X1396414D01*
G01X1391008D02*
X1392481D01*
G01X1389220Y525713D02*
X1388630D01*
G01X1390913D02*
X1390323D01*
G01X1393157D02*
X1392567D01*
G01X1394850D02*
X1394260D01*
G01X1397094D02*
X1396504D01*
G01X1398787D02*
X1398197D01*
G01X1401031D02*
X1400441D01*
G01X1398197Y525555D02*
X1401031D01*
G01X1394260D02*
X1397094D01*
G01X1390323D02*
X1393157D01*
G01X1392567Y525457D02*
X1390913D01*
G01X1400441D02*
X1398787D01*
G01X1392227Y525368D02*
X1391262D01*
G01X1396160D02*
X1395194D01*
G01X1400102D02*
X1399136D01*
G01X1398197Y525358D02*
X1398512D01*
G01X1394260D02*
X1394575D01*
G01X1390323D02*
X1390638D01*
G01X1389220D02*
X1388906D01*
G01X1393157D02*
X1392843D01*
G01X1397094D02*
X1396780D01*
G01X1401031D02*
X1400717D01*
G01X1392755Y525261D02*
X1390734D01*
G01X1396688D02*
X1394667D01*
G01X1400629D02*
X1398608D01*
G01X1398787Y524965D02*
X1400441D01*
G01X1390913D02*
X1392567D01*
G01X1392495Y524772D02*
X1390995D01*
G01X1396427D02*
X1394927D01*
G01X1400369D02*
X1398869D01*
G01X1392493Y524763D02*
X1390997D01*
G01X1396425D02*
X1394929D01*
G01X1400367D02*
X1398871D01*
G01X1399091Y524441D02*
X1400147D01*
G01X1395149D02*
X1396205D01*
G01X1391217D02*
X1392273D01*
G01X1392921Y524394D02*
X1390559D01*
G01X1396858D02*
X1394496D01*
G01X1400795D02*
X1398433D01*
G01X1400717Y523862D02*
X1401031D01*
G01X1398197D02*
X1398512D01*
G01X1396780D02*
X1397094D01*
G01X1394260D02*
X1394575D01*
G01X1392843D02*
X1393157D01*
G01X1390323D02*
X1390638D01*
G01X1388906D02*
X1389220D01*
G01X1398847Y523826D02*
X1400391D01*
G01X1394905D02*
X1396449D01*
G01X1390973D02*
X1392517D01*
G01X1398858Y523807D02*
X1400380D01*
G01X1394916D02*
X1396438D01*
G01X1390984D02*
X1392506D01*
G01X1398787Y523193D02*
X1400441D01*
G01X1390913D02*
X1392567D01*
G01Y522701D02*
X1390913D01*
G01X1400441D02*
X1398787D01*
G01X1392409Y522602D02*
X1391071D01*
G01X1400283D02*
X1398945D01*
G01Y521618D02*
X1400283D01*
G01X1391071D02*
X1392409D01*
G01X1392542Y520999D02*
X1390947D01*
G01X1396475D02*
X1394880D01*
G01X1400416D02*
X1398821D01*
G01X1392843Y520890D02*
X1390638D01*
G01X1396780D02*
X1394575D01*
G01X1400717D02*
X1398512D01*
G01X1392614Y520239D02*
X1390875D01*
G01X1396547D02*
X1394808D01*
G01X1400488D02*
X1398749D01*
G01X1398824Y520037D02*
X1400414D01*
G01X1394882D02*
X1396472D01*
G01X1390950D02*
X1392540D01*
G01X1398771Y520013D02*
X1400467D01*
G01X1394829D02*
X1396525D01*
G01X1390897D02*
X1392593D01*
G01X1392600Y519945D02*
X1390890D01*
G01X1396532D02*
X1394822D01*
G01X1400474D02*
X1398764D01*
G01X1398745Y519353D02*
X1400493D01*
G01X1394803D02*
X1396551D01*
G01X1390871D02*
X1392619D01*
G01X1392591Y519051D02*
X1390899D01*
G01X1396523D02*
X1394831D01*
G01X1400465D02*
X1398773D01*
G01X1392600Y518961D02*
X1390890D01*
G01X1396532D02*
X1394822D01*
G01X1400474D02*
X1398764D01*
G01X1398512Y518635D02*
X1400717D01*
G01X1394575D02*
X1396780D01*
G01X1390638D02*
X1392843D01*
G01X1398512Y518468D02*
X1400717D01*
G01X1394575D02*
X1396780D01*
G01X1390638D02*
X1392843D01*
G01Y515910D02*
X1390638D01*
G01X1396780D02*
X1394575D01*
G01X1400717D02*
X1398512D01*
G01X1392843Y515743D02*
X1390638D01*
G01X1396780D02*
X1394575D01*
G01X1400717D02*
X1398512D01*
G01X1398754Y515417D02*
X1400465D01*
G01X1394822D02*
X1396532D01*
G01X1390880D02*
X1392591D01*
G01X1398764Y515327D02*
X1400455D01*
G01X1394831D02*
X1396523D01*
G01X1390890D02*
X1392581D01*
G01X1392610Y515025D02*
X1390861D01*
G01X1396551D02*
X1394803D01*
G01X1400484D02*
X1398735D01*
G01X1398754Y514433D02*
X1400465D01*
G01X1394822D02*
X1396532D01*
G01X1390880D02*
X1392591D01*
G01X1392584Y514365D02*
X1390887D01*
G01X1396525D02*
X1394829D01*
G01X1400458D02*
X1398761D01*
G01X1392531Y514341D02*
X1390940D01*
G01X1396472D02*
X1394882D01*
G01X1400405D02*
X1398814D01*
G01X1398740Y514139D02*
X1400479D01*
G01X1394808D02*
X1396547D01*
G01X1390866D02*
X1392605D01*
G01X1398512Y513488D02*
X1400717D01*
G01X1394575D02*
X1396780D01*
G01X1390638D02*
X1392843D01*
G01X1398812Y513379D02*
X1400407D01*
G01X1394880D02*
X1396475D01*
G01X1390938D02*
X1392533D01*
G01X1392409Y512760D02*
X1391071D01*
G01X1400283D02*
X1398945D01*
G01X1392409Y511776D02*
X1391071D01*
G01X1400283D02*
X1398945D01*
G01X1398787Y511677D02*
X1400441D01*
G01X1390913D02*
X1392567D01*
G01Y511185D02*
X1390913D01*
G01X1400441D02*
X1398787D01*
G01X1396196Y524394D02*
X1396205Y524441D01*
G01X1391217Y509984D02*
X1391207Y509937D01*
G01X1392264Y524394D02*
X1392273Y524441D01*
G01X1388322Y524394D02*
X1388331Y524441D01*
G01X1392496Y510571D02*
X1390975D01*
G01X1396438D02*
X1394916D01*
G01X1400370D02*
X1398849D01*
G01X1392507Y510552D02*
X1390964D01*
G01X1396449D02*
X1394905D01*
G01X1400381D02*
X1398838D01*
G01X1389220Y510516D02*
X1388906D01*
G01X1390638D02*
X1390323D01*
G01X1393157D02*
X1392843D01*
G01X1394575D02*
X1394260D01*
G01X1397094D02*
X1396780D01*
G01X1398512D02*
X1398197D01*
G01X1401031D02*
X1400717D01*
G01X1392921Y509984D02*
X1390559D01*
G01X1396858D02*
X1394496D01*
G01X1400795D02*
X1398433D01*
G01X1392264Y509937D02*
X1391207D01*
G01X1396205D02*
X1395149D01*
G01X1400138D02*
X1399081D01*
G01X1398861Y509615D02*
X1400358D01*
G01X1394929D02*
X1396425D01*
G01X1390987D02*
X1392484D01*
G01X1398860Y509606D02*
X1400359D01*
G01X1394927D02*
X1396427D01*
G01X1390986D02*
X1392485D01*
G01X1392567Y509413D02*
X1390913D01*
G01X1400441D02*
X1398787D01*
G01X1398599Y509117D02*
X1400620D01*
G01X1394667D02*
X1396688D01*
G01X1390725D02*
X1392746D01*
G01X1400717Y509020D02*
X1401031D01*
G01X1396780D02*
X1397094D01*
G01X1392843D02*
X1393157D01*
G01X1388906D02*
X1389220D01*
G01X1390638D02*
X1390323D01*
G01X1394575D02*
X1394260D01*
G01X1398512D02*
X1398197D01*
G01X1399127Y509010D02*
X1400092D01*
G01X1395194D02*
X1396160D01*
G01X1391253D02*
X1392218D01*
G01X1398787Y508921D02*
X1400441D01*
G01X1390913D02*
X1392567D01*
G01X1398197Y508823D02*
X1401031D01*
G01X1394260D02*
X1397094D01*
G01X1390323D02*
X1393157D01*
G01X1400441Y508665D02*
X1401031D01*
G01X1398197D02*
X1398787D01*
G01X1396504D02*
X1397094D01*
G01X1394260D02*
X1394850D01*
G01X1392567D02*
X1393157D01*
G01X1390323D02*
X1390913D01*
G01X1388630D02*
X1389220D01*
G01X1392472Y508640D02*
X1390999D01*
G01X1396414D02*
X1394941D01*
G01X1400346D02*
X1398873D01*
G01X1398860Y508621D02*
X1400359D01*
G01X1394927D02*
X1396427D01*
G01X1390986D02*
X1392485D01*
G01X1392741Y508231D02*
X1390730D01*
G01X1396683D02*
X1394672D01*
G01X1400615D02*
X1398604D01*
G01X1389220Y507996D02*
X1388630D01*
G01X1390913D02*
X1390323D01*
G01X1393157D02*
X1392567D01*
G01X1394850D02*
X1394260D01*
G01X1397094D02*
X1396504D01*
G01X1398787D02*
X1398197D01*
G01X1401031D02*
X1400441D01*
G01X1393157Y507839D02*
X1390323D01*
G01X1397094D02*
X1394260D01*
G01X1401031D02*
X1398197D01*
G01X1396504Y507740D02*
X1394850D01*
G01Y507248D02*
X1396504D01*
G01X1398197Y506343D02*
X1401031D01*
G01X1394260D02*
X1397094D01*
G01X1390323D02*
X1393157D01*
G01X1394850Y505476D02*
X1396504D01*
G01X1392921Y505083D02*
X1390559D01*
G01X1396858D02*
X1394496D01*
G01X1400795D02*
X1398433D01*
G01X1396504Y504984D02*
X1394850D01*
G01X1396346Y504886D02*
X1395008D01*
G01X1398433Y503902D02*
X1400795D01*
G01X1394496D02*
X1396858D01*
G01X1390559D02*
X1392921D01*
G01X1398873Y508640D02*
X1399127Y509010D01*
G01X1398860Y509615D02*
X1399081Y509937D01*
G01X1394941Y508640D02*
X1395194Y509010D01*
G01X1394928Y509615D02*
X1395149Y509937D01*
G01X1390999Y508640D02*
X1391253Y509010D01*
G01X1390986Y509615D02*
X1391207Y509937D01*
G01X1400368Y524763D02*
X1400147Y524441D01*
G01X1400355Y525738D02*
X1400102Y525368D01*
G01X1396427Y524763D02*
X1396205Y524441D01*
G01X1396414Y525738D02*
X1396160Y525368D01*
G01X1392494Y524763D02*
X1392273Y524441D01*
G01X1392481Y525738D02*
X1392227Y525368D01*
G01X1388553Y524763D02*
X1388331Y524441D01*
G01X1388540Y525738D02*
X1388286Y525368D01*
G01X1399437Y553653D02*
X1399191Y554156D01*
G01X1399683Y555412D02*
X1400421Y554658D01*
G01X1399191Y554156D02*
X1398945Y554407D01*
G01X1392547Y555412D02*
X1393039Y554910D01*
G01X1392055Y554156D02*
X1391809Y554407D01*
G01X1388610Y555412D02*
X1389348Y554658D01*
G01X1388118Y554156D02*
X1387872Y554407D01*
G01X1398945D02*
X1398453Y554658D01*
G01X1393039Y554910D02*
X1393531Y553653D01*
G01X1392301D02*
X1392055Y554156D01*
G01X1388364Y553653D02*
X1388118Y554156D01*
G01X1391809Y554407D02*
X1391317Y554658D01*
G01X1398945Y555664D02*
X1399683Y555412D01*
G01X1391809Y555664D02*
X1392547Y555412D01*
G01X1387872Y555664D02*
X1388610Y555412D01*
G01X1395677Y577012D02*
X1415362D01*
G01X1397961Y555664D02*
X1398945D01*
G01X1395500D02*
X1396730D01*
G01X1390825D02*
X1391809D01*
G01X1391317Y554658D02*
X1390579D01*
G01X1398453D02*
X1397961D01*
G01X1398827Y582524D02*
Y577012D01*
G01X1396730Y555664D02*
Y554910D01*
G01X1395677Y582524D02*
Y577012D01*
G01X1391740Y582524D02*
Y577012D01*
G01X1388591Y582524D02*
Y577012D01*
G01X1400913Y554156D02*
X1400667Y553653D01*
G01X1389841Y554156D02*
X1389594Y553653D01*
G01X1401159Y554407D02*
X1400913Y554156D01*
G01X1400421Y554658D02*
X1401159Y555412D01*
G01X1397222Y554407D02*
X1396730Y553905D01*
G01Y554910D02*
X1397222Y555412D01*
G01X1390087Y554407D02*
X1389841Y554156D01*
G01X1389348Y554658D02*
X1390087Y555412D01*
G01X1397961Y554658D02*
X1397222Y554407D01*
G01Y555412D02*
X1397961Y555664D01*
G01X1390087Y555412D02*
X1390825Y555664D01*
G01X1390579Y554658D02*
X1390087Y554407D01*
G01X1404300Y525754D02*
X1404299Y525751D01*
G01X1404300Y525756D02*
Y525754D01*
G01X1404301Y525757D02*
X1404300Y525756D01*
G01X1412174Y525754D02*
X1412173Y525751D01*
G01X1412174Y525756D02*
Y525754D01*
G01X1412175Y525757D02*
X1412174Y525756D01*
G01X1402803Y508624D02*
Y508627D01*
G01X1402802Y508622D02*
X1402803Y508624D01*
G01X1402801Y508621D02*
X1402802Y508622D01*
G01X1410677Y508624D02*
Y508627D01*
G01X1410676Y508622D02*
X1410677Y508624D01*
G01X1410675Y508621D02*
X1410676Y508622D01*
G01X1414304Y508823D02*
X1414289D01*
G01X1414319Y508824D02*
X1414304Y508823D01*
G01X1414334Y508825D02*
X1414319Y508824D01*
G01X1410372Y508823D02*
X1410357D01*
G01X1410387Y508824D02*
X1410372Y508823D01*
G01X1410402Y508825D02*
X1410387Y508824D01*
G01X1406430Y508823D02*
X1406415D01*
G01X1406445Y508824D02*
X1406430Y508823D01*
G01X1406460Y508825D02*
X1406445Y508824D01*
G01X1402498Y508823D02*
X1402483D01*
G01X1402513Y508824D02*
X1402498Y508823D01*
G01X1402528Y508825D02*
X1402513Y508824D01*
G01X1414304Y507839D02*
X1414289D01*
G01X1414319D02*
X1414304D01*
G01X1414334Y507840D02*
X1414319Y507839D01*
G01X1410372D02*
X1410357D01*
G01X1410387D02*
X1410372D01*
G01X1410402Y507840D02*
X1410387Y507839D01*
G01X1406430D02*
X1406415D01*
G01X1406445D02*
X1406430D01*
G01X1406460Y507840D02*
X1406445Y507839D01*
G01X1402498D02*
X1402483D01*
G01X1402513D02*
X1402498D01*
G01X1402528Y507840D02*
X1402513Y507839D01*
G01X1404590D02*
X1404575Y507840D01*
G01X1404605Y507839D02*
X1404590D01*
G01X1404620D02*
X1404605D01*
G01X1408522D02*
X1408507Y507840D01*
G01X1408537Y507839D02*
X1408522D01*
G01X1408552D02*
X1408537D01*
G01X1412464D02*
X1412449Y507840D01*
G01X1412479Y507839D02*
X1412464D01*
G01X1412494D02*
X1412479D01*
G01X1416396D02*
X1416381Y507840D01*
G01X1404590Y508824D02*
X1404575Y508825D01*
G01X1404605Y508823D02*
X1404590Y508824D01*
G01X1404620Y508823D02*
X1404605D01*
G01X1408522Y508824D02*
X1408507Y508825D01*
G01X1408537Y508823D02*
X1408522Y508824D01*
G01X1408552Y508823D02*
X1408537D01*
G01X1412464Y508824D02*
X1412449Y508825D01*
G01X1412479Y508823D02*
X1412464Y508824D01*
G01X1412494Y508823D02*
X1412479D01*
G01X1416396Y508824D02*
X1416381Y508825D01*
G01X1404300Y524768D02*
X1404299Y524763D01*
G01X1404300Y524771D02*
Y524768D01*
G01X1404301Y524772D02*
X1404300Y524771D01*
G01X1402802Y509610D02*
X1402803Y509615D01*
G01X1402802Y509607D02*
Y509610D01*
G01X1402801Y509606D02*
X1402802Y509607D01*
G01X1412174Y524768D02*
X1412173Y524763D01*
G01X1412174Y524771D02*
Y524768D01*
G01X1412175Y524772D02*
X1412174Y524771D01*
G01X1410676Y509610D02*
X1410677Y509615D01*
G01X1410676Y509607D02*
Y509610D01*
G01X1410675Y509606D02*
X1410676Y509607D01*
G01X1412479Y525555D02*
X1412494D01*
G01X1412464Y525554D02*
X1412479Y525555D01*
G01X1412449Y525553D02*
X1412464Y525554D01*
G01X1408546Y525555D02*
X1408562D01*
G01X1408531Y525554D02*
X1408546Y525555D01*
G01X1408516Y525553D02*
X1408531Y525554D01*
G01X1404605Y525555D02*
X1404620D01*
G01X1404590Y525554D02*
X1404605Y525555D01*
G01X1404575Y525553D02*
X1404590Y525554D01*
G01X1412479Y526539D02*
X1412494D01*
G01X1412464D02*
X1412479D01*
G01X1412449Y526538D02*
X1412464Y526539D01*
G01X1408546D02*
X1408562D01*
G01X1408531D02*
X1408546D01*
G01X1408516Y526538D02*
X1408531Y526539D01*
G01X1404605D02*
X1404620D01*
G01X1404590D02*
X1404605D01*
G01X1404575Y526538D02*
X1404590Y526539D01*
G01X1402513D02*
X1402528Y526538D01*
G01X1402498Y526539D02*
X1402513D01*
G01X1402483D02*
X1402498D01*
G01X1406454D02*
X1406469Y526538D01*
G01X1406439Y526539D02*
X1406454D01*
G01X1406424D02*
X1406439D01*
G01X1410387D02*
X1410402Y526538D01*
G01X1410372Y526539D02*
X1410387D01*
G01X1410357D02*
X1410372D01*
G01X1414328D02*
X1414343Y526538D01*
G01X1414313Y526539D02*
X1414328D01*
G01X1414298D02*
X1414313D01*
G01X1402513Y525554D02*
X1402528Y525553D01*
G01X1402498Y525555D02*
X1402513Y525554D01*
G01X1402483Y525555D02*
X1402498D01*
G01X1410387Y525554D02*
X1410402Y525553D01*
G01X1410372Y525555D02*
X1410387Y525554D01*
G01X1410357Y525555D02*
X1410372D01*
G01X1414328Y525554D02*
X1414343Y525553D01*
G01X1414313Y525555D02*
X1414328Y525554D01*
G01X1414298Y525555D02*
X1414313D01*
G01X1406439D02*
X1406424D01*
G01X1406454Y525554D02*
X1406439Y525555D01*
G01X1406469Y525553D02*
X1406454Y525554D01*
G01X1402534Y526485D02*
X1402528Y526538D01*
G01X1402540Y526353D02*
X1402534Y526485D01*
G01X1402546Y526147D02*
X1402540Y526353D01*
G01X1404569Y507893D02*
X1404575Y507840D01*
G01X1404563Y508025D02*
X1404569Y507893D01*
G01X1404557Y508231D02*
X1404563Y508025D01*
G01X1402532Y525511D02*
X1402528Y525553D01*
G01X1402537Y525413D02*
X1402532Y525511D01*
G01X1402541Y525261D02*
X1402537Y525413D01*
G01X1404570Y508867D02*
X1404575Y508825D01*
G01X1404566Y508965D02*
X1404570Y508867D01*
G01X1404562Y509117D02*
X1404566Y508965D01*
G01X1402793Y508770D02*
X1402801Y508621D01*
G01X1402786Y509184D02*
X1402793Y508770D01*
G01X1402781Y509804D02*
X1402786Y509184D01*
G01X1402780Y510552D02*
X1402781Y509804D01*
G01X1402797Y509679D02*
X1402801Y509606D01*
G01X1402794Y509887D02*
X1402797Y509679D01*
G01X1402791Y510200D02*
X1402794Y509887D01*
G01X1402790Y510571D02*
X1402791Y510200D01*
G01X1404305Y524699D02*
X1404301Y524772D01*
G01X1404309Y524491D02*
X1404305Y524699D01*
G01X1404311Y524178D02*
X1404309Y524491D01*
G01X1404312Y523807D02*
X1404311Y524178D01*
G01X1404309Y525608D02*
X1404301Y525757D01*
G01X1404316Y525193D02*
X1404309Y525608D01*
G01X1404321Y524573D02*
X1404316Y525193D01*
G01X1404323Y523826D02*
X1404321Y524573D01*
G01X1402781D02*
X1402780Y523826D01*
G01X1402786Y525193D02*
X1402781Y524573D01*
G01X1402793Y525608D02*
X1402786Y525193D01*
G01X1402801Y525757D02*
X1402793Y525608D01*
G01X1404321Y509804D02*
X1404323Y510552D01*
G01X1404316Y509184D02*
X1404321Y509804D01*
G01X1404309Y508770D02*
X1404316Y509184D01*
G01X1404301Y508621D02*
X1404309Y508770D01*
G01X1402791Y524178D02*
X1402790Y523807D01*
G01X1402794Y524491D02*
X1402791Y524178D01*
G01X1402797Y524699D02*
X1402794Y524491D01*
G01X1402801Y524772D02*
X1402797Y524699D01*
G01X1404311Y510200D02*
X1404312Y510571D01*
G01X1404309Y509887D02*
X1404311Y510200D01*
G01X1404305Y509679D02*
X1404309Y509887D01*
G01X1404301Y509606D02*
X1404305Y509679D01*
G01X1402537Y508965D02*
X1402541Y509117D01*
G01X1402532Y508867D02*
X1402537Y508965D01*
G01X1402528Y508825D02*
X1402532Y508867D01*
G01X1404566Y525413D02*
X1404562Y525261D01*
G01X1404570Y525511D02*
X1404566Y525413D01*
G01X1404575Y525553D02*
X1404570Y525511D01*
G01X1406469Y508965D02*
X1406473Y509117D01*
G01X1406464Y508867D02*
X1406469Y508965D01*
G01X1406460Y508825D02*
X1406464Y508867D01*
G01X1408508Y525413D02*
X1408503Y525261D01*
G01X1408512Y525511D02*
X1408508Y525413D01*
G01X1408516Y525553D02*
X1408512Y525511D01*
G01X1410411Y508965D02*
X1410415Y509117D01*
G01X1410406Y508867D02*
X1410411Y508965D01*
G01X1410402Y508825D02*
X1410406Y508867D01*
G01X1412440Y525413D02*
X1412436Y525261D01*
G01X1412444Y525511D02*
X1412440Y525413D01*
G01X1412449Y525553D02*
X1412444Y525511D01*
G01X1404563Y526353D02*
X1404557Y526147D01*
G01X1404569Y526485D02*
X1404563Y526353D01*
G01X1404575Y526538D02*
X1404569Y526485D01*
G01X1402540Y508025D02*
X1402546Y508231D01*
G01X1402534Y507893D02*
X1402540Y508025D01*
G01X1402528Y507840D02*
X1402534Y507893D01*
G01X1408504Y526353D02*
X1408498Y526147D01*
G01X1408510Y526485D02*
X1408504Y526353D01*
G01X1408516Y526538D02*
X1408510Y526485D01*
G01X1406472Y508025D02*
X1406478Y508231D01*
G01X1406466Y507893D02*
X1406472Y508025D01*
G01X1406460Y507840D02*
X1406466Y507893D01*
G01X1412437Y526353D02*
X1412431Y526147D01*
G01X1412443Y526485D02*
X1412437Y526353D01*
G01X1412449Y526538D02*
X1412443Y526485D01*
G01X1410414Y508025D02*
X1410420Y508231D01*
G01X1410408Y507893D02*
X1410414Y508025D01*
G01X1410402Y507840D02*
X1410408Y507893D01*
G01X1406733Y524209D02*
X1406732Y523807D01*
G01X1406736Y524537D02*
X1406733Y524209D01*
G01X1406740Y524733D02*
X1406736Y524537D01*
G01X1406745Y524763D02*
X1406740Y524733D01*
G01X1408243Y510169D02*
X1408244Y510571D01*
G01X1408240Y509841D02*
X1408243Y510169D01*
G01X1408236Y509645D02*
X1408240Y509841D01*
G01X1408232Y509615D02*
X1408236Y509645D01*
G01X1414607Y524209D02*
X1414606Y523807D01*
G01X1414610Y524537D02*
X1414607Y524209D01*
G01X1414614Y524733D02*
X1414610Y524537D01*
G01X1414619Y524763D02*
X1414614Y524733D01*
G01X1402802Y524771D02*
X1402801Y524772D01*
G01X1402802Y524768D02*
Y524771D01*
G01X1402803Y524763D02*
X1402802Y524768D01*
G01X1404300Y509607D02*
X1404301Y509606D01*
G01X1404300Y509610D02*
Y509607D01*
G01X1404299Y509615D02*
X1404300Y509610D01*
G01X1410676Y524771D02*
X1410675Y524772D01*
G01X1410676Y524768D02*
Y524771D01*
G01X1410677Y524763D02*
X1410676Y524768D01*
G01X1412174Y509607D02*
X1412175Y509606D01*
G01X1412174Y509610D02*
Y509607D01*
G01X1412173Y509615D02*
X1412174Y509610D01*
G01X1406475Y526485D02*
X1406469Y526538D01*
G01X1406481Y526353D02*
X1406475Y526485D01*
G01X1406487Y526147D02*
X1406481Y526353D01*
G01X1408501Y507893D02*
X1408507Y507840D01*
G01X1408495Y508025D02*
X1408501Y507893D01*
G01X1408489Y508231D02*
X1408495Y508025D01*
G01X1410408Y526485D02*
X1410402Y526538D01*
G01X1410414Y526353D02*
X1410408Y526485D01*
G01X1410420Y526147D02*
X1410414Y526353D01*
G01X1412443Y507893D02*
X1412449Y507840D01*
G01X1412437Y508025D02*
X1412443Y507893D01*
G01X1412431Y508231D02*
X1412437Y508025D01*
G01X1414349Y526485D02*
X1414343Y526538D01*
G01X1414355Y526353D02*
X1414349Y526485D01*
G01X1414361Y526147D02*
X1414355Y526353D01*
G01X1416375Y507893D02*
X1416381Y507840D01*
G01X1416369Y508025D02*
X1416375Y507893D01*
G01X1416363Y508231D02*
X1416369Y508025D01*
G01X1406474Y525511D02*
X1406469Y525553D01*
G01X1406478Y525413D02*
X1406474Y525511D01*
G01X1406482Y525261D02*
X1406478Y525413D01*
G01X1408503Y508867D02*
X1408507Y508825D01*
G01X1408498Y508965D02*
X1408503Y508867D01*
G01X1408494Y509117D02*
X1408498Y508965D01*
G01X1410406Y525511D02*
X1410402Y525553D01*
G01X1410411Y525413D02*
X1410406Y525511D01*
G01X1410415Y525261D02*
X1410411Y525413D01*
G01X1412444Y508867D02*
X1412449Y508825D01*
G01X1412440Y508965D02*
X1412444Y508867D01*
G01X1412436Y509117D02*
X1412440Y508965D01*
G01X1414348Y525511D02*
X1414343Y525553D01*
G01X1414352Y525413D02*
X1414348Y525511D01*
G01X1414356Y525261D02*
X1414352Y525413D01*
G01X1416377Y508867D02*
X1416381Y508825D01*
G01X1416372Y508965D02*
X1416377Y508867D01*
G01X1416368Y509117D02*
X1416372Y508965D01*
G01X1406731Y509645D02*
X1406735Y509615D01*
G01X1406727Y509841D02*
X1406731Y509645D01*
G01X1406724Y510169D02*
X1406727Y509841D01*
G01X1406723Y510571D02*
X1406724Y510169D01*
G01X1408246Y524733D02*
X1408241Y524763D01*
G01X1408250Y524537D02*
X1408246Y524733D01*
G01X1408253Y524209D02*
X1408250Y524537D01*
G01X1408254Y523807D02*
X1408253Y524209D01*
G01X1414605Y509645D02*
X1414609Y509615D01*
G01X1414601Y509841D02*
X1414605Y509645D01*
G01X1414598Y510169D02*
X1414601Y509841D01*
G01X1414597Y510571D02*
X1414598Y510169D01*
G01X1416120Y524733D02*
X1416115Y524763D01*
G01X1416124Y524537D02*
X1416120Y524733D01*
G01X1416127Y524209D02*
X1416124Y524537D01*
G01X1416128Y523807D02*
X1416127Y524209D01*
G01X1410667Y508770D02*
X1410675Y508621D01*
G01X1410660Y509184D02*
X1410667Y508770D01*
G01X1410655Y509804D02*
X1410660Y509184D01*
G01X1410654Y510552D02*
X1410655Y509804D01*
G01X1410671Y509679D02*
X1410675Y509606D01*
G01X1410668Y509887D02*
X1410671Y509679D01*
G01X1410665Y510200D02*
X1410668Y509887D01*
G01X1410664Y510571D02*
X1410665Y510200D01*
G01X1412179Y524699D02*
X1412175Y524772D01*
G01X1412183Y524491D02*
X1412179Y524699D01*
G01X1412185Y524178D02*
X1412183Y524491D01*
G01X1412186Y523807D02*
X1412185Y524178D01*
G01X1412183Y525608D02*
X1412175Y525757D01*
G01X1412190Y525193D02*
X1412183Y525608D01*
G01X1412195Y524573D02*
X1412190Y525193D01*
G01X1412197Y523826D02*
X1412195Y524573D01*
G01X1410655D02*
X1410654Y523826D01*
G01X1410660Y525193D02*
X1410655Y524573D01*
G01X1410667Y525608D02*
X1410660Y525193D01*
G01X1410675Y525757D02*
X1410667Y525608D01*
G01X1412195Y509804D02*
X1412197Y510552D01*
G01X1412190Y509184D02*
X1412195Y509804D01*
G01X1412183Y508770D02*
X1412190Y509184D01*
G01X1412175Y508621D02*
X1412183Y508770D01*
G01X1410665Y524178D02*
X1410664Y523807D01*
G01X1410668Y524491D02*
X1410665Y524178D01*
G01X1410671Y524699D02*
X1410668Y524491D01*
G01X1410675Y524772D02*
X1410671Y524699D01*
G01X1412185Y510200D02*
X1412186Y510571D01*
G01X1412183Y509887D02*
X1412185Y510200D01*
G01X1412179Y509679D02*
X1412183Y509887D01*
G01X1412175Y509606D02*
X1412179Y509679D01*
G01X1414343Y508965D02*
X1414347Y509117D01*
G01X1414338Y508867D02*
X1414343Y508965D01*
G01X1414334Y508825D02*
X1414338Y508867D01*
G01X1416382Y525413D02*
X1416377Y525261D01*
G01X1416386Y525511D02*
X1416382Y525413D01*
G01X1416390Y525553D02*
X1416386Y525511D01*
G01X1416378Y526353D02*
X1416373Y526147D01*
G01X1416384Y526485D02*
X1416378Y526353D01*
G01X1416390Y526538D02*
X1416384Y526485D01*
G01X1414346Y508025D02*
X1414352Y508231D01*
G01X1414340Y507893D02*
X1414346Y508025D01*
G01X1414334Y507840D02*
X1414340Y507893D01*
G01X1416117Y510169D02*
X1416118Y510571D01*
G01X1416114Y509841D02*
X1416117Y510169D01*
G01X1416110Y509645D02*
X1416114Y509841D01*
G01X1416106Y509615D02*
X1416110Y509645D01*
G01X1404300Y508622D02*
X1404301Y508621D01*
G01X1404300Y508624D02*
Y508622D01*
G01X1404299Y508627D02*
X1404300Y508624D01*
G01X1402802Y525756D02*
X1402801Y525757D01*
G01X1402803Y525754D02*
X1402802Y525756D01*
G01X1402803Y525751D02*
Y525754D01*
G01X1412174Y508622D02*
X1412175Y508621D01*
G01X1412174Y508624D02*
Y508622D01*
G01X1412173Y508627D02*
X1412174Y508624D01*
G01X1410676Y525756D02*
X1410675Y525757D01*
G01X1410677Y525754D02*
X1410676Y525756D01*
G01X1410677Y525751D02*
Y525754D01*
G01X1414630Y525738D02*
X1414884Y525368D01*
G01X1414839Y524441D02*
X1414617Y524763D01*
G01X1414839Y524441D02*
X1414848Y524394D01*
G01X1415886Y509937D02*
X1415876Y509984D01*
G01X1410897Y524441D02*
X1410906Y524394D01*
G01X1411953Y509937D02*
X1411944Y509984D01*
G01X1406965Y524441D02*
X1406974Y524394D01*
G01X1408012Y509937D02*
X1408002Y509984D01*
G01X1403023Y524441D02*
X1403032Y524394D01*
G01X1404079Y509937D02*
X1404070Y509984D01*
G01X1410689Y525738D02*
X1410943Y525368D01*
G01X1410897Y524441D02*
X1410676Y524763D01*
G01X1406756Y525738D02*
X1407010Y525368D01*
G01X1406965Y524441D02*
X1406743Y524763D01*
G01X1415886Y509937D02*
X1416107Y509615D01*
G01X1416094Y508640D02*
X1415840Y509010D01*
G01X1402815Y525738D02*
X1403069Y525368D01*
G01X1403023Y524441D02*
X1402802Y524763D01*
G01X1411953Y509937D02*
X1412175Y509615D01*
G01X1412162Y508640D02*
X1411908Y509010D01*
G01X1408012Y509937D02*
X1408233Y509615D01*
G01X1408220Y508640D02*
X1407966Y509010D01*
G01X1404079Y509937D02*
X1404301Y509615D01*
G01X1404288Y508640D02*
X1404034Y509010D01*
G01X1416155Y513379D02*
X1416206Y514365D01*
G01X1416203Y515327D02*
X1416153Y514341D01*
G01X1414521Y519051D02*
X1414572Y520037D01*
G01X1414569Y520999D02*
X1414519Y520013D01*
G01X1412223Y513379D02*
X1412273Y514365D01*
G01X1412271Y515327D02*
X1412220Y514341D01*
G01X1410579Y519051D02*
X1410630Y520037D01*
G01X1410628Y520999D02*
X1410577Y520013D01*
G01X1416241Y519353D02*
X1416377Y525261D01*
G01X1416373Y526147D02*
X1416236Y520239D01*
G01X1414352Y508231D02*
X1414488Y514139D01*
G01X1414483Y515025D02*
X1414347Y509117D01*
G01X1412299Y519353D02*
X1412436Y525261D01*
G01X1412431Y526147D02*
X1412295Y520239D01*
G01X1410420Y508231D02*
X1410556Y514139D01*
G01X1410551Y515025D02*
X1410415Y509117D01*
G01X1408367Y519353D02*
X1408503Y525261D01*
G01X1408498Y526147D02*
X1408362Y520239D01*
G01X1415853Y509984D02*
X1415840Y509010D01*
G01X1414871Y524394D02*
X1414884Y525368D01*
G01X1411921Y509984D02*
X1411908Y509010D01*
G01X1410929Y524394D02*
X1410943Y525368D01*
G01X1407979Y509984D02*
X1407966Y509010D01*
G01X1416390Y526538D02*
Y525553D01*
G01X1416381Y508825D02*
Y507840D01*
G01X1416189Y521698D02*
Y526539D01*
G01Y507839D02*
Y512680D01*
G01X1416115Y524760D02*
Y525751D01*
G01X1416106Y508627D02*
Y509618D01*
G01X1416031Y512760D02*
Y511696D01*
G01Y522681D02*
Y521618D01*
G01X1415756D02*
Y522602D01*
G01Y512760D02*
Y511776D01*
G01X1414968Y521618D02*
Y522602D01*
G01Y511776D02*
Y512760D01*
G01X1414693D02*
Y511696D01*
G01Y522682D02*
Y521618D01*
G01X1414619Y525751D02*
Y524760D01*
G01X1414610Y509618D02*
Y508627D01*
G01X1414535Y521698D02*
Y526539D01*
G01Y507839D02*
Y512680D01*
G01X1414343Y525553D02*
Y526538D01*
G01X1414334Y507840D02*
Y508825D01*
G01X1414260Y526539D02*
Y507839D01*
G01X1414181Y509984D02*
Y503902D01*
G01Y530476D02*
Y524394D01*
G01X1413989Y526539D02*
Y525555D01*
G01X1413984Y526539D02*
Y525555D01*
G01X1413980Y508823D02*
Y507839D01*
G01X1413945Y510516D02*
Y506343D01*
G01Y528035D02*
Y523862D01*
G01X1412843D02*
Y528035D01*
G01Y506343D02*
Y510516D01*
G01X1412808Y508823D02*
Y507839D01*
G01X1412803Y508823D02*
Y507839D01*
G01Y526539D02*
Y525555D01*
G01X1412606Y509984D02*
Y503902D01*
G01Y530476D02*
Y524394D01*
G01X1412528Y507839D02*
Y526539D01*
G01X1412449Y508825D02*
Y507840D01*
G01Y526538D02*
Y525553D01*
G01X1412252Y525555D02*
Y530396D01*
G01Y503982D02*
Y508823D01*
G01X1412173Y524760D02*
Y525751D01*
G01Y508627D02*
Y509618D01*
G01X1412094Y504965D02*
Y503902D01*
G01Y530476D02*
Y529413D01*
G01X1411819Y504886D02*
Y503902D01*
G01Y530476D02*
Y529492D01*
G01X1411031D02*
Y530476D01*
G01Y504886D02*
Y503902D01*
G01X1410756Y504965D02*
Y503902D01*
G01Y530476D02*
Y529413D01*
G01X1410677Y509618D02*
Y508627D01*
G01Y525751D02*
Y524760D01*
G01X1410598Y525555D02*
Y530396D01*
G01Y503982D02*
Y508823D01*
G01X1410402Y525553D02*
Y526538D01*
G01Y507840D02*
Y508825D01*
G01X1410323Y526539D02*
Y507839D01*
G01X1410244Y509984D02*
Y503902D01*
G01Y530476D02*
Y524394D01*
G01X1410047Y508823D02*
Y507839D01*
G01Y526539D02*
Y525555D01*
G01X1410043Y526539D02*
Y525555D01*
G01X1410008Y510516D02*
Y506343D01*
G01Y528035D02*
Y523862D01*
G01X1408906D02*
Y528035D01*
G01Y506343D02*
Y510516D01*
G01X1408871Y526539D02*
Y525555D01*
G01X1408866Y508823D02*
Y507839D01*
G01X1408861Y508823D02*
Y507839D01*
G01X1408669Y509984D02*
Y503902D01*
G01Y530476D02*
Y524394D01*
G01X1408591Y507839D02*
Y526539D01*
G01X1408516Y526538D02*
Y525553D01*
G01X1408507Y508825D02*
Y507840D01*
G01X1408315Y521698D02*
Y526539D01*
G01Y507839D02*
Y512680D01*
G01X1408241Y524760D02*
Y525751D01*
G01X1408232Y508627D02*
Y509618D01*
G01X1408157Y512760D02*
Y511696D01*
G01Y522681D02*
Y521618D01*
G01X1407882Y512760D02*
Y511776D01*
G01Y522602D02*
Y521618D01*
G01X1407094Y512760D02*
Y511776D01*
G01Y522602D02*
Y521618D01*
G01X1406819Y512760D02*
Y511696D01*
G01Y522682D02*
Y521618D01*
G01X1406745Y525751D02*
Y524760D01*
G01X1406735Y509618D02*
Y508627D01*
G01X1406661Y521698D02*
Y526539D01*
G01Y507839D02*
Y512680D01*
G01X1415850Y525368D02*
X1415863Y524394D01*
G01X1414875Y509010D02*
X1414862Y509984D01*
G01X1411908Y525368D02*
X1411921Y524394D01*
G01X1410943Y509010D02*
X1410929Y509984D01*
G01X1407976Y525368D02*
X1407989Y524394D01*
G01X1407001Y509010D02*
X1406988Y509984D01*
G01X1416368Y509117D02*
X1416232Y515025D01*
G01X1416227Y514139D02*
X1416363Y508231D01*
G01X1414497Y520239D02*
X1414361Y526147D01*
G01X1414356Y525261D02*
X1414493Y519353D01*
G01X1412436Y509117D02*
X1412299Y515025D01*
G01X1412295Y514139D02*
X1412431Y508231D01*
G01X1410556Y520239D02*
X1410420Y526147D01*
G01X1410415Y525261D02*
X1410551Y519353D01*
G01X1408494Y509117D02*
X1408358Y515025D01*
G01X1408353Y514139D02*
X1408489Y508231D01*
G01X1406623Y520239D02*
X1406487Y526147D01*
G01X1406482Y525261D02*
X1406619Y519353D01*
G01X1416215Y520013D02*
X1416164Y520999D01*
G01X1416162Y520037D02*
X1416213Y519051D01*
G01X1414562Y514341D02*
X1414512Y515327D01*
G01X1414509Y514365D02*
X1414560Y513379D01*
G01X1412273Y520013D02*
X1412223Y520999D01*
G01X1412220Y520037D02*
X1412271Y519051D01*
G01X1410630Y514341D02*
X1410579Y515327D01*
G01X1410577Y514365D02*
X1410628Y513379D01*
G01X1408341Y520013D02*
X1408290Y520999D01*
G01X1408288Y520037D02*
X1408339Y519051D01*
G01X1406688Y514341D02*
X1406638Y515327D01*
G01X1406635Y514365D02*
X1406686Y513379D01*
G01X1404399Y520013D02*
X1404349Y520999D01*
G01X1404346Y520037D02*
X1404397Y519051D01*
G01X1404604Y547622D02*
X1403374D01*
G01X1414839Y509984D02*
X1414829Y509937D01*
G01X1415886Y524394D02*
X1415895Y524441D01*
G01X1410906Y509984D02*
X1410897Y509937D01*
G01X1411944Y524394D02*
X1411953Y524441D01*
G01X1406965Y509984D02*
X1406955Y509937D01*
G01X1408012Y524394D02*
X1408021Y524441D01*
G01X1403032Y509984D02*
X1403023Y509937D01*
G01X1404070Y524394D02*
X1404079Y524441D01*
G01X1408281Y513379D02*
X1408332Y514365D01*
G01X1408329Y515327D02*
X1408279Y514341D01*
G01X1406647Y519051D02*
X1406698Y520037D01*
G01X1406695Y520999D02*
X1406645Y520013D01*
G01X1404349Y513379D02*
X1404399Y514365D01*
G01X1404397Y515327D02*
X1404346Y514341D01*
G01X1402705Y519051D02*
X1402756Y520037D01*
G01X1402754Y520999D02*
X1402703Y520013D01*
G01X1406478Y508231D02*
X1406614Y514139D01*
G01X1406609Y515025D02*
X1406473Y509117D01*
G01X1404425Y519353D02*
X1404562Y525261D01*
G01X1404557Y526147D02*
X1404421Y520239D01*
G01X1402546Y508231D02*
X1402682Y514139D01*
G01X1402677Y515025D02*
X1402541Y509117D01*
G01X1406997Y524394D02*
X1407010Y525368D01*
G01X1404047Y509984D02*
X1404034Y509010D01*
G01X1403055Y524394D02*
X1403069Y525368D01*
G01X1406469Y525553D02*
Y526538D01*
G01X1406460Y507840D02*
Y508825D01*
G01X1406386Y526539D02*
Y507839D01*
G01X1406307Y509984D02*
Y503902D01*
G01Y530476D02*
Y524394D01*
G01X1406115Y526539D02*
Y525555D01*
G01X1406110Y526539D02*
Y525555D01*
G01X1406106Y508823D02*
Y507839D01*
G01X1406071Y510516D02*
Y506343D01*
G01Y528035D02*
Y523862D01*
G01X1404968D02*
Y528035D01*
G01Y506343D02*
Y510516D01*
G01X1404934Y508823D02*
Y507839D01*
G01X1404929Y508823D02*
Y507839D01*
G01Y526539D02*
Y525555D01*
G01X1404732Y509984D02*
Y503902D01*
G01Y530476D02*
Y524394D01*
G01X1404654Y507839D02*
Y526539D01*
G01X1404604Y553653D02*
Y547622D01*
G01X1404575Y508825D02*
Y507840D01*
G01Y526538D02*
Y525553D01*
G01X1404378Y525555D02*
Y530396D01*
G01Y503982D02*
Y508823D01*
G01X1404299Y524760D02*
Y525751D01*
G01Y508627D02*
Y509618D01*
G01X1404220Y504965D02*
Y503902D01*
G01Y530476D02*
Y529413D01*
G01X1403945Y504886D02*
Y503902D01*
G01Y530476D02*
Y529492D01*
G01X1403374Y547622D02*
Y553653D01*
G01X1403157Y529492D02*
Y530476D01*
G01Y504886D02*
Y503902D01*
G01X1402882Y504965D02*
Y503902D01*
G01Y530476D02*
Y529413D01*
G01X1402803Y509618D02*
Y508627D01*
G01Y525751D02*
Y524760D01*
G01X1402724Y525555D02*
Y530396D01*
G01Y503982D02*
Y508823D01*
G01X1402528Y507840D02*
Y508825D01*
G01Y525553D02*
Y526538D01*
G01X1402449Y526539D02*
Y507839D01*
G01X1402370Y509984D02*
Y503902D01*
G01Y530476D02*
Y524394D01*
G01X1402173Y508823D02*
Y507839D01*
G01Y526539D02*
Y525555D01*
G01X1402169Y526539D02*
Y525555D01*
G01X1402134Y510516D02*
Y506343D01*
G01Y528035D02*
Y523862D01*
G01X1401031D02*
Y528035D01*
G01Y506343D02*
Y510516D01*
G01X1400997Y526539D02*
Y525555D01*
G01X1400992Y508823D02*
Y507839D01*
G01X1400987Y508823D02*
Y507839D01*
G01X1404034Y525368D02*
X1404047Y524394D01*
G01X1403069Y509010D02*
X1403055Y509984D01*
G01X1404562Y509117D02*
X1404425Y515025D01*
G01X1404421Y514139D02*
X1404557Y508231D01*
G01X1402682Y520239D02*
X1402546Y526147D01*
G01X1402541Y525261D02*
X1402677Y519353D01*
G01X1402756Y514341D02*
X1402705Y515327D01*
G01X1402703Y514365D02*
X1402754Y513379D01*
G01X1404732Y530476D02*
X1402370D01*
G01X1408669D02*
X1406307D01*
G01X1412606D02*
X1410244D01*
G01X1404220Y529492D02*
X1402882D01*
G01X1412094D02*
X1410756D01*
G01X1410598Y529394D02*
X1412252D01*
G01X1402724D02*
X1404378D01*
G01X1404732Y529295D02*
X1402370D01*
G01X1408669D02*
X1406307D01*
G01X1412606D02*
X1410244D01*
G01X1404378Y528902D02*
X1402724D01*
G01X1412252D02*
X1410598D01*
G01X1404968Y528035D02*
X1402134D01*
G01X1408906D02*
X1406071D01*
G01X1412843D02*
X1410008D01*
G01X1404378Y527130D02*
X1402724D01*
G01X1412252D02*
X1410598D01*
G01Y526638D02*
X1412252D01*
G01X1402724D02*
X1404378D01*
G01X1404968Y526539D02*
X1402134D01*
G01X1408906D02*
X1406071D01*
G01X1412843D02*
X1410008D01*
G01X1413945Y526382D02*
X1414535D01*
G01X1412252D02*
X1412843D01*
G01X1410008D02*
X1410598D01*
G01X1408315D02*
X1408906D01*
G01X1406071D02*
X1406661D01*
G01X1404378D02*
X1404968D01*
G01X1402134D02*
X1402724D01*
G01X1414361Y526147D02*
X1416373D01*
G01X1410420D02*
X1412431D01*
G01X1406487D02*
X1408498D01*
G01X1402546D02*
X1404557D01*
G01X1404301Y525757D02*
X1402801D01*
G01X1408243D02*
X1406743D01*
G01X1412175D02*
X1410675D01*
G01X1416117D02*
X1414617D01*
G01X1414630Y525738D02*
X1416103D01*
G01X1410689D02*
X1412162D01*
G01X1406756D02*
X1408229D01*
G01X1402815D02*
X1404288D01*
G01X1402724Y525713D02*
X1402134D01*
G01X1404968D02*
X1404378D01*
G01X1406661D02*
X1406071D01*
G01X1408906D02*
X1408315D01*
G01X1410598D02*
X1410008D01*
G01X1412843D02*
X1412252D01*
G01X1414535D02*
X1413945D01*
G01X1410008Y525555D02*
X1412843D01*
G01X1406071D02*
X1408906D01*
G01X1402134D02*
X1404968D01*
G01X1408315Y525457D02*
X1406661D01*
G01X1416189D02*
X1414535D01*
G01X1404034Y525368D02*
X1403069D01*
G01X1407976D02*
X1407010D01*
G01X1411908D02*
X1410943D01*
G01X1415850D02*
X1414884D01*
G01X1413945Y525358D02*
X1414260D01*
G01X1410008D02*
X1410323D01*
G01X1406071D02*
X1406386D01*
G01X1402134D02*
X1402449D01*
G01X1404968D02*
X1404654D01*
G01X1408906D02*
X1408591D01*
G01X1412843D02*
X1412528D01*
G01X1404562Y525261D02*
X1402541D01*
G01X1408503D02*
X1406482D01*
G01X1412436D02*
X1410415D01*
G01X1416377D02*
X1414356D01*
G01X1414535Y524965D02*
X1416189D01*
G01X1406661D02*
X1408315D01*
G01X1404301Y524772D02*
X1402801D01*
G01X1408243D02*
X1406743D01*
G01X1412175D02*
X1410675D01*
G01X1416117D02*
X1414617D01*
G01X1404299Y524763D02*
X1402803D01*
G01X1408241D02*
X1406745D01*
G01X1412173D02*
X1410677D01*
G01X1416115D02*
X1414619D01*
G01X1414839Y524441D02*
X1415895D01*
G01X1410897D02*
X1411953D01*
G01X1406965D02*
X1408021D01*
G01X1403023D02*
X1404079D01*
G01X1404732Y524394D02*
X1402370D01*
G01X1408669D02*
X1406307D01*
G01X1412606D02*
X1410244D01*
G01X1413945Y523862D02*
X1414260D01*
G01X1412528D02*
X1412843D01*
G01X1410008D02*
X1410323D01*
G01X1408591D02*
X1408906D01*
G01X1406071D02*
X1406386D01*
G01X1404654D02*
X1404968D01*
G01X1402134D02*
X1402449D01*
G01X1414595Y523826D02*
X1416139D01*
G01X1410654D02*
X1412197D01*
G01X1406721D02*
X1408265D01*
G01X1402780D02*
X1404323D01*
G01X1414606Y523807D02*
X1416128D01*
G01X1410664D02*
X1412186D01*
G01X1406732D02*
X1408254D01*
G01X1402790D02*
X1404312D01*
G01X1414535Y523193D02*
X1416189D01*
G01X1406661D02*
X1408315D01*
G01Y522701D02*
X1406661D01*
G01X1416189D02*
X1414535D01*
G01X1408157Y522602D02*
X1406819D01*
G01X1416031D02*
X1414693D01*
G01Y521618D02*
X1416031D01*
G01X1406819D02*
X1408157D01*
G01X1404349Y520999D02*
X1402754D01*
G01X1408290D02*
X1406695D01*
G01X1412223D02*
X1410628D01*
G01X1416164D02*
X1414569D01*
G01X1404654Y520890D02*
X1402449D01*
G01X1408591D02*
X1406386D01*
G01X1412528D02*
X1410323D01*
G01X1404421Y520239D02*
X1402682D01*
G01X1408362D02*
X1406623D01*
G01X1412295D02*
X1410556D01*
G01X1416236D02*
X1414497D01*
G01X1414572Y520037D02*
X1416162D01*
G01X1410630D02*
X1412220D01*
G01X1406698D02*
X1408288D01*
G01X1402756D02*
X1404346D01*
G01X1414519Y520013D02*
X1416215D01*
G01X1410577D02*
X1412273D01*
G01X1406645D02*
X1408341D01*
G01X1402703D02*
X1404399D01*
G01X1404406Y519945D02*
X1402696D01*
G01X1408348D02*
X1406638D01*
G01X1412280D02*
X1410570D01*
G01X1416222D02*
X1414512D01*
G01X1414493Y519353D02*
X1416241D01*
G01X1410551D02*
X1412299D01*
G01X1406619D02*
X1408367D01*
G01X1402677D02*
X1404425D01*
G01X1404397Y519051D02*
X1402705D01*
G01X1408339D02*
X1406647D01*
G01X1412271D02*
X1410579D01*
G01X1416213D02*
X1414521D01*
G01X1404406Y518961D02*
X1402696D01*
G01X1408348D02*
X1406638D01*
G01X1412280D02*
X1410570D01*
G01X1416222D02*
X1414512D01*
G01X1410323Y518635D02*
X1412528D01*
G01X1406386D02*
X1408591D01*
G01X1402449D02*
X1404654D01*
G01X1410323Y518468D02*
X1412528D01*
G01X1406386D02*
X1408591D01*
G01X1402449D02*
X1404654D01*
G01Y515910D02*
X1402449D01*
G01X1408591D02*
X1406386D01*
G01X1412528D02*
X1410323D01*
G01X1404654Y515743D02*
X1402449D01*
G01X1408591D02*
X1406386D01*
G01X1412528D02*
X1410323D01*
G01X1414502Y515417D02*
X1416213D01*
G01X1410570D02*
X1412280D01*
G01X1406628D02*
X1408339D01*
G01X1402696D02*
X1404406D01*
G01X1414512Y515327D02*
X1416203D01*
G01X1410579D02*
X1412271D01*
G01X1406638D02*
X1408329D01*
G01X1402705D02*
X1404397D01*
G01X1404425Y515025D02*
X1402677D01*
G01X1408358D02*
X1406609D01*
G01X1412299D02*
X1410551D01*
G01X1416232D02*
X1414483D01*
G01X1414502Y514433D02*
X1416213D01*
G01X1410570D02*
X1412280D01*
G01X1406628D02*
X1408339D01*
G01X1402696D02*
X1404406D01*
G01X1404399Y514365D02*
X1402703D01*
G01X1408332D02*
X1406635D01*
G01X1412273D02*
X1410577D01*
G01X1416206D02*
X1414509D01*
G01X1404346Y514341D02*
X1402756D01*
G01X1408279D02*
X1406688D01*
G01X1412220D02*
X1410630D01*
G01X1416153D02*
X1414562D01*
G01X1414488Y514139D02*
X1416227D01*
G01X1410556D02*
X1412295D01*
G01X1406614D02*
X1408353D01*
G01X1402682D02*
X1404421D01*
G01X1410323Y513488D02*
X1412528D01*
G01X1406386D02*
X1408591D01*
G01X1402449D02*
X1404654D01*
G01X1414560Y513379D02*
X1416155D01*
G01X1410628D02*
X1412223D01*
G01X1406686D02*
X1408281D01*
G01X1402754D02*
X1404349D01*
G01X1408157Y512760D02*
X1406819D01*
G01X1416031D02*
X1414693D01*
G01X1408157Y511776D02*
X1406819D01*
G01X1416031D02*
X1414693D01*
G01X1414535Y511677D02*
X1416189D01*
G01X1406661D02*
X1408315D01*
G01Y511185D02*
X1406661D01*
G01X1416189D02*
X1414535D01*
G01X1414621Y508640D02*
X1414875Y509010D01*
G01X1414608Y509615D02*
X1414829Y509937D01*
G01X1410689Y508640D02*
X1410943Y509010D01*
G01X1410676Y509615D02*
X1410897Y509937D01*
G01X1406747Y508640D02*
X1407001Y509010D01*
G01X1406734Y509615D02*
X1406955Y509937D01*
G01X1416117Y524763D02*
X1415895Y524441D01*
G01X1416103Y525738D02*
X1415850Y525368D01*
G01X1404312Y510571D02*
X1402790D01*
G01X1408244D02*
X1406723D01*
G01X1412186D02*
X1410664D01*
G01X1416118D02*
X1414597D01*
G01X1404323Y510552D02*
X1402780D01*
G01X1408255D02*
X1406712D01*
G01X1412197D02*
X1410654D01*
G01X1416129D02*
X1414586D01*
G01X1402449Y510516D02*
X1402134D01*
G01X1404968D02*
X1404654D01*
G01X1406386D02*
X1406071D01*
G01X1408906D02*
X1408591D01*
G01X1410323D02*
X1410008D01*
G01X1412843D02*
X1412528D01*
G01X1414260D02*
X1413945D01*
G01X1404732Y509984D02*
X1402370D01*
G01X1408669D02*
X1406307D01*
G01X1412606D02*
X1410244D01*
G01X1404079Y509937D02*
X1403023D01*
G01X1408012D02*
X1406955D01*
G01X1411953D02*
X1410897D01*
G01X1415886D02*
X1414829D01*
G01X1414609Y509615D02*
X1416106D01*
G01X1410677D02*
X1412173D01*
G01X1406735D02*
X1408232D01*
G01X1402803D02*
X1404299D01*
G01X1414608Y509606D02*
X1416107D01*
G01X1410675D02*
X1412175D01*
G01X1406734D02*
X1408233D01*
G01X1402801D02*
X1404301D01*
G01X1408315Y509413D02*
X1406661D01*
G01X1416189D02*
X1414535D01*
G01X1414347Y509117D02*
X1416368D01*
G01X1410415D02*
X1412436D01*
G01X1406473D02*
X1408494D01*
G01X1402541D02*
X1404562D01*
G01X1412528Y509020D02*
X1412843D01*
G01X1408591D02*
X1408906D01*
G01X1404654D02*
X1404968D01*
G01X1402449D02*
X1402134D01*
G01X1406386D02*
X1406071D01*
G01X1410323D02*
X1410008D01*
G01X1414260D02*
X1413945D01*
G01X1414875Y509010D02*
X1415840D01*
G01X1410943D02*
X1411908D01*
G01X1407001D02*
X1407966D01*
G01X1403069D02*
X1404034D01*
G01X1414535Y508921D02*
X1416189D01*
G01X1406661D02*
X1408315D01*
G01X1410008Y508823D02*
X1412843D01*
G01X1406071D02*
X1408906D01*
G01X1402134D02*
X1404968D01*
G01X1413945Y508665D02*
X1414535D01*
G01X1412252D02*
X1412843D01*
G01X1410008D02*
X1410598D01*
G01X1408315D02*
X1408906D01*
G01X1406071D02*
X1406661D01*
G01X1404378D02*
X1404968D01*
G01X1402134D02*
X1402724D01*
G01X1404288Y508640D02*
X1402815D01*
G01X1408220D02*
X1406747D01*
G01X1412162D02*
X1410689D01*
G01X1416094D02*
X1414621D01*
G01X1414608Y508621D02*
X1416107D01*
G01X1410675D02*
X1412175D01*
G01X1406734D02*
X1408233D01*
G01X1402801D02*
X1404301D01*
G01X1404557Y508231D02*
X1402546D01*
G01X1408489D02*
X1406478D01*
G01X1412431D02*
X1410420D01*
G01X1416363D02*
X1414352D01*
G01X1402724Y507996D02*
X1402134D01*
G01X1404968D02*
X1404378D01*
G01X1406661D02*
X1406071D01*
G01X1408906D02*
X1408315D01*
G01X1410598D02*
X1410008D01*
G01X1412843D02*
X1412252D01*
G01X1414535D02*
X1413945D01*
G01X1404968Y507839D02*
X1402134D01*
G01X1408906D02*
X1406071D01*
G01X1412843D02*
X1410008D01*
G01X1404378Y507740D02*
X1402724D01*
G01X1412252D02*
X1410598D01*
G01Y507248D02*
X1412252D01*
G01X1402724D02*
X1404378D01*
G01X1410008Y506343D02*
X1412843D01*
G01X1406071D02*
X1408906D01*
G01X1402134D02*
X1404968D01*
G01X1410598Y505476D02*
X1412252D01*
G01X1402724D02*
X1404378D01*
G01X1404732Y505083D02*
X1402370D01*
G01X1408669D02*
X1406307D01*
G01X1412606D02*
X1410244D01*
G01X1404378Y504984D02*
X1402724D01*
G01X1412252D02*
X1410598D01*
G01X1404220Y504886D02*
X1402882D01*
G01X1412094D02*
X1410756D01*
G01X1410244Y503902D02*
X1412606D01*
G01X1406307D02*
X1408669D01*
G01X1402370D02*
X1404732D01*
G01X1402815Y508640D02*
X1403069Y509010D01*
G01X1402802Y509615D02*
X1403023Y509937D01*
G01X1412175Y524763D02*
X1411953Y524441D01*
G01X1412162Y525738D02*
X1411908Y525368D01*
G01X1408242Y524763D02*
X1408021Y524441D01*
G01X1408229Y525738D02*
X1407976Y525368D01*
G01X1404301Y524763D02*
X1404079Y524441D01*
G01X1404288Y525738D02*
X1404034Y525368D01*
G01X1404112Y554910D02*
X1404604Y553653D01*
G01X1403374D02*
X1403128Y554156D01*
G01X1403620Y555412D02*
X1404112Y554910D01*
G01X1403128Y554156D02*
X1402882Y554407D01*
G01D02*
X1402390Y554658D01*
G01X1402882Y555664D02*
X1403620Y555412D01*
G01X1415362Y582524D02*
Y577012D01*
G01X1412213Y582524D02*
Y577012D01*
G01X1401898Y555664D02*
X1402882D01*
G01X1402390Y554658D02*
X1401652D01*
G01D02*
X1401159Y554407D01*
G01Y555412D02*
X1401898Y555664D01*
G01X1418551Y588624D02*
Y588627D01*
G01X1418550Y588622D02*
X1418551Y588624D01*
G01X1418549Y588621D02*
X1418550Y588622D01*
G01X1426425Y588624D02*
Y588627D01*
G01X1426424Y588622D02*
X1426425Y588624D01*
G01X1426423Y588621D02*
X1426424Y588622D01*
G01X1418550Y589610D02*
X1418551Y589615D01*
G01X1418550Y589607D02*
Y589610D01*
G01X1418549Y589606D02*
X1418550Y589607D01*
G01X1426424Y589610D02*
X1426425Y589615D01*
G01X1426424Y589607D02*
Y589610D01*
G01X1426423Y589606D02*
X1426424Y589607D01*
G01X1418285Y588965D02*
X1418289Y589117D01*
G01X1418280Y588867D02*
X1418285Y588965D01*
G01X1418276Y588825D02*
X1418280Y588867D01*
G01X1418288Y588025D02*
X1418294Y588231D01*
G01X1418282Y587893D02*
X1418288Y588025D01*
G01X1418276Y587840D02*
X1418282Y587893D01*
G01X1423991Y590169D02*
X1423992Y590571D01*
G01X1423988Y589841D02*
X1423991Y590169D01*
G01X1423984Y589645D02*
X1423988Y589841D01*
G01X1423980Y589615D02*
X1423984Y589645D01*
G01X1420317Y587893D02*
X1420323Y587840D01*
G01X1420311Y588025D02*
X1420317Y587893D01*
G01X1420305Y588231D02*
X1420311Y588025D01*
G01X1424249Y587893D02*
X1424255Y587840D01*
G01X1424243Y588025D02*
X1424249Y587893D01*
G01X1424237Y588231D02*
X1424243Y588025D01*
G01X1420318Y588867D02*
X1420323Y588825D01*
G01X1420314Y588965D02*
X1420318Y588867D01*
G01X1420310Y589117D02*
X1420314Y588965D01*
G01X1424251Y588867D02*
X1424255Y588825D01*
G01X1424246Y588965D02*
X1424251Y588867D01*
G01X1424242Y589117D02*
X1424246Y588965D01*
G01X1422479Y589645D02*
X1422483Y589615D01*
G01X1422475Y589841D02*
X1422479Y589645D01*
G01X1422472Y590169D02*
X1422475Y589841D01*
G01X1422471Y590571D02*
X1422472Y590169D01*
G01X1418541Y588770D02*
X1418549Y588621D01*
G01X1418534Y589184D02*
X1418541Y588770D01*
G01X1418529Y589804D02*
X1418534Y589184D01*
G01X1418528Y590552D02*
X1418529Y589804D01*
G01X1418545Y589679D02*
X1418549Y589606D01*
G01X1418542Y589887D02*
X1418545Y589679D01*
G01X1418539Y590200D02*
X1418542Y589887D01*
G01X1418538Y590571D02*
X1418539Y590200D01*
G01X1426415Y588770D02*
X1426423Y588621D01*
G01X1426408Y589184D02*
X1426415Y588770D01*
G01X1426403Y589804D02*
X1426408Y589184D01*
G01X1426402Y590552D02*
X1426403Y589804D01*
G01X1426419Y589679D02*
X1426423Y589606D01*
G01X1426416Y589887D02*
X1426419Y589679D01*
G01X1426413Y590200D02*
X1426416Y589887D01*
G01X1426413Y590571D02*
Y590200D01*
G01X1420069Y589804D02*
X1420071Y590552D01*
G01X1420064Y589184D02*
X1420069Y589804D01*
G01X1420057Y588770D02*
X1420064Y589184D01*
G01X1420049Y588621D02*
X1420057Y588770D01*
G01X1427943Y589804D02*
X1427945Y590552D01*
G01X1427938Y589184D02*
X1427943Y589804D01*
G01X1427931Y588770D02*
X1427938Y589184D01*
G01X1427923Y588621D02*
X1427931Y588770D01*
G01X1420059Y590200D02*
X1420060Y590571D01*
G01X1420057Y589887D02*
X1420059Y590200D01*
G01X1420053Y589679D02*
X1420057Y589887D01*
G01X1420049Y589606D02*
X1420053Y589679D01*
G01X1427933Y590200D02*
X1427934Y590571D01*
G01X1427931Y589887D02*
X1427933Y590200D01*
G01X1427927Y589679D02*
X1427931Y589887D01*
G01X1427923Y589606D02*
X1427927Y589679D01*
G01X1422217Y588965D02*
X1422221Y589117D01*
G01X1422212Y588867D02*
X1422217Y588965D01*
G01X1422208Y588825D02*
X1422212Y588867D01*
G01X1426159Y588965D02*
X1426163Y589117D01*
G01X1426154Y588867D02*
X1426159Y588965D01*
G01X1426150Y588825D02*
X1426154Y588867D01*
G01X1422220Y588025D02*
X1422226Y588231D01*
G01X1422214Y587893D02*
X1422220Y588025D01*
G01X1422208Y587840D02*
X1422214Y587893D01*
G01X1426162Y588025D02*
X1426168Y588231D01*
G01X1426156Y587893D02*
X1426162Y588025D01*
G01X1426150Y587840D02*
X1426156Y587893D01*
G01X1426120Y588823D02*
X1426105D01*
G01X1426135Y588824D02*
X1426120Y588823D01*
G01X1426150Y588825D02*
X1426135Y588824D01*
G01X1422178Y588823D02*
X1422163D01*
G01X1422193Y588824D02*
X1422178Y588823D01*
G01X1422208Y588825D02*
X1422193Y588824D01*
G01X1418246Y588823D02*
X1418231D01*
G01X1418261Y588824D02*
X1418246Y588823D01*
G01X1418276Y588825D02*
X1418261Y588824D01*
G01X1426120Y587839D02*
X1426105D01*
G01X1426135D02*
X1426120D01*
G01X1426150Y587840D02*
X1426135Y587839D01*
G01X1422178D02*
X1422163D01*
G01X1422193D02*
X1422178D01*
G01X1422208Y587840D02*
X1422193Y587839D01*
G01X1418246D02*
X1418231D01*
G01X1418261D02*
X1418246D01*
G01X1418276Y587840D02*
X1418261Y587839D01*
G01X1420048Y589607D02*
X1420049Y589606D01*
G01X1420048Y589610D02*
Y589607D01*
G01X1420047Y589615D02*
X1420048Y589610D01*
G01X1427922Y589607D02*
X1427923Y589606D01*
G01X1427922Y589610D02*
Y589607D01*
G01X1427921Y589615D02*
X1427922Y589610D01*
G01X1428191Y587893D02*
X1428197Y587840D01*
G01X1428185Y588025D02*
X1428191Y587893D01*
G01X1428179Y588231D02*
X1428185Y588025D01*
G01X1428192Y588867D02*
X1428197Y588825D01*
G01X1428188Y588965D02*
X1428192Y588867D01*
G01X1428184Y589117D02*
X1428188Y588965D01*
G01X1416411Y587839D02*
X1416396D01*
G01X1416426D02*
X1416411D01*
G01X1420338D02*
X1420323Y587840D01*
G01X1420353Y587839D02*
X1420338D01*
G01X1420368D02*
X1420353D01*
G01X1424270D02*
X1424255Y587840D01*
G01X1424285Y587839D02*
X1424270D01*
G01X1424300D02*
X1424285D01*
G01X1428212D02*
X1428197Y587840D01*
G01X1428227Y587839D02*
X1428212D01*
G01X1428242D02*
X1428227D01*
G01X1416411Y588823D02*
X1416396Y588824D01*
G01X1416426Y588823D02*
X1416411D01*
G01X1420338Y588824D02*
X1420323Y588825D01*
G01X1420353Y588823D02*
X1420338Y588824D01*
G01X1420368Y588823D02*
X1420353D01*
G01X1424270Y588824D02*
X1424255Y588825D01*
G01X1424285Y588823D02*
X1424270Y588824D01*
G01X1424300Y588823D02*
X1424285D01*
G01X1428227D02*
X1428242D01*
G01X1428212Y588824D02*
X1428227Y588823D01*
G01X1428197Y588825D02*
X1428212Y588824D01*
G01X1420048Y588622D02*
X1420049Y588621D01*
G01X1420048Y588624D02*
Y588622D01*
G01X1420047Y588627D02*
X1420048Y588624D01*
G01X1427922Y588622D02*
X1427923Y588621D01*
G01X1427922Y588624D02*
Y588622D01*
G01X1427921Y588627D02*
X1427922Y588624D01*
G01X1437390Y597189D02*
G03I-3130J0D01*
G01X1438492D02*
G03I-4232J0D01*
G01X1438886D02*
G03I-4626J0D01*
G01X1462092Y598076D02*
X1462353Y597676D01*
G01X1432617Y593646D02*
X1434575Y590693D01*
G01X1427702Y589937D02*
X1427923Y589615D01*
G01X1462092Y595412D02*
X1459614Y596744D01*
G01X1460527D02*
X1462353Y595811D01*
G01X1427910Y588640D02*
X1427656Y589010D01*
G01X1423760Y589937D02*
X1423981Y589615D01*
G01X1423968Y588640D02*
X1423714Y589010D01*
G01X1419828Y589937D02*
X1420049Y589615D01*
G01X1420036Y588640D02*
X1419782Y589010D01*
G01X1467700Y593547D02*
Y594213D01*
G01X1466656D02*
Y593547D01*
G01X1466004D02*
Y594213D01*
G01X1464961Y599807D02*
Y593547D01*
G01X1464179D02*
Y598742D01*
G01X1463396Y597809D02*
Y598875D01*
G01X1458571Y599807D02*
Y593547D01*
G01X1457788Y597277D02*
Y599807D01*
G01Y593547D02*
Y596477D01*
G01X1427702Y589937D02*
X1427692Y589984D01*
G01X1423760Y589937D02*
X1423750Y589984D01*
G01X1419828Y589937D02*
X1419818Y589984D01*
G01X1420169Y600239D02*
X1418430D01*
G01X1424110D02*
X1422371D01*
G01X1428043D02*
X1426304D01*
G01X1426378Y600037D02*
X1427968D01*
G01X1422446D02*
X1424036D01*
G01X1418504D02*
X1420094D01*
G01X1426325Y600013D02*
X1428021D01*
G01X1422393D02*
X1424089D01*
G01X1418451D02*
X1420147D01*
G01X1420154Y599945D02*
X1418444D01*
G01X1424096D02*
X1422386D01*
G01X1428028D02*
X1426318D01*
G01X1464179Y599807D02*
X1464961D01*
G01X1457788D02*
X1458571D01*
G01X1453354D02*
X1454137D01*
G01X1426299Y599353D02*
X1428047D01*
G01X1422367D02*
X1424115D01*
G01X1418425D02*
X1420173D01*
G01X1420145Y599051D02*
X1418453D01*
G01X1424087D02*
X1422395D01*
G01X1428019D02*
X1426327D01*
G01X1420154Y598961D02*
X1418444D01*
G01X1424096D02*
X1422386D01*
G01X1428028D02*
X1426318D01*
G01X1426071Y598635D02*
X1428276D01*
G01X1422134D02*
X1424339D01*
G01X1418197D02*
X1420402D01*
G01X1414260D02*
X1416465D01*
G01X1426071Y598468D02*
X1428276D01*
G01X1422134D02*
X1424339D01*
G01X1418197D02*
X1420402D01*
G01X1414260D02*
X1416465D01*
G01X1454137Y597277D02*
X1457788D01*
G01Y596477D02*
X1454137D01*
G01X1416465Y595910D02*
X1414260D01*
G01X1420402D02*
X1418197D01*
G01X1424339D02*
X1422134D01*
G01X1428276D02*
X1426071D01*
G01X1416465Y595743D02*
X1414260D01*
G01X1420402D02*
X1418197D01*
G01X1424339D02*
X1422134D01*
G01X1428276D02*
X1426071D01*
G01X1426318Y595417D02*
X1428028D01*
G01X1422376D02*
X1424087D01*
G01X1418444D02*
X1420154D01*
G01X1426327Y595327D02*
X1428019D01*
G01X1422386D02*
X1424077D01*
G01X1418453D02*
X1420145D01*
G01X1420173Y595025D02*
X1418425D01*
G01X1424106D02*
X1422357D01*
G01X1428047D02*
X1426299D01*
G01X1426318Y594433D02*
X1428028D01*
G01X1422376D02*
X1424087D01*
G01X1418444D02*
X1420154D01*
G01X1420147Y594365D02*
X1418451D01*
G01X1424080D02*
X1422383D01*
G01X1428021D02*
X1426325D01*
G01X1420094Y594341D02*
X1418504D01*
G01X1424027D02*
X1422436D01*
G01X1427968D02*
X1426378D01*
G01X1466004Y594213D02*
X1466656D01*
G01X1426304Y594139D02*
X1428043D01*
G01X1422362D02*
X1424101D01*
G01X1418430D02*
X1420169D01*
G01X1454137Y593547D02*
X1453354D01*
G01X1458571D02*
X1457788D01*
G01X1464961D02*
X1464179D01*
G01X1466656D02*
X1466004D01*
G01X1472395D02*
X1467700D01*
G01X1426071Y593488D02*
X1428276D01*
G01X1422134D02*
X1424339D01*
G01X1418197D02*
X1420402D01*
G01X1414260D02*
X1416465D01*
G01X1426376Y593379D02*
X1427971D01*
G01X1422434D02*
X1424029D01*
G01X1418502D02*
X1420097D01*
G01X1423906Y592760D02*
X1422567D01*
G01X1423906Y591776D02*
X1422567D01*
G01X1422409Y591677D02*
X1424063D01*
G01Y591185D02*
X1422409D01*
G01X1420060Y590571D02*
X1418538D01*
G01X1423992D02*
X1422471D01*
G01X1427934D02*
X1426413D01*
G01X1420071Y590552D02*
X1418528D01*
G01X1424003D02*
X1422460D01*
G01X1427945D02*
X1426402D01*
G01X1416780Y590516D02*
X1416465D01*
G01X1418197D02*
X1417882D01*
G01X1422134D02*
X1421819D01*
G01X1420717D02*
X1420402D01*
G01X1424654D02*
X1424339D01*
G01X1426071D02*
X1425756D01*
G01X1428591D02*
X1428276D01*
G01X1416543Y589984D02*
X1414181D01*
G01X1420480D02*
X1418118D01*
G01X1424417D02*
X1422055D01*
G01X1428354D02*
X1425992D01*
G01X1419828Y589937D02*
X1418771D01*
G01X1423760D02*
X1422703D01*
G01X1427702D02*
X1426645D01*
G01X1426425Y589615D02*
X1427921D01*
G01X1422483D02*
X1423980D01*
G01X1418551D02*
X1420047D01*
G01X1438256Y589610D02*
X1433531D01*
G01X1426423Y589606D02*
X1427923D01*
G01X1422482D02*
X1423981D01*
G01X1418549D02*
X1420049D01*
G01X1424063Y589413D02*
X1422409D01*
G01X1426163Y589117D02*
X1428184D01*
G01X1422221D02*
X1424242D01*
G01X1418289D02*
X1420310D01*
G01X1428276Y589020D02*
X1428591D01*
G01X1424339D02*
X1424654D01*
G01X1420402D02*
X1420717D01*
G01X1416465D02*
X1416780D01*
G01X1418197D02*
X1417882D01*
G01X1422134D02*
X1421819D01*
G01X1426071D02*
X1425756D01*
G01X1426691Y589010D02*
X1427656D01*
G01X1422749D02*
X1423714D01*
G01X1418817D02*
X1419782D01*
G01X1422409Y588921D02*
X1424063D01*
G01X1425756Y588823D02*
X1428591D01*
G01X1421819D02*
X1424654D01*
G01X1417882D02*
X1420717D01*
G01X1413945D02*
X1416780D01*
G01X1428000Y588665D02*
X1428591D01*
G01X1425756D02*
X1426346D01*
G01X1424063D02*
X1424654D01*
G01X1421819D02*
X1422409D01*
G01X1420126D02*
X1420717D01*
G01X1417882D02*
X1418472D01*
G01X1416189D02*
X1416780D01*
G01X1420036Y588640D02*
X1418563D01*
G01X1423968D02*
X1422495D01*
G01X1427910D02*
X1426437D01*
G01X1431110Y588626D02*
X1435047D01*
G01X1426423Y588621D02*
X1427923D01*
G01X1422482D02*
X1423981D01*
G01X1418549D02*
X1420049D01*
G01X1420305Y588231D02*
X1418294D01*
G01X1424237D02*
X1422226D01*
G01X1428179D02*
X1426168D01*
G01X1416780Y587996D02*
X1416189D01*
G01X1418472D02*
X1417882D01*
G01X1420717D02*
X1420126D01*
G01X1422409D02*
X1421819D01*
G01X1424654D02*
X1424063D01*
G01X1426346D02*
X1425756D01*
G01X1428591D02*
X1428000D01*
G01X1416780Y587839D02*
X1413945D01*
G01X1420717D02*
X1417882D01*
G01X1424654D02*
X1421819D01*
G01X1428591D02*
X1425756D01*
G01X1420126Y587740D02*
X1418472D01*
G01X1428000D02*
X1426346D01*
G01Y587248D02*
X1428000D01*
G01X1418472D02*
X1420126D01*
G01X1425756Y586343D02*
X1428591D01*
G01X1421819D02*
X1424654D01*
G01X1417882D02*
X1420717D01*
G01X1413945D02*
X1416780D01*
G01X1498433Y586264D02*
X1446858D01*
G01X1426346Y585476D02*
X1428000D01*
G01X1418472D02*
X1420126D01*
G01X1433531Y585083D02*
X1438256D01*
G01X1425992D02*
X1428354D01*
G01X1416543D02*
X1414181D01*
G01X1420480D02*
X1418118D01*
G01X1424417D02*
X1422055D01*
G01X1420126Y584984D02*
X1418472D01*
G01X1428000D02*
X1426346D01*
G01X1419968Y584886D02*
X1418630D01*
G01X1427843D02*
X1426504D01*
G01X1435047D02*
X1431110D01*
G01X1454137Y596477D02*
Y593547D01*
G01Y599807D02*
Y597277D01*
G01X1453354Y593547D02*
Y599807D01*
G01X1438256Y598583D02*
Y609295D01*
G01Y585083D02*
Y595795D01*
G01X1435047Y588626D02*
Y584886D01*
G01X1434575Y590693D02*
Y603685D01*
G01X1433531Y593020D02*
Y585083D01*
G01X1431169Y600732D02*
Y593646D01*
G01X1431110Y584886D02*
Y588626D01*
G01X1428184Y589117D02*
X1428047Y595025D01*
G01X1428043Y594139D02*
X1428179Y588231D01*
G01X1428021Y600013D02*
X1427971Y600999D01*
G01X1427968Y600037D02*
X1428019Y599051D01*
G01X1426378Y594341D02*
X1426327Y595327D01*
G01X1426325Y594365D02*
X1426376Y593379D01*
G01X1424089Y600013D02*
X1424038Y600999D01*
G01X1424036Y600037D02*
X1424087Y599051D01*
G01X1425992Y583902D02*
X1428354D01*
G01X1422055D02*
X1424417D01*
G01X1418118D02*
X1420480D01*
G01X1414181D02*
X1416543D01*
G01X1427971Y593379D02*
X1428021Y594365D01*
G01X1428019Y595327D02*
X1427968Y594341D01*
G01X1426327Y599051D02*
X1426378Y600037D01*
G01X1426376Y600999D02*
X1426325Y600013D01*
G01X1424029Y593379D02*
X1424080Y594365D01*
G01X1424077Y595327D02*
X1424027Y594341D01*
G01X1422395Y599051D02*
X1422446Y600037D01*
G01X1422443Y600999D02*
X1422393Y600013D01*
G01X1420097Y593379D02*
X1420147Y594365D01*
G01X1420145Y595327D02*
X1420094Y594341D01*
G01X1418453Y599051D02*
X1418504Y600037D01*
G01X1418502Y600999D02*
X1418451Y600013D01*
G01X1428047Y599353D02*
X1428184Y605261D01*
G01X1428179Y606147D02*
X1428043Y600239D01*
G01X1426168Y588231D02*
X1426304Y594139D01*
G01X1426299Y595025D02*
X1426163Y589117D01*
G01X1424115Y599353D02*
X1424251Y605261D01*
G01X1424247Y606147D02*
X1424110Y600239D01*
G01X1422226Y588231D02*
X1422362Y594139D01*
G01X1422357Y595025D02*
X1422221Y589117D01*
G01X1420173Y599353D02*
X1420310Y605261D01*
G01X1420305Y606147D02*
X1420169Y600239D01*
G01X1418294Y588231D02*
X1418430Y594139D01*
G01X1418425Y595025D02*
X1418289Y589117D01*
G01X1427669Y589984D02*
X1427656Y589010D01*
G01X1423727Y589984D02*
X1423714Y589010D01*
G01X1419795Y589984D02*
X1419782Y589010D01*
G01X1428591Y586343D02*
Y590516D01*
G01X1428556Y588823D02*
Y587839D01*
G01X1428551Y588823D02*
Y587839D01*
G01X1428354Y589984D02*
Y583902D01*
G01X1428276Y587839D02*
Y606539D01*
G01X1428197Y588825D02*
Y587840D01*
G01X1428000Y583982D02*
Y588823D01*
G01X1427921Y588627D02*
Y589618D01*
G01X1427843Y584965D02*
Y583902D01*
G01X1427567D02*
Y584886D01*
G01X1426780Y583902D02*
Y584886D01*
G01X1426504Y584965D02*
Y583902D01*
G01X1426425Y589618D02*
Y588627D01*
G01X1426346Y583982D02*
Y588823D01*
G01X1426150Y587840D02*
Y588825D01*
G01X1426071Y606539D02*
Y587839D01*
G01X1425992Y589984D02*
Y583902D01*
G01X1425795Y588823D02*
Y587839D01*
G01X1425756Y590516D02*
Y586343D01*
G01X1424654D02*
Y590516D01*
G01X1424614Y588823D02*
Y587839D01*
G01X1424610Y588823D02*
Y587839D01*
G01X1424417Y589984D02*
Y583902D01*
G01X1424339Y587839D02*
Y606539D01*
G01X1424255Y588825D02*
Y587840D01*
G01X1424063Y587839D02*
Y592680D01*
G01X1423980Y588627D02*
Y589618D01*
G01X1423906Y592760D02*
Y591696D01*
G01X1423630Y592760D02*
Y591776D01*
G01X1422843D02*
Y592760D01*
G01X1422567D02*
Y591696D01*
G01X1422484Y589618D02*
Y588627D01*
G01X1422409Y587839D02*
Y592680D01*
G01X1422208Y587840D02*
Y588825D01*
G01X1422134Y606539D02*
Y587839D01*
G01X1422055Y589984D02*
Y583902D01*
G01X1421854Y588823D02*
Y587839D01*
G01X1421819Y590516D02*
Y586343D01*
G01X1420717D02*
Y590516D01*
G01X1420682Y588823D02*
Y587839D01*
G01X1420677Y588823D02*
Y587839D01*
G01X1420480Y589984D02*
Y583902D01*
G01X1420402Y587839D02*
Y606539D01*
G01X1420323Y588825D02*
Y587840D01*
G01X1420126Y583982D02*
Y588823D01*
G01X1420047Y588627D02*
Y589618D01*
G01X1419968Y584965D02*
Y583902D01*
G01X1419693Y584886D02*
Y583902D01*
G01X1418906Y584886D02*
Y583902D01*
G01X1418630Y584965D02*
Y583902D01*
G01X1418551Y589618D02*
Y588627D01*
G01X1418472Y583982D02*
Y588823D01*
G01X1418276Y587840D02*
Y588825D01*
G01X1418197Y606539D02*
Y587839D01*
G01X1418118Y589984D02*
Y583902D01*
G01X1417921Y588823D02*
Y587839D01*
G01X1417882Y590516D02*
Y586343D01*
G01X1416780D02*
Y590516D01*
G01X1416740Y588823D02*
Y587839D01*
G01X1416735Y588823D02*
Y587839D01*
G01X1416543Y589984D02*
Y583902D01*
G01X1416465Y587839D02*
Y606539D01*
G01X1426691Y589010D02*
X1426677Y589984D01*
G01X1422749Y589010D02*
X1422736Y589984D01*
G01X1418817Y589010D02*
X1418803Y589984D01*
G01X1426304Y600239D02*
X1426168Y606147D01*
G01X1426163Y605261D02*
X1426299Y599353D01*
G01X1424242Y589117D02*
X1424106Y595025D01*
G01X1424101Y594139D02*
X1424237Y588231D01*
G01X1422371Y600239D02*
X1422235Y606147D01*
G01X1422230Y605261D02*
X1422367Y599353D01*
G01X1420310Y589117D02*
X1420173Y595025D01*
G01X1420169Y594139D02*
X1420305Y588231D01*
G01X1418430Y600239D02*
X1418294Y606147D01*
G01X1418289Y605261D02*
X1418425Y599353D01*
G01X1422436Y594341D02*
X1422386Y595327D01*
G01X1422383Y594365D02*
X1422434Y593379D01*
G01X1420147Y600013D02*
X1420097Y600999D01*
G01X1420094Y600037D02*
X1420145Y599051D01*
G01X1418504Y594341D02*
X1418453Y595327D01*
G01X1418451Y594365D02*
X1418502Y593379D01*
G01X1426655Y589984D02*
X1426645Y589937D01*
G01X1422713Y589984D02*
X1422703Y589937D01*
G01X1418781Y589984D02*
X1418771Y589937D01*
G01X1462353Y595811D02*
X1462092Y595412D01*
G01X1464179Y598742D02*
X1463396Y597809D01*
G01Y598875D02*
X1464179Y599807D01*
G01X1467700Y594213D02*
X1471351Y597543D01*
G01X1426437Y588640D02*
X1426691Y589010D01*
G01X1426424Y589615D02*
X1426645Y589937D01*
G01X1422495Y588640D02*
X1422749Y589010D01*
G01X1422482Y589615D02*
X1422703Y589937D01*
G01X1418563Y588640D02*
X1418817Y589010D01*
G01X1418550Y589615D02*
X1418771Y589937D01*
G01X1434575Y603685D02*
X1432617Y600732D01*
G01X1462353Y597676D02*
X1460527Y596744D01*
G01X1459614D02*
X1462092Y598076D01*
G01X1580306Y615988D02*
X1446858D01*
G01X1388552Y605754D02*
X1388551Y605751D01*
G01X1388552Y605756D02*
Y605754D01*
G01X1388553Y605757D02*
X1388552Y605756D01*
G01X1396426Y605754D02*
X1396425Y605751D01*
G01X1396426Y605756D02*
Y605754D01*
G01X1396427Y605757D02*
X1396426Y605756D01*
G01X1394929Y588624D02*
Y588627D01*
G01X1394928Y588622D02*
X1394929Y588624D01*
G01X1394927Y588621D02*
X1394928Y588622D01*
G01X1388552Y604768D02*
X1388551Y604763D01*
G01X1388552Y604771D02*
Y604768D01*
G01X1388553Y604772D02*
X1388552Y604771D01*
G01X1396426Y604768D02*
X1396425Y604763D01*
G01X1396426Y604771D02*
Y604768D01*
G01X1396427Y604772D02*
X1396426Y604771D01*
G01X1394928Y589610D02*
X1394929Y589615D01*
G01X1394928Y589607D02*
Y589610D01*
G01X1394927Y589606D02*
X1394928Y589607D01*
G01X1388573Y589804D02*
X1388575Y590552D01*
G01X1388568Y589184D02*
X1388573Y589804D01*
G01X1388561Y588770D02*
X1388568Y589184D01*
G01X1388553Y588621D02*
X1388561Y588770D01*
G01X1388563Y590200D02*
X1388564Y590571D01*
G01X1388561Y589887D02*
X1388563Y590200D01*
G01X1388557Y589679D02*
X1388561Y589887D01*
G01X1388553Y589606D02*
X1388557Y589679D01*
G01X1388818Y605413D02*
X1388814Y605261D01*
G01X1388822Y605511D02*
X1388818Y605413D01*
G01X1388827Y605553D02*
X1388822Y605511D01*
G01X1390721Y588965D02*
X1390725Y589117D01*
G01X1390716Y588867D02*
X1390721Y588965D01*
G01X1390712Y588825D02*
X1390716Y588867D01*
G01X1392759Y605413D02*
X1392755Y605261D01*
G01X1392764Y605511D02*
X1392759Y605413D01*
G01X1392768Y605553D02*
X1392764Y605511D01*
G01X1394663Y588965D02*
X1394667Y589117D01*
G01X1394658Y588867D02*
X1394663Y588965D01*
G01X1394654Y588825D02*
X1394658Y588867D01*
G01X1396692Y605413D02*
X1396688Y605261D01*
G01X1396696Y605511D02*
X1396692Y605413D01*
G01X1396701Y605553D02*
X1396696Y605511D01*
G01X1388815Y606353D02*
X1388809Y606147D01*
G01X1388821Y606485D02*
X1388815Y606353D01*
G01X1388827Y606538D02*
X1388821Y606485D01*
G01X1392756Y606353D02*
X1392750Y606147D01*
G01X1392762Y606485D02*
X1392756Y606353D01*
G01X1392768Y606538D02*
X1392762Y606485D01*
G01X1390724Y588025D02*
X1390730Y588231D01*
G01X1390718Y587893D02*
X1390724Y588025D01*
G01X1390712Y587840D02*
X1390718Y587893D01*
G01X1396689Y606353D02*
X1396683Y606147D01*
G01X1396695Y606485D02*
X1396689Y606353D01*
G01X1396701Y606538D02*
X1396695Y606485D01*
G01X1394666Y588025D02*
X1394672Y588231D01*
G01X1394660Y587893D02*
X1394666Y588025D01*
G01X1394654Y587840D02*
X1394660Y587893D01*
G01X1390985Y604209D02*
X1390984Y603807D01*
G01X1390988Y604537D02*
X1390985Y604209D01*
G01X1390992Y604733D02*
X1390988Y604537D01*
G01X1390997Y604763D02*
X1390992Y604733D01*
G01X1392495Y590169D02*
X1392496Y590571D01*
G01X1392492Y589841D02*
X1392495Y590169D01*
G01X1392488Y589645D02*
X1392492Y589841D01*
G01X1392484Y589615D02*
X1392488Y589645D01*
G01X1398859Y604209D02*
X1398858Y603807D01*
G01X1398862Y604537D02*
X1398859Y604209D01*
G01X1398866Y604733D02*
X1398862Y604537D01*
G01X1398871Y604763D02*
X1398866Y604733D01*
G01X1400369Y590169D02*
X1400370Y590571D01*
G01X1400366Y589841D02*
X1400369Y590169D01*
G01X1400362Y589645D02*
X1400366Y589841D01*
G01X1400358Y589615D02*
X1400362Y589645D01*
G01X1388552Y589607D02*
X1388553Y589606D01*
G01X1388552Y589610D02*
Y589607D01*
G01X1388551Y589615D02*
X1388552Y589610D01*
G01X1388821Y587893D02*
X1388827Y587840D01*
G01X1388815Y588025D02*
X1388821Y587893D01*
G01X1388809Y588231D02*
X1388815Y588025D01*
G01X1390727Y606485D02*
X1390721Y606538D01*
G01X1390733Y606353D02*
X1390727Y606485D01*
G01X1390739Y606147D02*
X1390733Y606353D01*
G01X1392753Y587893D02*
X1392759Y587840D01*
G01X1392747Y588025D02*
X1392753Y587893D01*
G01X1392741Y588231D02*
X1392747Y588025D01*
G01X1394660Y606485D02*
X1394654Y606538D01*
G01X1394666Y606353D02*
X1394660Y606485D01*
G01X1394672Y606147D02*
X1394666Y606353D01*
G01X1396695Y587893D02*
X1396701Y587840D01*
G01X1396689Y588025D02*
X1396695Y587893D01*
G01X1396683Y588231D02*
X1396689Y588025D01*
G01X1398601Y606485D02*
X1398595Y606538D01*
G01X1398607Y606353D02*
X1398601Y606485D01*
G01X1398613Y606147D02*
X1398607Y606353D01*
G01X1400627Y587893D02*
X1400633Y587840D01*
G01X1400621Y588025D02*
X1400627Y587893D01*
G01X1400615Y588231D02*
X1400621Y588025D01*
G01X1388822Y588867D02*
X1388827Y588825D01*
G01X1388818Y588965D02*
X1388822Y588867D01*
G01X1388814Y589117D02*
X1388818Y588965D01*
G01X1390726Y605511D02*
X1390721Y605553D01*
G01X1390730Y605413D02*
X1390726Y605511D01*
G01X1390734Y605261D02*
X1390730Y605413D01*
G01X1392755Y588867D02*
X1392759Y588825D01*
G01X1392750Y588965D02*
X1392755Y588867D01*
G01X1392746Y589117D02*
X1392750Y588965D01*
G01X1394658Y605511D02*
X1394654Y605553D01*
G01X1394663Y605413D02*
X1394658Y605511D01*
G01X1394667Y605261D02*
X1394663Y605413D01*
G01X1396696Y588867D02*
X1396701Y588825D01*
G01X1396692Y588965D02*
X1396696Y588867D01*
G01X1396688Y589117D02*
X1396692Y588965D01*
G01X1398600Y605511D02*
X1398595Y605553D01*
G01X1398604Y605413D02*
X1398600Y605511D01*
G01X1398608Y605261D02*
X1398604Y605413D01*
G01X1400629Y588867D02*
X1400633Y588825D01*
G01X1400624Y588965D02*
X1400629Y588867D01*
G01X1400620Y589117D02*
X1400624Y588965D01*
G01X1390983Y589645D02*
X1390987Y589615D01*
G01X1390979Y589841D02*
X1390983Y589645D01*
G01X1390976Y590169D02*
X1390979Y589841D01*
G01X1390975Y590571D02*
X1390976Y590169D01*
G01X1392498Y604733D02*
X1392493Y604763D01*
G01X1392502Y604537D02*
X1392498Y604733D01*
G01X1392504Y604209D02*
X1392502Y604537D01*
G01X1392506Y603807D02*
X1392504Y604209D01*
G01X1398857Y589645D02*
X1398861Y589615D01*
G01X1398853Y589841D02*
X1398857Y589645D01*
G01X1398850Y590169D02*
X1398853Y589841D01*
G01X1398849Y590571D02*
X1398850Y590169D01*
G01X1400372Y604733D02*
X1400367Y604763D01*
G01X1400376Y604537D02*
X1400372Y604733D01*
G01X1400378Y604209D02*
X1400376Y604537D01*
G01X1400380Y603807D02*
X1400378Y604209D01*
G01X1388557Y604699D02*
X1388553Y604772D01*
G01X1388561Y604491D02*
X1388557Y604699D01*
G01X1388563Y604178D02*
X1388561Y604491D01*
G01X1388564Y603807D02*
X1388563Y604178D01*
G01X1388561Y605608D02*
X1388553Y605757D01*
G01X1388568Y605193D02*
X1388561Y605608D01*
G01X1388573Y604573D02*
X1388568Y605193D01*
G01X1388575Y603826D02*
X1388573Y604573D01*
G01X1394919Y588770D02*
X1394927Y588621D01*
G01X1394912Y589184D02*
X1394919Y588770D01*
G01X1394907Y589804D02*
X1394912Y589184D01*
G01X1394905Y590552D02*
X1394907Y589804D01*
G01X1394923Y589679D02*
X1394927Y589606D01*
G01X1394920Y589887D02*
X1394923Y589679D01*
G01X1394917Y590200D02*
X1394920Y589887D01*
G01X1394916Y590571D02*
X1394917Y590200D01*
G01X1396431Y604699D02*
X1396427Y604772D01*
G01X1396435Y604491D02*
X1396431Y604699D01*
G01X1396437Y604178D02*
X1396435Y604491D01*
G01X1396438Y603807D02*
X1396437Y604178D01*
G01X1396435Y605608D02*
X1396427Y605757D01*
G01X1396442Y605193D02*
X1396435Y605608D01*
G01X1396447Y604573D02*
X1396442Y605193D01*
G01X1396449Y603826D02*
X1396447Y604573D01*
G01X1394907D02*
X1394905Y603826D01*
G01X1394912Y605193D02*
X1394907Y604573D01*
G01X1394919Y605608D02*
X1394912Y605193D01*
G01X1394927Y605757D02*
X1394919Y605608D01*
G01X1396447Y589804D02*
X1396449Y590552D01*
G01X1396442Y589184D02*
X1396447Y589804D01*
G01X1396435Y588770D02*
X1396442Y589184D01*
G01X1396427Y588621D02*
X1396435Y588770D01*
G01X1394917Y604178D02*
X1394916Y603807D01*
G01X1394920Y604491D02*
X1394917Y604178D01*
G01X1394923Y604699D02*
X1394920Y604491D01*
G01X1394927Y604772D02*
X1394923Y604699D01*
G01X1396437Y590200D02*
X1396438Y590571D01*
G01X1396435Y589887D02*
X1396437Y590200D01*
G01X1396431Y589679D02*
X1396435Y589887D01*
G01X1396427Y589606D02*
X1396431Y589679D01*
G01X1398595Y588965D02*
X1398599Y589117D01*
G01X1398590Y588867D02*
X1398595Y588965D01*
G01X1398586Y588825D02*
X1398590Y588867D01*
G01X1400633Y605413D02*
X1400629Y605261D01*
G01X1400638Y605511D02*
X1400633Y605413D01*
G01X1400642Y605553D02*
X1400638Y605511D01*
G01X1400630Y606353D02*
X1400624Y606147D01*
G01X1400636Y606485D02*
X1400630Y606353D01*
G01X1400642Y606538D02*
X1400636Y606485D01*
G01X1398598Y588025D02*
X1398604Y588231D01*
G01X1398592Y587893D02*
X1398598Y588025D01*
G01X1398586Y587840D02*
X1398592Y587893D01*
G01X1394928Y604771D02*
X1394927Y604772D01*
G01X1394928Y604768D02*
Y604771D01*
G01X1394929Y604763D02*
X1394928Y604768D01*
G01X1396426Y589607D02*
X1396427Y589606D01*
G01X1396426Y589610D02*
Y589607D01*
G01X1396425Y589615D02*
X1396426Y589610D01*
G01X1398556Y588823D02*
X1398541D01*
G01X1398571Y588824D02*
X1398556Y588823D01*
G01X1398586Y588825D02*
X1398571Y588824D01*
G01X1394624Y588823D02*
X1394609D01*
G01X1394639Y588824D02*
X1394624Y588823D01*
G01X1394654Y588825D02*
X1394639Y588824D01*
G01X1390682Y588823D02*
X1390667D01*
G01X1390697Y588824D02*
X1390682Y588823D01*
G01X1390712Y588825D02*
X1390697Y588824D01*
G01X1398556Y587839D02*
X1398541D01*
G01X1398571D02*
X1398556D01*
G01X1398586Y587840D02*
X1398571Y587839D01*
G01X1394624D02*
X1394609D01*
G01X1394639D02*
X1394624D01*
G01X1394654Y587840D02*
X1394639Y587839D01*
G01X1390682D02*
X1390667D01*
G01X1390697D02*
X1390682D01*
G01X1390712Y587840D02*
X1390697Y587839D01*
G01X1388552Y588622D02*
X1388553Y588621D01*
G01X1388552Y588624D02*
Y588622D01*
G01X1388551Y588627D02*
X1388552Y588624D01*
G01X1396426Y588622D02*
X1396427Y588621D01*
G01X1396426Y588624D02*
Y588622D01*
G01X1396425Y588627D02*
X1396426Y588624D01*
G01X1394928Y605756D02*
X1394927Y605757D01*
G01X1394929Y605754D02*
X1394928Y605756D01*
G01X1394929Y605751D02*
Y605754D01*
G01X1400672Y605555D02*
X1400687D01*
G01X1400657Y605554D02*
X1400672Y605555D01*
G01X1400642Y605553D02*
X1400657Y605554D01*
G01X1396731Y605555D02*
X1396746D01*
G01X1396716Y605554D02*
X1396731Y605555D01*
G01X1396701Y605553D02*
X1396716Y605554D01*
G01X1388857Y605555D02*
X1388872D01*
G01X1388842Y605554D02*
X1388857Y605555D01*
G01X1388827Y605553D02*
X1388842Y605554D01*
G01X1400672Y606539D02*
X1400687D01*
G01X1400657D02*
X1400672D01*
G01X1400642Y606538D02*
X1400657Y606539D01*
G01X1396731D02*
X1396746D01*
G01X1396716D02*
X1396731D01*
G01X1396701Y606538D02*
X1396716Y606539D01*
G01X1392798D02*
X1392813D01*
G01X1392783D02*
X1392798D01*
G01X1392768Y606538D02*
X1392783Y606539D01*
G01X1388857D02*
X1388872D01*
G01X1388842D02*
X1388857D01*
G01X1388827Y606538D02*
X1388842Y606539D01*
G01Y587839D02*
X1388827Y587840D01*
G01X1388857Y587839D02*
X1388842D01*
G01X1388872D02*
X1388857D01*
G01X1392774D02*
X1392759Y587840D01*
G01X1392789Y587839D02*
X1392774D01*
G01X1392804D02*
X1392789D01*
G01X1396716D02*
X1396701Y587840D01*
G01X1396731Y587839D02*
X1396716D01*
G01X1396746D02*
X1396731D01*
G01X1400648D02*
X1400633Y587840D01*
G01X1400663Y587839D02*
X1400648D01*
G01X1400678D02*
X1400663D01*
G01X1390706Y606539D02*
X1390721Y606538D01*
G01X1390691Y606539D02*
X1390706D01*
G01X1390676D02*
X1390691D01*
G01X1394639D02*
X1394654Y606538D01*
G01X1394624Y606539D02*
X1394639D01*
G01X1394609D02*
X1394624D01*
G01X1398580D02*
X1398595Y606538D01*
G01X1398565Y606539D02*
X1398580D01*
G01X1398550D02*
X1398565D01*
G01X1388842Y588824D02*
X1388827Y588825D01*
G01X1388857Y588823D02*
X1388842Y588824D01*
G01X1388872Y588823D02*
X1388857D01*
G01X1392774Y588824D02*
X1392759Y588825D01*
G01X1392789Y588823D02*
X1392774Y588824D01*
G01X1392804Y588823D02*
X1392789D01*
G01X1396716Y588824D02*
X1396701Y588825D01*
G01X1396731Y588823D02*
X1396716Y588824D01*
G01X1396746Y588823D02*
X1396731D01*
G01X1400648Y588824D02*
X1400633Y588825D01*
G01X1400663Y588823D02*
X1400648Y588824D01*
G01X1400678Y588823D02*
X1400663D01*
G01X1390706Y605554D02*
X1390721Y605553D01*
G01X1390691Y605555D02*
X1390706Y605554D01*
G01X1390676Y605555D02*
X1390691D01*
G01X1394639Y605554D02*
X1394654Y605553D01*
G01X1394624Y605555D02*
X1394639Y605554D01*
G01X1394609Y605555D02*
X1394624D01*
G01X1398565D02*
X1398550D01*
G01X1398580Y605554D02*
X1398565Y605555D01*
G01X1398595Y605553D02*
X1398580Y605554D01*
G01X1398882Y605738D02*
X1399136Y605368D01*
G01X1399091Y604441D02*
X1398869Y604763D01*
G01X1394941Y605738D02*
X1395194Y605368D01*
G01X1395149Y604441D02*
X1394928Y604763D01*
G01X1391008Y605738D02*
X1391262Y605368D01*
G01X1391217Y604441D02*
X1390995Y604763D01*
G01X1400138Y589937D02*
X1400359Y589615D01*
G01X1400346Y588640D02*
X1400092Y589010D01*
G01X1392921Y610476D02*
X1390559D01*
G01X1396858D02*
X1394496D01*
G01X1400795D02*
X1398433D01*
G01X1396346Y609492D02*
X1395008D01*
G01X1394850Y609394D02*
X1396504D01*
G01X1392921Y609295D02*
X1390559D01*
G01X1396858D02*
X1394496D01*
G01X1400795D02*
X1398433D01*
G01X1396205Y589937D02*
X1396427Y589615D01*
G01X1396414Y588640D02*
X1396160Y589010D01*
G01X1392264Y589937D02*
X1392485Y589615D01*
G01X1392472Y588640D02*
X1392218Y589010D01*
G01X1388331Y589937D02*
X1388553Y589615D01*
G01X1388540Y588640D02*
X1388286Y589010D01*
G01X1396504Y608902D02*
X1394850D01*
G01X1393157Y608035D02*
X1390323D01*
G01X1397094D02*
X1394260D01*
G01X1401031D02*
X1398197D01*
G01X1396504Y607130D02*
X1394850D01*
G01Y606638D02*
X1396504D01*
G01X1393157Y606539D02*
X1390323D01*
G01X1397094D02*
X1394260D01*
G01X1401031D02*
X1398197D01*
G01X1400441Y606382D02*
X1401031D01*
G01X1398197D02*
X1398787D01*
G01X1396504D02*
X1397094D01*
G01X1394260D02*
X1394850D01*
G01X1392567D02*
X1393157D01*
G01X1390323D02*
X1390913D01*
G01X1388630D02*
X1389220D01*
G01X1398613Y606147D02*
X1400624D01*
G01X1394672D02*
X1396683D01*
G01X1390739D02*
X1392750D01*
G01X1392495Y605757D02*
X1390995D01*
G01X1396427D02*
X1394927D01*
G01X1400369D02*
X1398869D01*
G01X1398882Y605738D02*
X1400355D01*
G01X1394941D02*
X1396414D01*
G01X1391008D02*
X1392481D01*
G01X1389220Y605713D02*
X1388630D01*
G01X1390913D02*
X1390323D01*
G01X1393157D02*
X1392567D01*
G01X1394850D02*
X1394260D01*
G01X1397094D02*
X1396504D01*
G01X1398787D02*
X1398197D01*
G01X1401031D02*
X1400441D01*
G01X1398197Y605555D02*
X1401031D01*
G01X1394260D02*
X1397094D01*
G01X1390323D02*
X1393157D01*
G01X1392567Y605457D02*
X1390913D01*
G01X1400441D02*
X1398787D01*
G01X1392227Y605368D02*
X1391262D01*
G01X1396160D02*
X1395194D01*
G01X1400102D02*
X1399136D01*
G01X1398197Y605358D02*
X1398512D01*
G01X1394260D02*
X1394575D01*
G01X1390323D02*
X1390638D01*
G01X1389220D02*
X1388906D01*
G01X1393157D02*
X1392843D01*
G01X1397094D02*
X1396780D01*
G01X1401031D02*
X1400717D01*
G01X1392755Y605261D02*
X1390734D01*
G01X1396688D02*
X1394667D01*
G01X1400629D02*
X1398608D01*
G01X1398787Y604965D02*
X1400441D01*
G01X1390913D02*
X1392567D01*
G01X1392495Y604772D02*
X1390995D01*
G01X1396427D02*
X1394927D01*
G01X1400369D02*
X1398869D01*
G01X1392493Y604763D02*
X1390997D01*
G01X1396425D02*
X1394929D01*
G01X1400367D02*
X1398871D01*
G01X1399091Y604441D02*
X1400147D01*
G01X1395149D02*
X1396205D01*
G01X1391217D02*
X1392273D01*
G01X1392921Y604394D02*
X1390559D01*
G01X1396858D02*
X1394496D01*
G01X1400795D02*
X1398433D01*
G01X1400717Y603862D02*
X1401031D01*
G01X1398197D02*
X1398512D01*
G01X1396780D02*
X1397094D01*
G01X1394260D02*
X1394575D01*
G01X1392843D02*
X1393157D01*
G01X1390323D02*
X1390638D01*
G01X1388906D02*
X1389220D01*
G01X1398847Y603826D02*
X1400391D01*
G01X1394905D02*
X1396449D01*
G01X1390973D02*
X1392517D01*
G01X1398858Y603807D02*
X1400380D01*
G01X1394916D02*
X1396438D01*
G01X1390984D02*
X1392506D01*
G01X1398787Y603193D02*
X1400441D01*
G01X1390913D02*
X1392567D01*
G01Y602701D02*
X1390913D01*
G01X1400441D02*
X1398787D01*
G01X1392409Y602602D02*
X1391071D01*
G01X1400283D02*
X1398945D01*
G01Y601618D02*
X1400283D01*
G01X1391071D02*
X1392409D01*
G01X1392542Y600999D02*
X1390947D01*
G01X1396475D02*
X1394880D01*
G01X1400416D02*
X1398821D01*
G01X1392843Y600890D02*
X1390638D01*
G01X1396780D02*
X1394575D01*
G01X1400717D02*
X1398512D01*
G01X1392614Y600239D02*
X1390875D01*
G01X1396547D02*
X1394808D01*
G01X1400488D02*
X1398749D01*
G01X1398824Y600037D02*
X1400414D01*
G01X1394882D02*
X1396472D01*
G01X1390950D02*
X1392540D01*
G01X1398771Y600013D02*
X1400467D01*
G01X1394829D02*
X1396525D01*
G01X1390897D02*
X1392593D01*
G01X1392600Y599945D02*
X1390890D01*
G01X1396532D02*
X1394822D01*
G01X1400474D02*
X1398764D01*
G01X1398745Y599353D02*
X1400493D01*
G01X1394803D02*
X1396551D01*
G01X1390871D02*
X1392619D01*
G01X1392591Y599051D02*
X1390899D01*
G01X1396523D02*
X1394831D01*
G01X1400465D02*
X1398773D01*
G01X1392600Y598961D02*
X1390890D01*
G01X1396532D02*
X1394822D01*
G01X1400474D02*
X1398764D01*
G01X1398512Y598635D02*
X1400717D01*
G01X1394575D02*
X1396780D01*
G01X1390638D02*
X1392843D01*
G01X1398512Y598468D02*
X1400717D01*
G01X1394575D02*
X1396780D01*
G01X1390638D02*
X1392843D01*
G01Y595910D02*
X1390638D01*
G01X1396780D02*
X1394575D01*
G01X1400717D02*
X1398512D01*
G01X1392843Y595743D02*
X1390638D01*
G01X1396780D02*
X1394575D01*
G01X1400717D02*
X1398512D01*
G01X1398754Y595417D02*
X1400465D01*
G01X1394822D02*
X1396532D01*
G01X1390880D02*
X1392591D01*
G01X1398764Y595327D02*
X1400455D01*
G01X1394831D02*
X1396523D01*
G01X1390890D02*
X1392581D01*
G01X1392610Y595025D02*
X1390861D01*
G01X1396551D02*
X1394803D01*
G01X1400484D02*
X1398735D01*
G01X1398754Y594433D02*
X1400465D01*
G01X1394822D02*
X1396532D01*
G01X1390880D02*
X1392591D01*
G01X1392584Y594365D02*
X1390887D01*
G01X1396525D02*
X1394829D01*
G01X1400458D02*
X1398761D01*
G01X1392531Y594341D02*
X1390940D01*
G01X1396472D02*
X1394882D01*
G01X1400405D02*
X1398814D01*
G01X1398740Y594139D02*
X1400479D01*
G01X1394808D02*
X1396547D01*
G01X1390866D02*
X1392605D01*
G01X1398512Y593488D02*
X1400717D01*
G01X1394575D02*
X1396780D01*
G01X1390638D02*
X1392843D01*
G01X1398812Y593379D02*
X1400407D01*
G01X1394880D02*
X1396475D01*
G01X1390938D02*
X1392533D01*
G01X1392409Y592760D02*
X1391071D01*
G01X1400283D02*
X1398945D01*
G01X1392409Y591776D02*
X1391071D01*
G01X1400283D02*
X1398945D01*
G01X1398787Y591677D02*
X1400441D01*
G01X1390913D02*
X1392567D01*
G01Y591185D02*
X1390913D01*
G01X1400441D02*
X1398787D01*
G01X1392496Y590571D02*
X1390975D01*
G01X1396438D02*
X1394916D01*
G01X1400370D02*
X1398849D01*
G01X1392507Y590552D02*
X1390964D01*
G01X1396449D02*
X1394905D01*
G01X1400381D02*
X1398838D01*
G01X1389220Y590516D02*
X1388906D01*
G01X1390638D02*
X1390323D01*
G01X1393157D02*
X1392843D01*
G01X1394575D02*
X1394260D01*
G01X1397094D02*
X1396780D01*
G01X1398512D02*
X1398197D01*
G01X1401031D02*
X1400717D01*
G01X1392921Y589984D02*
X1390559D01*
G01X1396858D02*
X1394496D01*
G01X1400795D02*
X1398433D01*
G01X1392264Y589937D02*
X1391207D01*
G01X1396205D02*
X1395149D01*
G01X1400138D02*
X1399081D01*
G01X1398861Y589615D02*
X1400358D01*
G01X1394929D02*
X1396425D01*
G01X1390987D02*
X1392484D01*
G01X1398860Y589606D02*
X1400359D01*
G01X1394927D02*
X1396427D01*
G01X1390986D02*
X1392485D01*
G01X1392567Y589413D02*
X1390913D01*
G01X1400441D02*
X1398787D01*
G01X1398599Y589117D02*
X1400620D01*
G01X1394667D02*
X1396688D01*
G01X1390725D02*
X1392746D01*
G01X1400717Y589020D02*
X1401031D01*
G01X1396780D02*
X1397094D01*
G01X1392843D02*
X1393157D01*
G01X1388906D02*
X1389220D01*
G01X1390638D02*
X1390323D01*
G01X1394575D02*
X1394260D01*
G01X1398512D02*
X1398197D01*
G01X1399127Y589010D02*
X1400092D01*
G01X1395194D02*
X1396160D01*
G01X1391253D02*
X1392218D01*
G01X1398787Y588921D02*
X1400441D01*
G01X1390913D02*
X1392567D01*
G01X1398197Y588823D02*
X1401031D01*
G01X1394260D02*
X1397094D01*
G01X1390323D02*
X1393157D01*
G01X1400441Y588665D02*
X1401031D01*
G01X1398197D02*
X1398787D01*
G01X1396504D02*
X1397094D01*
G01X1394260D02*
X1394850D01*
G01X1392567D02*
X1393157D01*
G01X1390323D02*
X1390913D01*
G01X1388630D02*
X1389220D01*
G01X1392472Y588640D02*
X1390999D01*
G01X1396414D02*
X1394941D01*
G01X1400346D02*
X1398873D01*
G01X1398860Y588621D02*
X1400359D01*
G01X1394927D02*
X1396427D01*
G01X1390986D02*
X1392485D01*
G01X1392741Y588231D02*
X1390730D01*
G01X1396683D02*
X1394672D01*
G01X1400615D02*
X1398604D01*
G01X1389220Y587996D02*
X1388630D01*
G01X1390913D02*
X1390323D01*
G01X1393157D02*
X1392567D01*
G01X1394850D02*
X1394260D01*
G01X1397094D02*
X1396504D01*
G01X1398787D02*
X1398197D01*
G01X1401031D02*
X1400441D01*
G01X1393157Y587839D02*
X1390323D01*
G01X1397094D02*
X1394260D01*
G01X1401031D02*
X1398197D01*
G01X1396504Y587740D02*
X1394850D01*
G01Y587248D02*
X1396504D01*
G01X1398197Y586343D02*
X1401031D01*
G01X1394260D02*
X1397094D01*
G01X1390323D02*
X1393157D01*
G01X1394850Y585476D02*
X1396504D01*
G01X1392921Y585083D02*
X1390559D01*
G01X1396858D02*
X1394496D01*
G01X1400795D02*
X1398433D01*
G01X1396504Y584984D02*
X1394850D01*
G01X1396346Y584886D02*
X1395008D01*
G01X1399091Y604441D02*
X1399100Y604394D01*
G01X1400138Y589937D02*
X1400128Y589984D01*
G01X1395149Y604441D02*
X1395158Y604394D01*
G01X1396205Y589937D02*
X1396196Y589984D01*
G01X1391217Y604441D02*
X1391226Y604394D01*
G01X1392264Y589937D02*
X1392254Y589984D01*
G01X1388331Y589937D02*
X1388322Y589984D01*
G01X1398433Y583902D02*
X1400795D01*
G01X1394496D02*
X1396858D01*
G01X1390559D02*
X1392921D01*
G01X1400467Y600013D02*
X1400416Y600999D01*
G01X1400414Y600037D02*
X1400465Y599051D01*
G01X1400407Y593379D02*
X1400458Y594365D01*
G01X1400455Y595327D02*
X1400405Y594341D01*
G01X1398773Y599051D02*
X1398824Y600037D01*
G01X1398821Y600999D02*
X1398771Y600013D01*
G01X1396475Y593379D02*
X1396525Y594365D01*
G01X1396523Y595327D02*
X1396472Y594341D01*
G01X1394831Y599051D02*
X1394882Y600037D01*
G01X1394880Y600999D02*
X1394829Y600013D01*
G01X1392533Y593379D02*
X1392584Y594365D01*
G01X1392581Y595327D02*
X1392531Y594341D01*
G01X1390899Y599051D02*
X1390950Y600037D01*
G01X1390947Y600999D02*
X1390897Y600013D01*
G01X1400493Y599353D02*
X1400629Y605261D01*
G01X1400624Y606147D02*
X1400488Y600239D01*
G01X1398604Y588231D02*
X1398740Y594139D01*
G01X1398735Y595025D02*
X1398599Y589117D01*
G01X1396551Y599353D02*
X1396688Y605261D01*
G01X1396683Y606147D02*
X1396547Y600239D01*
G01X1394672Y588231D02*
X1394808Y594139D01*
G01X1394803Y595025D02*
X1394667Y589117D01*
G01X1392619Y599353D02*
X1392755Y605261D01*
G01X1392750Y606147D02*
X1392614Y600239D01*
G01X1390730Y588231D02*
X1390866Y594139D01*
G01X1390861Y595025D02*
X1390725Y589117D01*
G01X1388677Y599353D02*
X1388814Y605261D01*
G01X1388809Y606147D02*
X1388673Y600239D01*
G01X1400105Y589984D02*
X1400092Y589010D01*
G01X1399123Y604394D02*
X1399136Y605368D01*
G01X1396173Y589984D02*
X1396160Y589010D01*
G01X1395181Y604394D02*
X1395194Y605368D01*
G01X1392231Y589984D02*
X1392218Y589010D01*
G01X1391249Y604394D02*
X1391262Y605368D01*
G01X1388299Y589984D02*
X1388286Y589010D01*
G01X1400795Y589984D02*
Y583902D01*
G01Y610476D02*
Y604394D01*
G01X1400717Y587839D02*
Y606539D01*
G01X1400642Y606538D02*
Y605553D01*
G01X1400633Y588825D02*
Y587840D01*
G01X1400441Y601698D02*
Y606539D01*
G01Y587839D02*
Y592680D01*
G01X1400367Y604760D02*
Y605751D01*
G01X1400358Y588627D02*
Y589618D01*
G01X1400283Y592760D02*
Y591696D01*
G01Y602681D02*
Y601618D01*
G01X1400008Y592760D02*
Y591776D01*
G01Y602602D02*
Y601618D01*
G01X1399220Y592760D02*
Y591776D01*
G01Y602602D02*
Y601618D01*
G01X1398945Y592760D02*
Y591696D01*
G01Y602682D02*
Y601618D01*
G01X1398871Y605751D02*
Y604760D01*
G01X1398861Y589618D02*
Y588627D01*
G01X1398787Y601698D02*
Y606539D01*
G01Y587839D02*
Y592680D01*
G01X1398595Y605553D02*
Y606538D01*
G01X1398586Y587840D02*
Y588825D01*
G01X1398512Y606539D02*
Y587839D01*
G01X1398433Y589984D02*
Y583902D01*
G01Y610476D02*
Y604394D01*
G01X1398241Y606539D02*
Y605555D01*
G01X1398236Y606539D02*
Y605555D01*
G01X1398232Y588823D02*
Y587839D01*
G01X1398197Y590516D02*
Y586343D01*
G01Y608035D02*
Y603862D01*
G01X1397094D02*
Y608035D01*
G01Y586343D02*
Y590516D01*
G01X1397060Y588823D02*
Y587839D01*
G01X1397055Y588823D02*
Y587839D01*
G01Y606539D02*
Y605555D01*
G01X1396858Y589984D02*
Y583902D01*
G01Y610476D02*
Y604394D01*
G01X1396780Y587839D02*
Y606539D01*
G01X1396701Y588825D02*
Y587840D01*
G01Y606538D02*
Y605553D01*
G01X1396504Y605555D02*
Y610396D01*
G01Y583982D02*
Y588823D01*
G01X1396425Y604760D02*
Y605751D01*
G01Y588627D02*
Y589618D01*
G01X1396346Y584965D02*
Y583902D01*
G01Y610476D02*
Y609413D01*
G01X1396071Y584886D02*
Y583902D01*
G01Y610476D02*
Y609492D01*
G01X1395283D02*
Y610476D01*
G01Y584886D02*
Y583902D01*
G01X1395008Y584965D02*
Y583902D01*
G01Y610476D02*
Y609413D01*
G01X1394929Y589618D02*
Y588627D01*
G01Y605751D02*
Y604760D01*
G01X1394850Y605555D02*
Y610396D01*
G01Y583982D02*
Y588823D01*
G01X1394654Y605553D02*
Y606538D01*
G01Y587840D02*
Y588825D01*
G01X1394575Y606539D02*
Y587839D01*
G01X1394496Y589984D02*
Y583902D01*
G01Y610476D02*
Y604394D01*
G01X1394299Y588823D02*
Y587839D01*
G01Y606539D02*
Y605555D01*
G01X1394295Y606539D02*
Y605555D01*
G01X1394260Y590516D02*
Y586343D01*
G01Y608035D02*
Y603862D01*
G01X1393157D02*
Y608035D01*
G01Y586343D02*
Y590516D01*
G01X1393123Y606539D02*
Y605555D01*
G01X1393118Y588823D02*
Y587839D01*
G01X1393113Y588823D02*
Y587839D01*
G01X1392921Y589984D02*
Y583902D01*
G01Y610476D02*
Y604394D01*
G01X1392843Y587839D02*
Y606539D01*
G01X1392768Y606538D02*
Y605553D01*
G01X1392759Y588825D02*
Y587840D01*
G01X1392567Y601698D02*
Y606539D01*
G01Y587839D02*
Y592680D01*
G01X1392493Y604760D02*
Y605751D01*
G01X1392484Y588627D02*
Y589618D01*
G01X1392409Y592760D02*
Y591696D01*
G01Y602681D02*
Y601618D01*
G01X1392134D02*
Y602602D01*
G01Y592760D02*
Y591776D01*
G01X1391346Y601618D02*
Y602602D01*
G01Y591776D02*
Y592760D01*
G01X1391071D02*
Y591696D01*
G01Y602682D02*
Y601618D01*
G01X1390997Y605751D02*
Y604760D01*
G01X1390987Y589618D02*
Y588627D01*
G01X1390913Y601698D02*
Y606539D01*
G01Y587839D02*
Y592680D01*
G01X1390721Y605553D02*
Y606538D01*
G01X1390712Y587840D02*
Y588825D01*
G01X1390638Y606539D02*
Y587839D01*
G01X1390559Y589984D02*
Y583902D01*
G01Y610476D02*
Y604394D01*
G01X1390367Y606539D02*
Y605555D01*
G01X1390362Y606539D02*
Y605555D01*
G01X1390358Y588823D02*
Y587839D01*
G01X1390323Y590516D02*
Y586343D01*
G01Y608035D02*
Y603862D01*
G01X1389220D02*
Y608035D01*
G01Y586343D02*
Y590516D01*
G01X1389186Y588823D02*
Y587839D01*
G01X1389181Y588823D02*
Y587839D01*
G01Y606539D02*
Y605555D01*
G01X1388984Y589984D02*
Y583902D01*
G01Y610476D02*
Y604394D01*
G01X1388906Y587839D02*
Y606539D01*
G01X1388827Y588825D02*
Y587840D01*
G01Y606538D02*
Y605553D01*
G01X1388630Y605555D02*
Y610396D01*
G01Y583982D02*
Y588823D01*
G01X1388551Y604760D02*
Y605751D01*
G01Y588627D02*
Y589618D01*
G01X1388472Y584965D02*
Y583902D01*
G01Y610476D02*
Y609413D01*
G01X1388197Y584886D02*
Y583902D01*
G01Y610476D02*
Y609492D01*
G01X1400102Y605368D02*
X1400115Y604394D01*
G01X1399127Y589010D02*
X1399114Y589984D01*
G01X1396160Y605368D02*
X1396173Y604394D01*
G01X1395194Y589010D02*
X1395181Y589984D01*
G01X1392227Y605368D02*
X1392241Y604394D01*
G01X1391253Y589010D02*
X1391240Y589984D01*
G01X1388286Y605368D02*
X1388299Y604394D01*
G01X1400620Y589117D02*
X1400484Y595025D01*
G01X1400479Y594139D02*
X1400615Y588231D01*
G01X1398749Y600239D02*
X1398613Y606147D01*
G01X1398608Y605261D02*
X1398745Y599353D01*
G01X1396688Y589117D02*
X1396551Y595025D01*
G01X1396547Y594139D02*
X1396683Y588231D01*
G01X1394808Y600239D02*
X1394672Y606147D01*
G01X1394667Y605261D02*
X1394803Y599353D01*
G01X1392746Y589117D02*
X1392610Y595025D01*
G01X1392605Y594139D02*
X1392741Y588231D01*
G01X1390875Y600239D02*
X1390739Y606147D01*
G01X1390734Y605261D02*
X1390871Y599353D01*
G01X1388814Y589117D02*
X1388677Y595025D01*
G01X1388673Y594139D02*
X1388809Y588231D01*
G01X1398814Y594341D02*
X1398764Y595327D01*
G01X1398761Y594365D02*
X1398812Y593379D01*
G01X1396525Y600013D02*
X1396475Y600999D01*
G01X1396472Y600037D02*
X1396523Y599051D01*
G01X1394882Y594341D02*
X1394831Y595327D01*
G01X1394829Y594365D02*
X1394880Y593379D01*
G01X1392593Y600013D02*
X1392542Y600999D01*
G01X1392540Y600037D02*
X1392591Y599051D01*
G01X1390940Y594341D02*
X1390890Y595327D01*
G01X1390887Y594365D02*
X1390938Y593379D01*
G01X1388651Y600013D02*
X1388601Y600999D01*
G01X1388598Y600037D02*
X1388649Y599051D01*
G01X1399091Y589984D02*
X1399081Y589937D01*
G01X1400138Y604394D02*
X1400147Y604441D01*
G01X1395158Y589984D02*
X1395149Y589937D01*
G01X1396196Y604394D02*
X1396205Y604441D01*
G01X1391217Y589984D02*
X1391207Y589937D01*
G01X1392264Y604394D02*
X1392273Y604441D01*
G01X1388322Y604394D02*
X1388331Y604441D01*
G01X1388601Y593379D02*
X1388651Y594365D01*
G01X1388649Y595327D02*
X1388598Y594341D01*
G01X1398873Y588640D02*
X1399127Y589010D01*
G01X1398860Y589615D02*
X1399081Y589937D01*
G01X1394941Y588640D02*
X1395194Y589010D01*
G01X1394928Y589615D02*
X1395149Y589937D01*
G01X1390999Y588640D02*
X1391253Y589010D01*
G01X1390986Y589615D02*
X1391207Y589937D01*
G01X1400368Y604763D02*
X1400147Y604441D01*
G01X1400355Y605738D02*
X1400102Y605368D01*
G01X1396427Y604763D02*
X1396205Y604441D01*
G01X1396414Y605738D02*
X1396160Y605368D01*
G01X1392494Y604763D02*
X1392273Y604441D01*
G01X1392481Y605738D02*
X1392227Y605368D01*
G01X1388553Y604763D02*
X1388331Y604441D01*
G01X1388540Y605738D02*
X1388286Y605368D01*
G01X1404300Y605754D02*
X1404299Y605751D01*
G01X1404300Y605756D02*
Y605754D01*
G01X1404301Y605757D02*
X1404300Y605756D01*
G01X1412174Y605754D02*
X1412173Y605751D01*
G01X1412174Y605756D02*
Y605754D01*
G01X1412175Y605757D02*
X1412174Y605756D01*
G01X1402803Y588624D02*
Y588627D01*
G01X1402802Y588622D02*
X1402803Y588624D01*
G01X1402801Y588621D02*
X1402802Y588622D01*
G01X1420048Y605754D02*
X1420047Y605751D01*
G01X1420048Y605756D02*
Y605754D01*
G01X1420049Y605757D02*
X1420048Y605756D01*
G01X1410677Y588624D02*
Y588627D01*
G01X1410676Y588622D02*
X1410677Y588624D01*
G01X1410675Y588621D02*
X1410676Y588622D01*
G01X1427922Y605754D02*
X1427921Y605751D01*
G01X1427922Y605756D02*
Y605754D01*
G01X1427923Y605757D02*
X1427922Y605756D01*
G01X1404300Y604768D02*
X1404299Y604763D01*
G01X1404300Y604771D02*
Y604768D01*
G01X1404301Y604772D02*
X1404300Y604771D01*
G01X1402802Y589610D02*
X1402803Y589615D01*
G01X1402802Y589607D02*
Y589610D01*
G01X1402801Y589606D02*
X1402802Y589607D01*
G01X1412174Y604768D02*
X1412173Y604763D01*
G01X1412174Y604771D02*
Y604768D01*
G01X1412175Y604772D02*
X1412174Y604771D01*
G01X1410676Y589610D02*
X1410677Y589615D01*
G01X1410676Y589607D02*
Y589610D01*
G01X1410675Y589606D02*
X1410676Y589607D01*
G01X1420048Y604768D02*
X1420047Y604763D01*
G01X1420048Y604771D02*
Y604768D01*
G01X1420049Y604772D02*
X1420048Y604771D01*
G01X1427922Y604768D02*
X1427921Y604763D01*
G01X1427922Y604771D02*
Y604768D01*
G01X1427923Y604772D02*
X1427922Y604771D01*
G01X1402793Y588770D02*
X1402801Y588621D01*
G01X1402786Y589184D02*
X1402793Y588770D01*
G01X1402781Y589804D02*
X1402786Y589184D01*
G01X1402780Y590552D02*
X1402781Y589804D01*
G01X1402797Y589679D02*
X1402801Y589606D01*
G01X1402794Y589887D02*
X1402797Y589679D01*
G01X1402791Y590200D02*
X1402794Y589887D01*
G01X1402790Y590571D02*
X1402791Y590200D01*
G01X1404305Y604699D02*
X1404301Y604772D01*
G01X1404309Y604491D02*
X1404305Y604699D01*
G01X1404311Y604178D02*
X1404309Y604491D01*
G01X1404312Y603807D02*
X1404311Y604178D01*
G01X1404309Y605608D02*
X1404301Y605757D01*
G01X1404316Y605193D02*
X1404309Y605608D01*
G01X1404321Y604573D02*
X1404316Y605193D01*
G01X1404323Y603826D02*
X1404321Y604573D01*
G01X1402781D02*
X1402780Y603826D01*
G01X1402786Y605193D02*
X1402781Y604573D01*
G01X1402793Y605608D02*
X1402786Y605193D01*
G01X1402801Y605757D02*
X1402793Y605608D01*
G01X1404321Y589804D02*
X1404323Y590552D01*
G01X1404316Y589184D02*
X1404321Y589804D01*
G01X1404309Y588770D02*
X1404316Y589184D01*
G01X1404301Y588621D02*
X1404309Y588770D01*
G01X1410655Y604573D02*
X1410654Y603826D01*
G01X1410660Y605193D02*
X1410655Y604573D01*
G01X1410667Y605608D02*
X1410660Y605193D01*
G01X1410675Y605757D02*
X1410667Y605608D01*
G01X1412195Y589804D02*
X1412197Y590552D01*
G01X1412190Y589184D02*
X1412195Y589804D01*
G01X1412183Y588770D02*
X1412190Y589184D01*
G01X1412175Y588621D02*
X1412183Y588770D01*
G01X1402791Y604178D02*
X1402790Y603807D01*
G01X1402794Y604491D02*
X1402791Y604178D01*
G01X1402797Y604699D02*
X1402794Y604491D01*
G01X1402801Y604772D02*
X1402797Y604699D01*
G01X1404311Y590200D02*
X1404312Y590571D01*
G01X1404309Y589887D02*
X1404311Y590200D01*
G01X1404305Y589679D02*
X1404309Y589887D01*
G01X1404301Y589606D02*
X1404305Y589679D01*
G01X1410665Y604178D02*
X1410664Y603807D01*
G01X1410668Y604491D02*
X1410665Y604178D01*
G01X1410671Y604699D02*
X1410668Y604491D01*
G01X1410675Y604772D02*
X1410671Y604699D01*
G01X1412185Y590200D02*
X1412186Y590571D01*
G01X1412183Y589887D02*
X1412185Y590200D01*
G01X1412179Y589679D02*
X1412183Y589887D01*
G01X1412175Y589606D02*
X1412179Y589679D01*
G01X1402537Y588965D02*
X1402541Y589117D01*
G01X1402532Y588867D02*
X1402537Y588965D01*
G01X1402528Y588825D02*
X1402532Y588867D01*
G01X1404566Y605413D02*
X1404562Y605261D01*
G01X1404570Y605511D02*
X1404566Y605413D01*
G01X1404575Y605553D02*
X1404570Y605511D01*
G01X1406469Y588965D02*
X1406473Y589117D01*
G01X1406464Y588867D02*
X1406469Y588965D01*
G01X1406460Y588825D02*
X1406464Y588867D01*
G01X1408508Y605413D02*
X1408503Y605261D01*
G01X1408512Y605511D02*
X1408508Y605413D01*
G01X1408516Y605553D02*
X1408512Y605511D01*
G01X1410411Y588965D02*
X1410415Y589117D01*
G01X1410406Y588867D02*
X1410411Y588965D01*
G01X1410402Y588825D02*
X1410406Y588867D01*
G01X1412440Y605413D02*
X1412436Y605261D01*
G01X1412444Y605511D02*
X1412440Y605413D01*
G01X1412449Y605553D02*
X1412444Y605511D01*
G01X1414343Y588965D02*
X1414347Y589117D01*
G01X1414338Y588867D02*
X1414343Y588965D01*
G01X1414334Y588825D02*
X1414338Y588867D01*
G01X1416382Y605413D02*
X1416377Y605261D01*
G01X1416386Y605511D02*
X1416382Y605413D01*
G01X1416390Y605553D02*
X1416386Y605511D01*
G01X1420314Y605413D02*
X1420310Y605261D01*
G01X1420318Y605511D02*
X1420314Y605413D01*
G01X1420323Y605553D02*
X1420318Y605511D01*
G01X1404563Y606353D02*
X1404557Y606147D01*
G01X1404569Y606485D02*
X1404563Y606353D01*
G01X1404575Y606538D02*
X1404569Y606485D01*
G01X1402540Y588025D02*
X1402546Y588231D01*
G01X1402534Y587893D02*
X1402540Y588025D01*
G01X1402528Y587840D02*
X1402534Y587893D01*
G01X1408504Y606353D02*
X1408498Y606147D01*
G01X1408510Y606485D02*
X1408504Y606353D01*
G01X1408516Y606538D02*
X1408510Y606485D01*
G01X1406472Y588025D02*
X1406478Y588231D01*
G01X1406466Y587893D02*
X1406472Y588025D01*
G01X1406460Y587840D02*
X1406466Y587893D01*
G01X1412437Y606353D02*
X1412431Y606147D01*
G01X1412443Y606485D02*
X1412437Y606353D01*
G01X1412449Y606538D02*
X1412443Y606485D01*
G01X1410414Y588025D02*
X1410420Y588231D01*
G01X1410408Y587893D02*
X1410414Y588025D01*
G01X1410402Y587840D02*
X1410408Y587893D01*
G01X1416378Y606353D02*
X1416373Y606147D01*
G01X1416384Y606485D02*
X1416378Y606353D01*
G01X1416390Y606538D02*
X1416384Y606485D01*
G01X1414346Y588025D02*
X1414352Y588231D01*
G01X1414340Y587893D02*
X1414346Y588025D01*
G01X1414334Y587840D02*
X1414340Y587893D01*
G01X1420311Y606353D02*
X1420305Y606147D01*
G01X1420317Y606485D02*
X1420311Y606353D01*
G01X1420323Y606538D02*
X1420317Y606485D01*
G01X1424252Y606353D02*
X1424247Y606147D01*
G01X1424258Y606485D02*
X1424252Y606353D01*
G01X1424265Y606538D02*
X1424258Y606485D01*
G01X1406733Y604209D02*
X1406732Y603807D01*
G01X1406736Y604537D02*
X1406733Y604209D01*
G01X1406740Y604733D02*
X1406736Y604537D01*
G01X1406745Y604763D02*
X1406740Y604733D01*
G01X1408243Y590169D02*
X1408244Y590571D01*
G01X1408240Y589841D02*
X1408243Y590169D01*
G01X1408236Y589645D02*
X1408240Y589841D01*
G01X1408232Y589615D02*
X1408236Y589645D01*
G01X1414607Y604209D02*
X1414606Y603807D01*
G01X1414610Y604537D02*
X1414607Y604209D01*
G01X1414614Y604733D02*
X1414610Y604537D01*
G01X1414619Y604763D02*
X1414614Y604733D01*
G01X1416117Y590169D02*
X1416118Y590571D01*
G01X1416114Y589841D02*
X1416117Y590169D01*
G01X1416110Y589645D02*
X1416114Y589841D01*
G01X1416106Y589615D02*
X1416110Y589645D01*
G01X1422481Y604209D02*
X1422480Y603807D01*
G01X1422484Y604537D02*
X1422481Y604209D01*
G01X1422488Y604733D02*
X1422484Y604537D01*
G01X1422493Y604763D02*
X1422488Y604733D01*
G01X1402802Y604771D02*
X1402801Y604772D01*
G01X1402802Y604768D02*
Y604771D01*
G01X1402803Y604763D02*
X1402802Y604768D01*
G01X1404300Y589607D02*
X1404301Y589606D01*
G01X1404300Y589610D02*
Y589607D01*
G01X1404299Y589615D02*
X1404300Y589610D01*
G01X1410676Y604771D02*
X1410675Y604772D01*
G01X1410676Y604768D02*
Y604771D01*
G01X1410677Y604763D02*
X1410676Y604768D01*
G01X1412174Y589607D02*
X1412175Y589606D01*
G01X1412174Y589610D02*
Y589607D01*
G01X1412173Y589615D02*
X1412174Y589610D01*
G01X1402534Y606485D02*
X1402528Y606538D01*
G01X1402540Y606353D02*
X1402534Y606485D01*
G01X1402546Y606147D02*
X1402540Y606353D01*
G01X1404569Y587893D02*
X1404575Y587840D01*
G01X1404563Y588025D02*
X1404569Y587893D01*
G01X1404557Y588231D02*
X1404563Y588025D01*
G01X1406475Y606485D02*
X1406469Y606538D01*
G01X1406481Y606353D02*
X1406475Y606485D01*
G01X1406487Y606147D02*
X1406481Y606353D01*
G01X1408501Y587893D02*
X1408507Y587840D01*
G01X1408495Y588025D02*
X1408501Y587893D01*
G01X1408489Y588231D02*
X1408495Y588025D01*
G01X1410408Y606485D02*
X1410402Y606538D01*
G01X1410414Y606353D02*
X1410408Y606485D01*
G01X1410420Y606147D02*
X1410414Y606353D01*
G01X1412443Y587893D02*
X1412449Y587840D01*
G01X1412437Y588025D02*
X1412443Y587893D01*
G01X1412431Y588231D02*
X1412437Y588025D01*
G01X1414349Y606485D02*
X1414343Y606538D01*
G01X1414355Y606353D02*
X1414349Y606485D01*
G01X1414361Y606147D02*
X1414355Y606353D01*
G01X1416375Y587893D02*
X1416381Y587840D01*
G01X1416369Y588025D02*
X1416375Y587893D01*
G01X1416363Y588231D02*
X1416369Y588025D01*
G01X1418282Y606485D02*
X1418276Y606538D01*
G01X1418288Y606353D02*
X1418282Y606485D01*
G01X1418294Y606147D02*
X1418288Y606353D01*
G01X1422223Y606485D02*
X1422217Y606538D01*
G01X1422229Y606353D02*
X1422223Y606485D01*
G01X1422235Y606147D02*
X1422229Y606353D01*
G01X1426156Y606485D02*
X1426150Y606538D01*
G01X1426162Y606353D02*
X1426156Y606485D01*
G01X1426168Y606147D02*
X1426162Y606353D01*
G01X1402532Y605511D02*
X1402528Y605553D01*
G01X1402537Y605413D02*
X1402532Y605511D01*
G01X1402541Y605261D02*
X1402537Y605413D01*
G01X1404570Y588867D02*
X1404575Y588825D01*
G01X1404566Y588965D02*
X1404570Y588867D01*
G01X1404562Y589117D02*
X1404566Y588965D01*
G01X1406474Y605511D02*
X1406469Y605553D01*
G01X1406478Y605413D02*
X1406474Y605511D01*
G01X1406482Y605261D02*
X1406478Y605413D01*
G01X1408503Y588867D02*
X1408507Y588825D01*
G01X1408498Y588965D02*
X1408503Y588867D01*
G01X1408494Y589117D02*
X1408498Y588965D01*
G01X1410406Y605511D02*
X1410402Y605553D01*
G01X1410411Y605413D02*
X1410406Y605511D01*
G01X1410415Y605261D02*
X1410411Y605413D01*
G01X1412444Y588867D02*
X1412449Y588825D01*
G01X1412440Y588965D02*
X1412444Y588867D01*
G01X1412436Y589117D02*
X1412440Y588965D01*
G01X1414348Y605511D02*
X1414343Y605553D01*
G01X1414352Y605413D02*
X1414348Y605511D01*
G01X1414356Y605261D02*
X1414352Y605413D01*
G01X1416377Y588867D02*
X1416381Y588825D01*
G01X1416372Y588965D02*
X1416377Y588867D01*
G01X1416368Y589117D02*
X1416372Y588965D01*
G01X1418280Y605511D02*
X1418276Y605553D01*
G01X1418285Y605413D02*
X1418280Y605511D01*
G01X1418289Y605261D02*
X1418285Y605413D01*
G01X1422222Y605511D02*
X1422217Y605553D01*
G01X1422226Y605413D02*
X1422222Y605511D01*
G01X1422230Y605261D02*
X1422226Y605413D01*
G01X1426154Y605511D02*
X1426150Y605553D01*
G01X1426159Y605413D02*
X1426154Y605511D01*
G01X1426163Y605261D02*
X1426159Y605413D01*
G01X1406731Y589645D02*
X1406735Y589615D01*
G01X1406727Y589841D02*
X1406731Y589645D01*
G01X1406724Y590169D02*
X1406727Y589841D01*
G01X1406723Y590571D02*
X1406724Y590169D01*
G01X1408246Y604733D02*
X1408241Y604763D01*
G01X1408250Y604537D02*
X1408246Y604733D01*
G01X1408253Y604209D02*
X1408250Y604537D01*
G01X1408254Y603807D02*
X1408253Y604209D01*
G01X1414605Y589645D02*
X1414609Y589615D01*
G01X1414601Y589841D02*
X1414605Y589645D01*
G01X1414598Y590169D02*
X1414601Y589841D01*
G01X1414597Y590571D02*
X1414598Y590169D01*
G01X1416120Y604733D02*
X1416115Y604763D01*
G01X1416124Y604537D02*
X1416120Y604733D01*
G01X1416127Y604209D02*
X1416124Y604537D01*
G01X1416128Y603807D02*
X1416127Y604209D01*
G01X1423994Y604733D02*
X1423989Y604763D01*
G01X1423998Y604537D02*
X1423994Y604733D01*
G01X1424001Y604209D02*
X1423998Y604537D01*
G01X1424002Y603807D02*
X1424001Y604209D01*
G01X1410667Y588770D02*
X1410675Y588621D01*
G01X1410660Y589184D02*
X1410667Y588770D01*
G01X1410655Y589804D02*
X1410660Y589184D01*
G01X1410654Y590552D02*
X1410655Y589804D01*
G01X1410671Y589679D02*
X1410675Y589606D01*
G01X1410668Y589887D02*
X1410671Y589679D01*
G01X1410665Y590200D02*
X1410668Y589887D01*
G01X1410664Y590571D02*
X1410665Y590200D01*
G01X1412179Y604699D02*
X1412175Y604772D01*
G01X1412183Y604491D02*
X1412179Y604699D01*
G01X1412185Y604178D02*
X1412183Y604491D01*
G01X1412186Y603807D02*
X1412185Y604178D01*
G01X1412183Y605608D02*
X1412175Y605757D01*
G01X1412190Y605193D02*
X1412183Y605608D01*
G01X1412195Y604573D02*
X1412190Y605193D01*
G01X1412197Y603826D02*
X1412195Y604573D01*
G01X1420053Y604699D02*
X1420049Y604772D01*
G01X1420057Y604491D02*
X1420053Y604699D01*
G01X1420059Y604178D02*
X1420057Y604491D01*
G01X1420060Y603807D02*
X1420059Y604178D01*
G01X1420057Y605608D02*
X1420049Y605757D01*
G01X1420064Y605193D02*
X1420057Y605608D01*
G01X1420069Y604573D02*
X1420064Y605193D01*
G01X1420071Y603826D02*
X1420069Y604573D01*
G01X1427927Y604699D02*
X1427923Y604772D01*
G01X1427931Y604491D02*
X1427927Y604699D01*
G01X1427933Y604178D02*
X1427931Y604491D01*
G01X1427934Y603807D02*
X1427933Y604178D01*
G01X1427931Y605608D02*
X1427923Y605757D01*
G01X1427938Y605193D02*
X1427931Y605608D01*
G01X1427943Y604573D02*
X1427938Y605193D01*
G01X1427945Y603826D02*
X1427943Y604573D01*
G01X1418529D02*
X1418528Y603826D01*
G01X1418534Y605193D02*
X1418529Y604573D01*
G01X1418541Y605608D02*
X1418534Y605193D01*
G01X1418549Y605757D02*
X1418541Y605608D01*
G01X1426403Y604573D02*
X1426402Y603826D01*
G01X1426408Y605193D02*
X1426403Y604573D01*
G01X1426415Y605608D02*
X1426408Y605193D01*
G01X1426423Y605757D02*
X1426415Y605608D01*
G01X1418539Y604178D02*
X1418538Y603807D01*
G01X1418542Y604491D02*
X1418539Y604178D01*
G01X1418545Y604699D02*
X1418542Y604491D01*
G01X1418549Y604772D02*
X1418545Y604699D01*
G01X1426413Y604178D02*
Y603807D01*
G01X1426416Y604491D02*
X1426413Y604178D01*
G01X1426419Y604699D02*
X1426416Y604491D01*
G01X1426423Y604772D02*
X1426419Y604699D01*
G01X1424256Y605413D02*
X1424251Y605261D01*
G01X1424260Y605511D02*
X1424256Y605413D01*
G01X1424265Y605553D02*
X1424260Y605511D01*
G01X1428188Y605413D02*
X1428184Y605261D01*
G01X1428192Y605511D02*
X1428188Y605413D01*
G01X1428197Y605553D02*
X1428192Y605511D01*
G01X1428185Y606353D02*
X1428179Y606147D01*
G01X1428191Y606485D02*
X1428185Y606353D01*
G01X1428197Y606538D02*
X1428191Y606485D01*
G01X1414304Y588823D02*
X1414289D01*
G01X1414319Y588824D02*
X1414304Y588823D01*
G01X1414334Y588825D02*
X1414319Y588824D01*
G01X1410372Y588823D02*
X1410357D01*
G01X1410387Y588824D02*
X1410372Y588823D01*
G01X1410402Y588825D02*
X1410387Y588824D01*
G01X1406430Y588823D02*
X1406415D01*
G01X1406445Y588824D02*
X1406430Y588823D01*
G01X1406460Y588825D02*
X1406445Y588824D01*
G01X1402498Y588823D02*
X1402483D01*
G01X1402513Y588824D02*
X1402498Y588823D01*
G01X1402528Y588825D02*
X1402513Y588824D01*
G01X1414304Y587839D02*
X1414289D01*
G01X1414319D02*
X1414304D01*
G01X1414334Y587840D02*
X1414319Y587839D01*
G01X1410372D02*
X1410357D01*
G01X1410387D02*
X1410372D01*
G01X1410402Y587840D02*
X1410387Y587839D01*
G01X1406430D02*
X1406415D01*
G01X1406445D02*
X1406430D01*
G01X1406460Y587840D02*
X1406445Y587839D01*
G01X1402498D02*
X1402483D01*
G01X1402513D02*
X1402498D01*
G01X1402528Y587840D02*
X1402513Y587839D01*
G01X1404300Y588622D02*
X1404301Y588621D01*
G01X1404300Y588624D02*
Y588622D01*
G01X1404299Y588627D02*
X1404300Y588624D01*
G01X1402802Y605756D02*
X1402801Y605757D01*
G01X1402803Y605754D02*
X1402802Y605756D01*
G01X1402803Y605751D02*
Y605754D01*
G01X1418550Y604771D02*
X1418549Y604772D01*
G01X1418550Y604768D02*
Y604771D01*
G01X1418551Y604763D02*
X1418550Y604768D01*
G01X1426424Y604771D02*
X1426423Y604772D01*
G01X1426424Y604768D02*
Y604771D01*
G01X1426425Y604763D02*
X1426424Y604768D01*
G01X1428227Y605555D02*
X1428242D01*
G01X1428212Y605554D02*
X1428227Y605555D01*
G01X1428197Y605553D02*
X1428212Y605554D01*
G01X1420353Y605555D02*
X1420368D01*
G01X1420338Y605554D02*
X1420353Y605555D01*
G01X1420323Y605553D02*
X1420338Y605554D01*
G01X1412479Y605555D02*
X1412494D01*
G01X1412464Y605554D02*
X1412479Y605555D01*
G01X1412449Y605553D02*
X1412464Y605554D01*
G01X1408546Y605555D02*
X1408562D01*
G01X1408531Y605554D02*
X1408546Y605555D01*
G01X1408516Y605553D02*
X1408531Y605554D01*
G01X1404605Y605555D02*
X1404620D01*
G01X1404590Y605554D02*
X1404605Y605555D01*
G01X1404575Y605553D02*
X1404590Y605554D01*
G01X1428227Y606539D02*
X1428242D01*
G01X1428212D02*
X1428227D01*
G01X1428197Y606538D02*
X1428212Y606539D01*
G01X1424295D02*
X1424310D01*
G01X1424280D02*
X1424295D01*
G01X1424265Y606538D02*
X1424280Y606539D01*
G01X1420353D02*
X1420368D01*
G01X1420338D02*
X1420353D01*
G01X1420323Y606538D02*
X1420338Y606539D01*
G01X1416421D02*
X1416436D01*
G01X1416406D02*
X1416421D01*
G01X1416390Y606538D02*
X1416406Y606539D01*
G01X1412479D02*
X1412494D01*
G01X1412464D02*
X1412479D01*
G01X1412449Y606538D02*
X1412464Y606539D01*
G01X1408546D02*
X1408562D01*
G01X1408531D02*
X1408546D01*
G01X1408516Y606538D02*
X1408531Y606539D01*
G01X1404605D02*
X1404620D01*
G01X1404590D02*
X1404605D01*
G01X1404575Y606538D02*
X1404590Y606539D01*
G01Y587839D02*
X1404575Y587840D01*
G01X1404605Y587839D02*
X1404590D01*
G01X1404620D02*
X1404605D01*
G01X1408522D02*
X1408507Y587840D01*
G01X1408537Y587839D02*
X1408522D01*
G01X1408552D02*
X1408537D01*
G01X1412464D02*
X1412449Y587840D01*
G01X1412479Y587839D02*
X1412464D01*
G01X1412494D02*
X1412479D01*
G01X1416396D02*
X1416381Y587840D01*
G01X1402513Y606539D02*
X1402528Y606538D01*
G01X1402498Y606539D02*
X1402513D01*
G01X1402483D02*
X1402498D01*
G01X1406454D02*
X1406469Y606538D01*
G01X1406439Y606539D02*
X1406454D01*
G01X1406424D02*
X1406439D01*
G01X1410387D02*
X1410402Y606538D01*
G01X1410372Y606539D02*
X1410387D01*
G01X1410357D02*
X1410372D01*
G01X1414328D02*
X1414343Y606538D01*
G01X1414313Y606539D02*
X1414328D01*
G01X1414298D02*
X1414313D01*
G01X1418261D02*
X1418276Y606538D01*
G01X1418246Y606539D02*
X1418261D01*
G01X1418231D02*
X1418246D01*
G01X1422202D02*
X1422217Y606538D01*
G01X1422187Y606539D02*
X1422202D01*
G01X1422172D02*
X1422187D01*
G01X1426135D02*
X1426150Y606538D01*
G01X1426120Y606539D02*
X1426135D01*
G01X1426105D02*
X1426120D01*
G01X1404590Y588824D02*
X1404575Y588825D01*
G01X1404605Y588823D02*
X1404590Y588824D01*
G01X1404620Y588823D02*
X1404605D01*
G01X1408522Y588824D02*
X1408507Y588825D01*
G01X1408537Y588823D02*
X1408522Y588824D01*
G01X1408552Y588823D02*
X1408537D01*
G01X1412464Y588824D02*
X1412449Y588825D01*
G01X1412479Y588823D02*
X1412464Y588824D01*
G01X1412494Y588823D02*
X1412479D01*
G01X1416396Y588824D02*
X1416381Y588825D01*
G01X1402513Y605554D02*
X1402528Y605553D01*
G01X1402498Y605555D02*
X1402513Y605554D01*
G01X1402483Y605555D02*
X1402498D01*
G01X1410387Y605554D02*
X1410402Y605553D01*
G01X1410372Y605555D02*
X1410387Y605554D01*
G01X1410357Y605555D02*
X1410372D01*
G01X1414328Y605554D02*
X1414343Y605553D01*
G01X1414313Y605555D02*
X1414328Y605554D01*
G01X1414298Y605555D02*
X1414313D01*
G01X1418261Y605554D02*
X1418276Y605553D01*
G01X1418246Y605555D02*
X1418261Y605554D01*
G01X1418231Y605555D02*
X1418246D01*
G01X1422202Y605554D02*
X1422217Y605553D01*
G01X1422187Y605555D02*
X1422202Y605554D01*
G01X1422172Y605555D02*
X1422187D01*
G01X1426135Y605554D02*
X1426150Y605553D01*
G01X1426120Y605555D02*
X1426135Y605554D01*
G01X1426105Y605555D02*
X1426120D01*
G01X1412174Y588622D02*
X1412175Y588621D01*
G01X1412174Y588624D02*
Y588622D01*
G01X1412173Y588627D02*
X1412174Y588624D01*
G01X1410676Y605756D02*
X1410675Y605757D01*
G01X1410677Y605754D02*
X1410676Y605756D01*
G01X1410677Y605751D02*
Y605754D01*
G01X1418550Y605756D02*
X1418549Y605757D01*
G01X1418551Y605754D02*
X1418550Y605756D01*
G01X1418551Y605751D02*
Y605754D01*
G01X1426424Y605756D02*
X1426423Y605757D01*
G01X1426425Y605754D02*
X1426424Y605756D01*
G01X1426425Y605751D02*
Y605754D01*
G01X1406439Y605555D02*
X1406424D01*
G01X1406454Y605554D02*
X1406439Y605555D01*
G01X1406469Y605553D02*
X1406454Y605554D01*
G01X1426437Y605738D02*
X1426691Y605368D01*
G01X1426645Y604441D02*
X1426424Y604763D01*
G01X1422504Y605738D02*
X1422758Y605368D01*
G01X1422713Y604441D02*
X1422491Y604763D01*
G01X1418563Y605738D02*
X1418817Y605368D01*
G01X1418771Y604441D02*
X1418550Y604763D01*
G01X1414630Y605738D02*
X1414884Y605368D01*
G01X1414839Y604441D02*
X1414617Y604763D01*
G01X1410689Y605738D02*
X1410943Y605368D01*
G01X1410897Y604441D02*
X1410676Y604763D01*
G01X1406756Y605738D02*
X1407010Y605368D01*
G01X1406965Y604441D02*
X1406743Y604763D01*
G01X1415886Y589937D02*
X1416107Y589615D01*
G01X1416094Y588640D02*
X1415840Y589010D01*
G01X1402815Y605738D02*
X1403069Y605368D01*
G01X1403023Y604441D02*
X1402802Y604763D01*
G01X1411953Y589937D02*
X1412175Y589615D01*
G01X1412162Y588640D02*
X1411908Y589010D01*
G01X1408012Y589937D02*
X1408233Y589615D01*
G01X1408220Y588640D02*
X1407966Y589010D01*
G01X1404079Y589937D02*
X1404301Y589615D01*
G01X1404288Y588640D02*
X1404034Y589010D01*
G01X1404732Y610476D02*
X1402370D01*
G01X1408669D02*
X1406307D01*
G01X1412606D02*
X1410244D01*
G01X1416543D02*
X1414181D01*
G01X1420480D02*
X1418118D01*
G01X1424417D02*
X1422055D01*
G01X1428354D02*
X1425992D01*
G01X1431110Y609492D02*
X1435047D01*
G01X1404220D02*
X1402882D01*
G01X1412094D02*
X1410756D01*
G01X1419968D02*
X1418630D01*
G01X1427843D02*
X1426504D01*
G01X1426346Y609394D02*
X1428000D01*
G01X1418472D02*
X1420126D01*
G01X1410598D02*
X1412252D01*
G01X1402724D02*
X1404378D01*
G01X1404732Y609295D02*
X1402370D01*
G01X1408669D02*
X1406307D01*
G01X1412606D02*
X1410244D01*
G01X1416543D02*
X1414181D01*
G01X1420480D02*
X1418118D01*
G01X1424417D02*
X1422055D01*
G01X1428354D02*
X1425992D01*
G01X1438256D02*
X1433531D01*
G01X1426645Y604441D02*
X1426655Y604394D01*
G01X1422713Y604441D02*
X1422722Y604394D01*
G01X1418771Y604441D02*
X1418781Y604394D01*
G01X1414839Y604441D02*
X1414848Y604394D01*
G01X1415886Y589937D02*
X1415876Y589984D01*
G01X1410897Y604441D02*
X1410906Y604394D01*
G01X1411953Y589937D02*
X1411944Y589984D01*
G01X1406965Y604441D02*
X1406974Y604394D01*
G01X1408012Y589937D02*
X1408002Y589984D01*
G01X1404378Y608902D02*
X1402724D01*
G01X1412252D02*
X1410598D01*
G01X1420126D02*
X1418472D01*
G01X1428000D02*
X1426346D01*
G01X1446858Y608311D02*
X1498433D01*
G01X1404968Y608035D02*
X1402134D01*
G01X1408906D02*
X1406071D01*
G01X1412843D02*
X1410008D01*
G01X1416780D02*
X1413945D01*
G01X1420717D02*
X1417882D01*
G01X1424654D02*
X1421819D01*
G01X1428591D02*
X1425756D01*
G01X1404378Y607130D02*
X1402724D01*
G01X1412252D02*
X1410598D01*
G01X1420126D02*
X1418472D01*
G01X1428000D02*
X1426346D01*
G01Y606638D02*
X1428000D01*
G01X1418472D02*
X1420126D01*
G01X1410598D02*
X1412252D01*
G01X1402724D02*
X1404378D01*
G01X1404968Y606539D02*
X1402134D01*
G01X1408906D02*
X1406071D01*
G01X1412843D02*
X1410008D01*
G01X1416780D02*
X1413945D01*
G01X1420717D02*
X1417882D01*
G01X1424654D02*
X1421819D01*
G01X1428591D02*
X1425756D01*
G01X1428000Y606382D02*
X1428591D01*
G01X1425756D02*
X1426346D01*
G01X1424063D02*
X1424654D01*
G01X1421819D02*
X1422409D01*
G01X1420126D02*
X1420717D01*
G01X1417882D02*
X1418472D01*
G01X1416189D02*
X1416780D01*
G01X1413945D02*
X1414535D01*
G01X1412252D02*
X1412843D01*
G01X1410008D02*
X1410598D01*
G01X1408315D02*
X1408906D01*
G01X1406071D02*
X1406661D01*
G01X1404378D02*
X1404968D01*
G01X1402134D02*
X1402724D01*
G01X1426168Y606147D02*
X1428179D01*
G01X1422235D02*
X1424247D01*
G01X1418294D02*
X1420305D01*
G01X1414361D02*
X1416373D01*
G01X1410420D02*
X1412431D01*
G01X1406487D02*
X1408498D01*
G01X1402546D02*
X1404557D01*
G01X1404301Y605757D02*
X1402801D01*
G01X1408243D02*
X1406743D01*
G01X1412175D02*
X1410675D01*
G01X1416117D02*
X1414617D01*
G01X1420049D02*
X1418549D01*
G01X1423991D02*
X1422491D01*
G01X1427923D02*
X1426423D01*
G01X1435047Y605752D02*
X1431110D01*
G01X1426437Y605738D02*
X1427910D01*
G01X1422504D02*
X1423977D01*
G01X1418563D02*
X1420036D01*
G01X1414630D02*
X1416103D01*
G01X1410689D02*
X1412162D01*
G01X1406756D02*
X1408229D01*
G01X1402815D02*
X1404288D01*
G01X1402724Y605713D02*
X1402134D01*
G01X1404968D02*
X1404378D01*
G01X1406661D02*
X1406071D01*
G01X1408906D02*
X1408315D01*
G01X1410598D02*
X1410008D01*
G01X1412843D02*
X1412252D01*
G01X1414535D02*
X1413945D01*
G01X1416780D02*
X1416189D01*
G01X1418472D02*
X1417882D01*
G01X1420717D02*
X1420126D01*
G01X1422409D02*
X1421819D01*
G01X1424654D02*
X1424063D01*
G01X1426346D02*
X1425756D01*
G01X1428591D02*
X1428000D01*
G01X1425756Y605555D02*
X1428591D01*
G01X1421819D02*
X1424654D01*
G01X1417882D02*
X1420717D01*
G01X1413945D02*
X1416780D01*
G01X1410008D02*
X1412843D01*
G01X1406071D02*
X1408906D01*
G01X1402134D02*
X1404968D01*
G01X1408315Y605457D02*
X1406661D01*
G01X1416189D02*
X1414535D01*
G01X1424063D02*
X1422409D01*
G01X1404034Y605368D02*
X1403069D01*
G01X1407976D02*
X1407010D01*
G01X1411908D02*
X1410943D01*
G01X1415850D02*
X1414884D01*
G01X1419782D02*
X1418817D01*
G01X1423724D02*
X1422758D01*
G01X1427656D02*
X1426691D01*
G01X1425756Y605358D02*
X1426071D01*
G01X1421819D02*
X1422134D01*
G01X1417882D02*
X1418197D01*
G01X1413945D02*
X1414260D01*
G01X1410008D02*
X1410323D01*
G01X1406071D02*
X1406386D01*
G01X1402134D02*
X1402449D01*
G01X1404968D02*
X1404654D01*
G01X1408906D02*
X1408591D01*
G01X1412843D02*
X1412528D01*
G01X1416780D02*
X1416465D01*
G01X1420717D02*
X1420402D01*
G01X1424654D02*
X1424339D01*
G01X1428591D02*
X1428276D01*
G01X1404562Y605261D02*
X1402541D01*
G01X1408503D02*
X1406482D01*
G01X1412436D02*
X1410415D01*
G01X1416377D02*
X1414356D01*
G01X1420310D02*
X1418289D01*
G01X1424251D02*
X1422230D01*
G01X1428184D02*
X1426163D01*
G01X1422409Y604965D02*
X1424063D01*
G01X1414535D02*
X1416189D01*
G01X1406661D02*
X1408315D01*
G01X1404301Y604772D02*
X1402801D01*
G01X1408243D02*
X1406743D01*
G01X1412175D02*
X1410675D01*
G01X1416117D02*
X1414617D01*
G01X1420049D02*
X1418549D01*
G01X1423991D02*
X1422491D01*
G01X1427923D02*
X1426423D01*
G01X1438256Y604768D02*
X1433531D01*
G01X1404299Y604763D02*
X1402803D01*
G01X1408241D02*
X1406745D01*
G01X1412173D02*
X1410677D01*
G01X1416115D02*
X1414619D01*
G01X1420047D02*
X1418551D01*
G01X1423989D02*
X1422493D01*
G01X1427921D02*
X1426425D01*
G01X1426645Y604441D02*
X1427702D01*
G01X1422713D02*
X1423769D01*
G01X1418771D02*
X1419828D01*
G01X1414839D02*
X1415895D01*
G01X1410897D02*
X1411953D01*
G01X1406965D02*
X1408021D01*
G01X1403023D02*
X1404079D01*
G01X1404732Y604394D02*
X1402370D01*
G01X1408669D02*
X1406307D01*
G01X1412606D02*
X1410244D01*
G01X1416543D02*
X1414181D01*
G01X1420480D02*
X1418118D01*
G01X1424417D02*
X1422055D01*
G01X1428354D02*
X1425992D01*
G01X1428276Y603862D02*
X1428591D01*
G01X1425756D02*
X1426071D01*
G01X1424339D02*
X1424654D01*
G01X1421819D02*
X1422134D01*
G01X1420402D02*
X1420717D01*
G01X1417882D02*
X1418197D01*
G01X1416465D02*
X1416780D01*
G01X1413945D02*
X1414260D01*
G01X1412528D02*
X1412843D01*
G01X1410008D02*
X1410323D01*
G01X1408591D02*
X1408906D01*
G01X1406071D02*
X1406386D01*
G01X1404654D02*
X1404968D01*
G01X1402134D02*
X1402449D01*
G01X1426402Y603826D02*
X1427945D01*
G01X1422469D02*
X1424013D01*
G01X1418528D02*
X1420071D01*
G01X1414595D02*
X1416139D01*
G01X1410654D02*
X1412197D01*
G01X1406721D02*
X1408265D01*
G01X1402780D02*
X1404323D01*
G01X1426413Y603807D02*
X1427934D01*
G01X1422480D02*
X1424002D01*
G01X1418538D02*
X1420060D01*
G01X1414606D02*
X1416128D01*
G01X1410664D02*
X1412186D01*
G01X1406732D02*
X1408254D01*
G01X1402790D02*
X1404312D01*
G01X1422409Y603193D02*
X1424063D01*
G01X1414535D02*
X1416189D01*
G01X1406661D02*
X1408315D01*
G01Y602701D02*
X1406661D01*
G01X1416189D02*
X1414535D01*
G01X1424063D02*
X1422409D01*
G01X1408157Y602602D02*
X1406819D01*
G01X1416031D02*
X1414693D01*
G01X1423906D02*
X1422567D01*
G01Y601618D02*
X1423906D01*
G01X1414693D02*
X1416031D01*
G01X1406819D02*
X1408157D01*
G01X1404349Y600999D02*
X1402754D01*
G01X1408290D02*
X1406695D01*
G01X1412223D02*
X1410628D01*
G01X1416164D02*
X1414569D01*
G01X1420097D02*
X1418502D01*
G01X1424038D02*
X1422443D01*
G01X1427971D02*
X1426376D01*
G01X1404654Y600890D02*
X1402449D01*
G01X1408591D02*
X1406386D01*
G01X1412528D02*
X1410323D01*
G01X1416465D02*
X1414260D01*
G01X1420402D02*
X1418197D01*
G01X1424339D02*
X1422134D01*
G01X1428276D02*
X1426071D01*
G01X1404421Y600239D02*
X1402682D01*
G01X1408362D02*
X1406623D01*
G01X1412295D02*
X1410556D01*
G01X1416236D02*
X1414497D01*
G01X1414572Y600037D02*
X1416162D01*
G01X1410630D02*
X1412220D01*
G01X1406698D02*
X1408288D01*
G01X1402756D02*
X1404346D01*
G01X1414519Y600013D02*
X1416215D01*
G01X1410577D02*
X1412273D01*
G01X1406645D02*
X1408341D01*
G01X1402703D02*
X1404399D01*
G01X1404406Y599945D02*
X1402696D01*
G01X1408348D02*
X1406638D01*
G01X1412280D02*
X1410570D01*
G01X1416222D02*
X1414512D01*
G01X1414493Y599353D02*
X1416241D01*
G01X1410551D02*
X1412299D01*
G01X1406619D02*
X1408367D01*
G01X1402677D02*
X1404425D01*
G01X1404397Y599051D02*
X1402705D01*
G01X1408339D02*
X1406647D01*
G01X1412271D02*
X1410579D01*
G01X1416213D02*
X1414521D01*
G01X1404406Y598961D02*
X1402696D01*
G01X1408348D02*
X1406638D01*
G01X1412280D02*
X1410570D01*
G01X1416222D02*
X1414512D01*
G01X1410323Y598635D02*
X1412528D01*
G01X1406386D02*
X1408591D01*
G01X1402449D02*
X1404654D01*
G01X1410323Y598468D02*
X1412528D01*
G01X1406386D02*
X1408591D01*
G01X1402449D02*
X1404654D01*
G01Y595910D02*
X1402449D01*
G01X1408591D02*
X1406386D01*
G01X1412528D02*
X1410323D01*
G01X1404654Y595743D02*
X1402449D01*
G01X1408591D02*
X1406386D01*
G01X1412528D02*
X1410323D01*
G01X1414502Y595417D02*
X1416213D01*
G01X1410570D02*
X1412280D01*
G01X1406628D02*
X1408339D01*
G01X1402696D02*
X1404406D01*
G01X1414512Y595327D02*
X1416203D01*
G01X1410579D02*
X1412271D01*
G01X1406638D02*
X1408329D01*
G01X1402705D02*
X1404397D01*
G01X1404425Y595025D02*
X1402677D01*
G01X1408358D02*
X1406609D01*
G01X1412299D02*
X1410551D01*
G01X1416232D02*
X1414483D01*
G01X1414502Y594433D02*
X1416213D01*
G01X1410570D02*
X1412280D01*
G01X1406628D02*
X1408339D01*
G01X1402696D02*
X1404406D01*
G01X1404399Y594365D02*
X1402703D01*
G01X1408332D02*
X1406635D01*
G01X1412273D02*
X1410577D01*
G01X1416206D02*
X1414509D01*
G01X1404346Y594341D02*
X1402756D01*
G01X1408279D02*
X1406688D01*
G01X1412220D02*
X1410630D01*
G01X1416153D02*
X1414562D01*
G01X1414488Y594139D02*
X1416227D01*
G01X1410556D02*
X1412295D01*
G01X1406614D02*
X1408353D01*
G01X1402682D02*
X1404421D01*
G01X1410323Y593488D02*
X1412528D01*
G01X1406386D02*
X1408591D01*
G01X1402449D02*
X1404654D01*
G01X1414560Y593379D02*
X1416155D01*
G01X1410628D02*
X1412223D01*
G01X1406686D02*
X1408281D01*
G01X1402754D02*
X1404349D01*
G01X1408157Y592760D02*
X1406819D01*
G01X1416031D02*
X1414693D01*
G01X1408157Y591776D02*
X1406819D01*
G01X1416031D02*
X1414693D01*
G01X1414535Y591677D02*
X1416189D01*
G01X1406661D02*
X1408315D01*
G01Y591185D02*
X1406661D01*
G01X1416189D02*
X1414535D01*
G01X1404312Y590571D02*
X1402790D01*
G01X1408244D02*
X1406723D01*
G01X1412186D02*
X1410664D01*
G01X1416118D02*
X1414597D01*
G01X1404323Y590552D02*
X1402780D01*
G01X1408255D02*
X1406712D01*
G01X1412197D02*
X1410654D01*
G01X1416129D02*
X1414586D01*
G01X1402449Y590516D02*
X1402134D01*
G01X1404968D02*
X1404654D01*
G01X1406386D02*
X1406071D01*
G01X1408906D02*
X1408591D01*
G01X1410323D02*
X1410008D01*
G01X1412843D02*
X1412528D01*
G01X1414260D02*
X1413945D01*
G01X1404732Y589984D02*
X1402370D01*
G01X1408669D02*
X1406307D01*
G01X1412606D02*
X1410244D01*
G01X1404079Y589937D02*
X1403023D01*
G01X1408012D02*
X1406955D01*
G01X1411953D02*
X1410897D01*
G01X1415886D02*
X1414829D01*
G01X1414609Y589615D02*
X1416106D01*
G01X1410677D02*
X1412173D01*
G01X1406735D02*
X1408232D01*
G01X1402803D02*
X1404299D01*
G01X1414608Y589606D02*
X1416107D01*
G01X1410675D02*
X1412175D01*
G01X1406734D02*
X1408233D01*
G01X1402801D02*
X1404301D01*
G01X1408315Y589413D02*
X1406661D01*
G01X1416189D02*
X1414535D01*
G01X1414347Y589117D02*
X1416368D01*
G01X1410415D02*
X1412436D01*
G01X1406473D02*
X1408494D01*
G01X1402541D02*
X1404562D01*
G01X1412528Y589020D02*
X1412843D01*
G01X1408591D02*
X1408906D01*
G01X1404654D02*
X1404968D01*
G01X1402449D02*
X1402134D01*
G01X1406386D02*
X1406071D01*
G01X1410323D02*
X1410008D01*
G01X1414260D02*
X1413945D01*
G01X1414875Y589010D02*
X1415840D01*
G01X1410943D02*
X1411908D01*
G01X1407001D02*
X1407966D01*
G01X1403069D02*
X1404034D01*
G01X1414535Y588921D02*
X1416189D01*
G01X1406661D02*
X1408315D01*
G01X1410008Y588823D02*
X1412843D01*
G01X1406071D02*
X1408906D01*
G01X1402134D02*
X1404968D01*
G01X1413945Y588665D02*
X1414535D01*
G01X1412252D02*
X1412843D01*
G01X1410008D02*
X1410598D01*
G01X1408315D02*
X1408906D01*
G01X1406071D02*
X1406661D01*
G01X1404378D02*
X1404968D01*
G01X1402134D02*
X1402724D01*
G01X1404288Y588640D02*
X1402815D01*
G01X1408220D02*
X1406747D01*
G01X1412162D02*
X1410689D01*
G01X1416094D02*
X1414621D01*
G01X1414608Y588621D02*
X1416107D01*
G01X1410675D02*
X1412175D01*
G01X1406734D02*
X1408233D01*
G01X1402801D02*
X1404301D01*
G01X1404557Y588231D02*
X1402546D01*
G01X1408489D02*
X1406478D01*
G01X1412431D02*
X1410420D01*
G01X1416363D02*
X1414352D01*
G01X1402724Y587996D02*
X1402134D01*
G01X1404968D02*
X1404378D01*
G01X1406661D02*
X1406071D01*
G01X1408906D02*
X1408315D01*
G01X1410598D02*
X1410008D01*
G01X1412843D02*
X1412252D01*
G01X1414535D02*
X1413945D01*
G01X1404968Y587839D02*
X1402134D01*
G01X1408906D02*
X1406071D01*
G01X1412843D02*
X1410008D01*
G01X1404378Y587740D02*
X1402724D01*
G01X1412252D02*
X1410598D01*
G01Y587248D02*
X1412252D01*
G01X1402724D02*
X1404378D01*
G01X1410008Y586343D02*
X1412843D01*
G01X1406071D02*
X1408906D01*
G01X1402134D02*
X1404968D01*
G01X1410598Y585476D02*
X1412252D01*
G01X1402724D02*
X1404378D01*
G01X1404732Y585083D02*
X1402370D01*
G01X1408669D02*
X1406307D01*
G01X1412606D02*
X1410244D01*
G01X1404378Y584984D02*
X1402724D01*
G01X1412252D02*
X1410598D01*
G01X1404220Y584886D02*
X1402882D01*
G01X1412094D02*
X1410756D01*
G01X1435047Y609492D02*
Y605752D01*
G01X1433531Y609295D02*
Y601358D01*
G01X1431110Y605752D02*
Y609492D01*
G01X1403023Y604441D02*
X1403032Y604394D01*
G01X1404079Y589937D02*
X1404070Y589984D01*
G01X1410244Y583902D02*
X1412606D01*
G01X1406307D02*
X1408669D01*
G01X1402370D02*
X1404732D01*
G01X1416155Y593379D02*
X1416206Y594365D01*
G01X1416203Y595327D02*
X1416153Y594341D01*
G01X1414521Y599051D02*
X1414572Y600037D01*
G01X1414569Y600999D02*
X1414519Y600013D01*
G01X1416241Y599353D02*
X1416377Y605261D01*
G01X1416373Y606147D02*
X1416236Y600239D01*
G01X1414352Y588231D02*
X1414488Y594139D01*
G01X1414483Y595025D02*
X1414347Y589117D01*
G01X1412299Y599353D02*
X1412436Y605261D01*
G01X1412431Y606147D02*
X1412295Y600239D01*
G01X1410420Y588231D02*
X1410556Y594139D01*
G01X1410551Y595025D02*
X1410415Y589117D01*
G01X1426677Y604394D02*
X1426691Y605368D01*
G01X1422745Y604394D02*
X1422758Y605368D01*
G01X1418803Y604394D02*
X1418817Y605368D01*
G01X1415853Y589984D02*
X1415840Y589010D01*
G01X1414871Y604394D02*
X1414884Y605368D01*
G01X1411921Y589984D02*
X1411908Y589010D01*
G01X1410929Y604394D02*
X1410943Y605368D01*
G01X1428591Y603862D02*
Y608035D01*
G01X1428551Y606539D02*
Y605555D01*
G01X1428354Y610476D02*
Y604394D01*
G01X1428197Y606538D02*
Y605553D01*
G01X1428000Y605555D02*
Y610396D01*
G01X1427921Y604760D02*
Y605751D01*
G01X1427843Y610476D02*
Y609413D01*
G01X1427567Y610476D02*
Y609492D01*
G01X1426780D02*
Y610476D01*
G01X1426504D02*
Y609413D01*
G01X1426425Y605751D02*
Y604760D01*
G01X1426346Y605555D02*
Y610396D01*
G01X1426150Y605553D02*
Y606538D01*
G01X1425992Y610476D02*
Y604394D01*
G01X1425795Y606539D02*
Y605555D01*
G01X1425791Y606539D02*
Y605555D01*
G01X1425756Y608035D02*
Y603862D01*
G01X1424654D02*
Y608035D01*
G01X1424619Y606539D02*
Y605555D01*
G01X1424417Y610476D02*
Y604394D01*
G01X1424265Y606538D02*
Y605553D01*
G01X1424063Y601698D02*
Y606539D01*
G01X1423989Y604760D02*
Y605751D01*
G01X1423906Y602681D02*
Y601618D01*
G01X1423630D02*
Y602602D01*
G01X1422843Y601618D02*
Y602602D01*
G01X1422567Y602682D02*
Y601618D01*
G01X1422493Y605751D02*
Y604760D01*
G01X1422409Y601698D02*
Y606539D01*
G01X1422217Y605553D02*
Y606538D01*
G01X1422055Y610476D02*
Y604394D01*
G01X1421863Y606539D02*
Y605555D01*
G01X1421858Y606539D02*
Y605555D01*
G01X1421819Y608035D02*
Y603862D01*
G01X1420717D02*
Y608035D01*
G01X1420677Y606539D02*
Y605555D01*
G01X1420480Y610476D02*
Y604394D01*
G01X1420323Y606538D02*
Y605553D01*
G01X1420126Y605555D02*
Y610396D01*
G01X1420047Y604760D02*
Y605751D01*
G01X1419968Y610476D02*
Y609413D01*
G01X1419693Y610476D02*
Y609492D01*
G01X1418906D02*
Y610476D01*
G01X1418630D02*
Y609413D01*
G01X1418551Y605751D02*
Y604760D01*
G01X1418472Y605555D02*
Y610396D01*
G01X1418276Y605553D02*
Y606538D01*
G01X1418118Y610476D02*
Y604394D01*
G01X1417921Y606539D02*
Y605555D01*
G01X1417917Y606539D02*
Y605555D01*
G01X1417882Y608035D02*
Y603862D01*
G01X1416780D02*
Y608035D01*
G01X1416745Y606539D02*
Y605555D01*
G01X1416543Y610476D02*
Y604394D01*
G01X1416390Y606538D02*
Y605553D01*
G01X1416381Y588825D02*
Y587840D01*
G01X1416189Y601698D02*
Y606539D01*
G01Y587839D02*
Y592680D01*
G01X1416115Y604760D02*
Y605751D01*
G01X1416106Y588627D02*
Y589618D01*
G01X1416031Y592760D02*
Y591696D01*
G01Y602681D02*
Y601618D01*
G01X1415756D02*
Y602602D01*
G01Y592760D02*
Y591776D01*
G01X1414968Y601618D02*
Y602602D01*
G01Y591776D02*
Y592760D01*
G01X1414693D02*
Y591696D01*
G01Y602682D02*
Y601618D01*
G01X1414619Y605751D02*
Y604760D01*
G01X1414610Y589618D02*
Y588627D01*
G01X1414535Y601698D02*
Y606539D01*
G01Y587839D02*
Y592680D01*
G01X1414343Y605553D02*
Y606538D01*
G01X1414334Y587840D02*
Y588825D01*
G01X1414260Y606539D02*
Y587839D01*
G01X1414181Y589984D02*
Y583902D01*
G01Y610476D02*
Y604394D01*
G01X1413989Y606539D02*
Y605555D01*
G01X1413984Y606539D02*
Y605555D01*
G01X1413980Y588823D02*
Y587839D01*
G01X1413945Y590516D02*
Y586343D01*
G01Y608035D02*
Y603862D01*
G01X1412843D02*
Y608035D01*
G01Y586343D02*
Y590516D01*
G01X1412808Y588823D02*
Y587839D01*
G01X1412803Y588823D02*
Y587839D01*
G01Y606539D02*
Y605555D01*
G01X1412606Y589984D02*
Y583902D01*
G01Y610476D02*
Y604394D01*
G01X1412528Y587839D02*
Y606539D01*
G01X1412449Y588825D02*
Y587840D01*
G01Y606538D02*
Y605553D01*
G01X1412252Y605555D02*
Y610396D01*
G01Y583982D02*
Y588823D01*
G01X1412173Y604760D02*
Y605751D01*
G01Y588627D02*
Y589618D01*
G01X1412094Y584965D02*
Y583902D01*
G01Y610476D02*
Y609413D01*
G01X1411819Y584886D02*
Y583902D01*
G01Y610476D02*
Y609492D01*
G01X1411031D02*
Y610476D01*
G01Y584886D02*
Y583902D01*
G01X1410756Y584965D02*
Y583902D01*
G01Y610476D02*
Y609413D01*
G01X1410677Y589618D02*
Y588627D01*
G01Y605751D02*
Y604760D01*
G01X1410598Y605555D02*
Y610396D01*
G01Y583982D02*
Y588823D01*
G01X1410402Y605553D02*
Y606538D01*
G01Y587840D02*
Y588825D01*
G01X1410323Y606539D02*
Y587839D01*
G01X1410244Y589984D02*
Y583902D01*
G01Y610476D02*
Y604394D01*
G01X1410047Y588823D02*
Y587839D01*
G01Y606539D02*
Y605555D01*
G01X1410043Y606539D02*
Y605555D01*
G01X1410008Y590516D02*
Y586343D01*
G01Y608035D02*
Y603862D01*
G01X1408906D02*
Y608035D01*
G01Y586343D02*
Y590516D01*
G01X1408871Y606539D02*
Y605555D01*
G01X1408866Y588823D02*
Y587839D01*
G01X1408861Y588823D02*
Y587839D01*
G01X1408669Y589984D02*
Y583902D01*
G01Y610476D02*
Y604394D01*
G01X1408591Y587839D02*
Y606539D01*
G01X1408516Y606538D02*
Y605553D01*
G01X1408507Y588825D02*
Y587840D01*
G01X1408315Y601698D02*
Y606539D01*
G01Y587839D02*
Y592680D01*
G01X1408241Y604760D02*
Y605751D01*
G01X1408232Y588627D02*
Y589618D01*
G01X1408157Y592760D02*
Y591696D01*
G01Y602681D02*
Y601618D01*
G01X1407882Y592760D02*
Y591776D01*
G01Y602602D02*
Y601618D01*
G01X1407094Y592760D02*
Y591776D01*
G01Y602602D02*
Y601618D01*
G01X1406819Y592760D02*
Y591696D01*
G01Y602682D02*
Y601618D01*
G01X1406745Y605751D02*
Y604760D01*
G01X1406735Y589618D02*
Y588627D01*
G01X1406661Y601698D02*
Y606539D01*
G01Y587839D02*
Y592680D01*
G01X1427656Y605368D02*
X1427669Y604394D01*
G01X1423724Y605368D02*
X1423737Y604394D01*
G01X1419782Y605368D02*
X1419795Y604394D01*
G01X1415850Y605368D02*
X1415863Y604394D01*
G01X1414875Y589010D02*
X1414862Y589984D01*
G01X1411908Y605368D02*
X1411921Y604394D01*
G01X1410943Y589010D02*
X1410929Y589984D01*
G01X1407976Y605368D02*
X1407989Y604394D01*
G01X1407001Y589010D02*
X1406988Y589984D01*
G01X1416368Y589117D02*
X1416232Y595025D01*
G01X1416227Y594139D02*
X1416363Y588231D01*
G01X1414497Y600239D02*
X1414361Y606147D01*
G01X1414356Y605261D02*
X1414493Y599353D01*
G01X1412436Y589117D02*
X1412299Y595025D01*
G01X1412295Y594139D02*
X1412431Y588231D01*
G01X1410556Y600239D02*
X1410420Y606147D01*
G01X1410415Y605261D02*
X1410551Y599353D01*
G01X1408494Y589117D02*
X1408358Y595025D01*
G01X1408353Y594139D02*
X1408489Y588231D01*
G01X1406623Y600239D02*
X1406487Y606147D01*
G01X1406482Y605261D02*
X1406619Y599353D01*
G01X1404562Y589117D02*
X1404425Y595025D01*
G01X1404421Y594139D02*
X1404557Y588231D01*
G01X1416215Y600013D02*
X1416164Y600999D01*
G01X1416162Y600037D02*
X1416213Y599051D01*
G01X1414562Y594341D02*
X1414512Y595327D01*
G01X1414509Y594365D02*
X1414560Y593379D01*
G01X1412273Y600013D02*
X1412223Y600999D01*
G01X1412220Y600037D02*
X1412271Y599051D01*
G01X1410630Y594341D02*
X1410579Y595327D01*
G01X1410577Y594365D02*
X1410628Y593379D01*
G01X1408341Y600013D02*
X1408290Y600999D01*
G01X1408288Y600037D02*
X1408339Y599051D01*
G01X1406688Y594341D02*
X1406638Y595327D01*
G01X1406635Y594365D02*
X1406686Y593379D01*
G01X1404399Y600013D02*
X1404349Y600999D01*
G01X1404346Y600037D02*
X1404397Y599051D01*
G01X1402756Y594341D02*
X1402705Y595327D01*
G01X1402703Y594365D02*
X1402754Y593379D01*
G01X1427692Y604394D02*
X1427702Y604441D01*
G01X1423760Y604394D02*
X1423769Y604441D01*
G01X1419818Y604394D02*
X1419828Y604441D01*
G01X1414839Y589984D02*
X1414829Y589937D01*
G01X1415886Y604394D02*
X1415895Y604441D01*
G01X1410906Y589984D02*
X1410897Y589937D01*
G01X1412223Y593379D02*
X1412273Y594365D01*
G01X1412271Y595327D02*
X1412220Y594341D01*
G01X1410579Y599051D02*
X1410630Y600037D01*
G01X1410628Y600999D02*
X1410577Y600013D01*
G01X1408281Y593379D02*
X1408332Y594365D01*
G01X1408329Y595327D02*
X1408279Y594341D01*
G01X1406647Y599051D02*
X1406698Y600037D01*
G01X1406695Y600999D02*
X1406645Y600013D01*
G01X1404349Y593379D02*
X1404399Y594365D01*
G01X1404397Y595327D02*
X1404346Y594341D01*
G01X1402705Y599051D02*
X1402756Y600037D01*
G01X1402754Y600999D02*
X1402703Y600013D01*
G01X1408367Y599353D02*
X1408503Y605261D01*
G01X1408498Y606147D02*
X1408362Y600239D01*
G01X1406478Y588231D02*
X1406614Y594139D01*
G01X1406609Y595025D02*
X1406473Y589117D01*
G01X1404425Y599353D02*
X1404562Y605261D01*
G01X1404557Y606147D02*
X1404421Y600239D01*
G01X1402546Y588231D02*
X1402682Y594139D01*
G01X1402677Y595025D02*
X1402541Y589117D01*
G01X1407979Y589984D02*
X1407966Y589010D01*
G01X1406997Y604394D02*
X1407010Y605368D01*
G01X1404047Y589984D02*
X1404034Y589010D01*
G01X1403055Y604394D02*
X1403069Y605368D01*
G01X1406469Y605553D02*
Y606538D01*
G01X1406460Y587840D02*
Y588825D01*
G01X1406386Y606539D02*
Y587839D01*
G01X1406307Y589984D02*
Y583902D01*
G01Y610476D02*
Y604394D01*
G01X1406115Y606539D02*
Y605555D01*
G01X1406110Y606539D02*
Y605555D01*
G01X1406106Y588823D02*
Y587839D01*
G01X1406071Y590516D02*
Y586343D01*
G01Y608035D02*
Y603862D01*
G01X1404968D02*
Y608035D01*
G01Y586343D02*
Y590516D01*
G01X1404934Y588823D02*
Y587839D01*
G01X1404929Y588823D02*
Y587839D01*
G01Y606539D02*
Y605555D01*
G01X1404732Y589984D02*
Y583902D01*
G01Y610476D02*
Y604394D01*
G01X1404654Y587839D02*
Y606539D01*
G01X1404575Y588825D02*
Y587840D01*
G01Y606538D02*
Y605553D01*
G01X1404378Y605555D02*
Y610396D01*
G01Y583982D02*
Y588823D01*
G01X1404299Y604760D02*
Y605751D01*
G01Y588627D02*
Y589618D01*
G01X1404220Y584965D02*
Y583902D01*
G01Y610476D02*
Y609413D01*
G01X1403945Y584886D02*
Y583902D01*
G01Y610476D02*
Y609492D01*
G01X1403157D02*
Y610476D01*
G01Y584886D02*
Y583902D01*
G01X1402882Y584965D02*
Y583902D01*
G01Y610476D02*
Y609413D01*
G01X1402803Y589618D02*
Y588627D01*
G01Y605751D02*
Y604760D01*
G01X1402724Y605555D02*
Y610396D01*
G01Y583982D02*
Y588823D01*
G01X1402528Y587840D02*
Y588825D01*
G01Y605553D02*
Y606538D01*
G01X1402449Y606539D02*
Y587839D01*
G01X1402370Y589984D02*
Y583902D01*
G01Y610476D02*
Y604394D01*
G01X1402173Y588823D02*
Y587839D01*
G01Y606539D02*
Y605555D01*
G01X1402169Y606539D02*
Y605555D01*
G01X1402134Y590516D02*
Y586343D01*
G01Y608035D02*
Y603862D01*
G01X1401031D02*
Y608035D01*
G01Y586343D02*
Y590516D01*
G01X1400997Y606539D02*
Y605555D01*
G01X1400992Y588823D02*
Y587839D01*
G01X1400987Y588823D02*
Y587839D01*
G01X1404034Y605368D02*
X1404047Y604394D01*
G01X1403069Y589010D02*
X1403055Y589984D01*
G01X1402682Y600239D02*
X1402546Y606147D01*
G01X1402541Y605261D02*
X1402677Y599353D01*
G01X1411944Y604394D02*
X1411953Y604441D01*
G01X1406965Y589984D02*
X1406955Y589937D01*
G01X1408012Y604394D02*
X1408021Y604441D01*
G01X1403032Y589984D02*
X1403023Y589937D01*
G01X1404070Y604394D02*
X1404079Y604441D01*
G01X1427923Y604763D02*
X1427702Y604441D01*
G01X1427910Y605738D02*
X1427656Y605368D01*
G01X1414621Y588640D02*
X1414875Y589010D01*
G01X1414608Y589615D02*
X1414829Y589937D01*
G01X1423991Y604763D02*
X1423769Y604441D01*
G01X1423977Y605738D02*
X1423724Y605368D01*
G01X1410689Y588640D02*
X1410943Y589010D01*
G01X1410676Y589615D02*
X1410897Y589937D01*
G01X1420049Y604763D02*
X1419828Y604441D01*
G01X1420036Y605738D02*
X1419782Y605368D01*
G01X1406747Y588640D02*
X1407001Y589010D01*
G01X1406734Y589615D02*
X1406955Y589937D01*
G01X1416117Y604763D02*
X1415895Y604441D01*
G01X1416103Y605738D02*
X1415850Y605368D01*
G01X1402815Y588640D02*
X1403069Y589010D01*
G01X1402802Y589615D02*
X1403023Y589937D01*
G01X1412175Y604763D02*
X1411953Y604441D01*
G01X1412162Y605738D02*
X1411908Y605368D01*
G01X1408242Y604763D02*
X1408021Y604441D01*
G01X1408229Y605738D02*
X1407976Y605368D01*
G01X1404301Y604763D02*
X1404079Y604441D01*
G01X1404288Y605738D02*
X1404034Y605368D01*
G01X1421408Y771135D02*
Y777435D01*
X1420468Y776175D01*
G01Y771135D02*
X1422348D01*
G01X1427708Y777435D02*
X1427081Y777225D01*
X1426611Y776700D01*
X1426298Y776070D01*
X1426063Y775230D01*
X1425985Y774285D01*
X1426063Y773340D01*
X1426298Y772500D01*
X1426611Y771870D01*
X1427081Y771345D01*
X1427708Y771135D01*
X1428335Y771345D01*
X1428805Y771870D01*
X1429118Y772500D01*
X1429353Y773340D01*
X1429431Y774285D01*
X1429353Y775230D01*
X1429118Y776070D01*
X1428805Y776700D01*
X1428335Y777225D01*
X1427708Y777435D01*
G01X1500672Y-578426D02*
Y-595749D01*
G01X1508663Y-473826D02*
X1510243Y-471720D01*
X1512086Y-470667D01*
X1514192Y-470316D01*
X1516824Y-471018D01*
X1518667Y-472773D01*
X1519193Y-474878D01*
X1518930Y-476985D01*
X1517877Y-478740D01*
X1512612Y-482249D01*
X1510243Y-484706D01*
X1508663Y-488217D01*
X1508137Y-491375D01*
X1519193D01*
G01X1534724Y-470316D02*
X1532618Y-471018D01*
X1531039Y-472773D01*
X1529986Y-474878D01*
X1529196Y-477687D01*
X1528933Y-480846D01*
X1529196Y-484005D01*
X1529986Y-486813D01*
X1531039Y-488919D01*
X1532618Y-490673D01*
X1534724Y-491375D01*
X1536830Y-490673D01*
X1538409Y-488919D01*
X1539462Y-486813D01*
X1540252Y-484005D01*
X1540515Y-480846D01*
X1540252Y-477687D01*
X1539462Y-474878D01*
X1538409Y-472773D01*
X1536830Y-471018D01*
X1534724Y-470316D01*
G01X1555783Y-491375D02*
Y-470316D01*
X1552624Y-474528D01*
G01Y-491375D02*
X1558941D01*
G01X1571840Y-482601D02*
X1573683Y-480143D01*
X1575263Y-478740D01*
X1577369Y-478038D01*
X1579211Y-478740D01*
X1580527Y-480143D01*
X1581580Y-482249D01*
X1581844Y-484706D01*
X1581580Y-486813D01*
X1580527Y-488919D01*
X1578948Y-490673D01*
X1577105Y-491375D01*
X1575000Y-490673D01*
X1573157Y-488568D01*
X1572104Y-485408D01*
X1571840Y-481899D01*
X1572367Y-477336D01*
X1573157Y-474878D01*
X1574473Y-472422D01*
X1576315Y-470667D01*
X1578158Y-470316D01*
X1580001Y-471018D01*
X1581317Y-472773D01*
G01X1594479Y-484356D02*
X1601323D01*
G01X1618960Y-470316D02*
X1616854Y-471018D01*
X1615275Y-472773D01*
X1614222Y-474878D01*
X1613432Y-477687D01*
X1613169Y-480846D01*
X1613432Y-484005D01*
X1614222Y-486813D01*
X1615275Y-488919D01*
X1616854Y-490673D01*
X1618960Y-491375D01*
X1621066Y-490673D01*
X1622645Y-488919D01*
X1623698Y-486813D01*
X1624488Y-484005D01*
X1624751Y-480846D01*
X1624488Y-477687D01*
X1623698Y-474878D01*
X1622645Y-472773D01*
X1621066Y-471018D01*
X1618960Y-470316D01*
G01X1640019Y-491375D02*
X1641861Y-491024D01*
X1643967Y-489971D01*
X1645284Y-488217D01*
X1645810Y-485759D01*
X1645284Y-483303D01*
X1643704Y-481197D01*
X1641335Y-480143D01*
X1638703D01*
X1637123Y-479442D01*
X1635807Y-477687D01*
X1635281Y-475230D01*
X1636071Y-472773D01*
X1637913Y-471018D01*
X1640019Y-470316D01*
X1642125Y-471018D01*
X1643967Y-472773D01*
X1644757Y-475230D01*
X1644231Y-477687D01*
X1642915Y-479442D01*
X1641335Y-480143D01*
X1638703D01*
X1636334Y-481197D01*
X1634754Y-483303D01*
X1634228Y-485759D01*
X1634754Y-488217D01*
X1636071Y-489971D01*
X1638177Y-491024D01*
X1640019Y-491375D01*
G01X1657656Y-484356D02*
X1664500D01*
G01X1677135Y-473826D02*
X1678715Y-471720D01*
X1680558Y-470667D01*
X1682664Y-470316D01*
X1685296Y-471018D01*
X1687139Y-472773D01*
X1687665Y-474878D01*
X1687402Y-476985D01*
X1686349Y-478740D01*
X1681084Y-482249D01*
X1678715Y-484706D01*
X1677135Y-488217D01*
X1676609Y-491375D01*
X1687665D01*
G01X1697405Y-488217D02*
X1698984Y-489971D01*
X1700827Y-491024D01*
X1703196Y-491375D01*
X1705565Y-490673D01*
X1707408Y-489270D01*
X1708724Y-486813D01*
X1708987Y-484005D01*
X1708461Y-481197D01*
X1707144Y-479442D01*
X1705302Y-478038D01*
X1703459Y-477687D01*
X1701617Y-478038D01*
X1699248Y-479442D01*
X1700037Y-470316D01*
X1707144D01*
G01X1475476Y-411970D02*
Y-502100D01*
G01X1521559Y-442667D02*
Y-421608D01*
X1518400Y-425820D01*
G01Y-442667D02*
X1524717D01*
G01X1542618Y-443369D02*
X1542091Y-443018D01*
Y-442316D01*
X1542618Y-441965D01*
X1543145Y-442316D01*
Y-443018D01*
X1542618Y-443369D01*
G01X1557886Y-439509D02*
X1559465Y-441263D01*
X1561308Y-442316D01*
X1563677Y-442667D01*
X1566046Y-441965D01*
X1567889Y-440562D01*
X1569205Y-438105D01*
X1569468Y-435297D01*
X1568942Y-432489D01*
X1567625Y-430734D01*
X1565783Y-429330D01*
X1563940Y-428979D01*
X1562098Y-429330D01*
X1559729Y-430734D01*
X1560518Y-421608D01*
X1567625D01*
G01X1584209Y-442667D02*
X1584736Y-438105D01*
X1585526Y-434244D01*
X1586578Y-430734D01*
X1587895Y-426873D01*
X1590001Y-421608D01*
X1579471D01*
G01X1597898Y-442667D02*
Y-428628D01*
G01Y-432489D02*
X1598688Y-430734D01*
X1600004Y-429330D01*
X1601847Y-428628D01*
X1603689Y-429330D01*
X1605005Y-430734D01*
X1605795Y-432489D01*
Y-442667D01*
G01Y-432489D02*
X1606585Y-430734D01*
X1607901Y-429330D01*
X1609743Y-428628D01*
X1611586Y-429330D01*
X1612902Y-430734D01*
X1613692Y-432840D01*
Y-442667D01*
G01X1618957D02*
Y-428628D01*
G01Y-432489D02*
X1619747Y-430734D01*
X1621063Y-429330D01*
X1622906Y-428628D01*
X1624748Y-429330D01*
X1626064Y-430734D01*
X1626854Y-432489D01*
Y-442667D01*
G01Y-432489D02*
X1627644Y-430734D01*
X1628960Y-429330D01*
X1630802Y-428628D01*
X1632645Y-429330D01*
X1633961Y-430734D01*
X1634751Y-432840D01*
Y-442667D01*
G01X1479973Y-153821D02*
Y-164057D01*
G01X1478989Y-153821D02*
Y-164057D01*
G01X1476824Y-153821D02*
Y-164057D01*
G01X1475840Y-153821D02*
Y-164057D01*
G01X1473674Y-153821D02*
Y-164057D01*
G01X1472690Y-153821D02*
Y-164057D01*
G01X1470525Y-153821D02*
Y-164057D01*
G01X1469540Y-153821D02*
Y-164057D01*
G01X1472690D02*
X1470525D01*
G01X1475840D02*
X1473674D01*
G01X1478989D02*
X1476824D01*
G01X1482139D02*
X1479973D01*
G01X1472690Y-153821D02*
X1470525D01*
G01X1475840D02*
X1473674D01*
G01X1478989D02*
X1476824D01*
G01X1482139D02*
X1479973D01*
G01X1514619Y-167994D02*
X1516588Y-166026D01*
G01X1514619Y-167994D02*
X1516588Y-166026D01*
G01D02*
Y-98585D01*
G01Y-166026D02*
Y-98585D01*
G01X1513635Y-153821D02*
Y-164057D01*
G01X1511469Y-153821D02*
Y-164057D01*
G01X1510485Y-153821D02*
Y-164057D01*
G01X1508320Y-153821D02*
Y-164057D01*
G01X1507336Y-153821D02*
Y-164057D01*
G01X1505170Y-153821D02*
Y-164057D01*
G01X1504186Y-153821D02*
Y-164057D01*
G01X1502021Y-153821D02*
Y-164057D01*
G01X1501036Y-153821D02*
Y-164057D01*
G01X1498871Y-153821D02*
Y-164057D01*
G01X1497887Y-153821D02*
Y-164057D01*
G01X1495721Y-153821D02*
Y-164057D01*
G01X1494737Y-153821D02*
Y-164057D01*
G01X1492572Y-153821D02*
Y-164057D01*
G01X1491588Y-153821D02*
Y-164057D01*
G01X1489422Y-153821D02*
Y-164057D01*
G01X1488438Y-153821D02*
Y-164057D01*
G01X1486273Y-153821D02*
Y-164057D01*
G01X1485288Y-153821D02*
Y-164057D01*
G01X1483123Y-153821D02*
Y-164057D01*
G01X1482139Y-153821D02*
Y-164057D01*
G01X1485288D02*
X1483123D01*
G01X1488438D02*
X1486273D01*
G01X1491588D02*
X1489422D01*
G01X1494737D02*
X1492572D01*
G01X1497887D02*
X1495721D01*
G01X1501036D02*
X1498871D01*
G01X1504186D02*
X1502021D01*
G01X1507336D02*
X1505170D01*
G01X1510485D02*
X1508320D01*
G01X1513635D02*
X1511469D01*
G01X1485288Y-153821D02*
X1483123D01*
G01X1488438D02*
X1486273D01*
G01X1491588D02*
X1489422D01*
G01X1494737D02*
X1492572D01*
G01X1497887D02*
X1495721D01*
G01X1501036D02*
X1498871D01*
G01X1504186D02*
X1502021D01*
G01X1507336D02*
X1505170D01*
G01X1510485D02*
X1508320D01*
G01X1513635D02*
X1511469D01*
G01X1534240Y-87685D02*
G03X1535170Y-85162I-3007J2541D01*
G01X1525665Y-94648D02*
G03X1528672Y-93253I1J3937D01*
G01X1520525Y-94648D02*
G03X1516588Y-98585I0J-3937D01*
G01X1520525Y-94648D02*
G03X1516588Y-98585I0J-3937D01*
G01X1534017Y-87927D02*
G03X1535170Y-85143I-2784J2784D01*
G01X1525665Y-94648D02*
G03X1528449Y-93495I0J3937D01*
G01X1535170Y17239D02*
Y-85162D01*
G01Y60726D02*
Y-85143D01*
G01X1534017Y-87927D02*
X1528449Y-93495D01*
G01X1534240Y-87685D02*
X1528672Y-93253D01*
G01X1517050Y10989D02*
X1516886Y-97082D01*
G01X1517009Y-15868D02*
Y-94648D01*
G01X1498899D02*
Y-15868D01*
G01X1517009Y-94648D02*
X1498899D01*
G01X1525665D02*
X1520525D01*
G01X1525665D02*
X1520525D01*
G01X1509545Y-67521D02*
X1509299Y-67856D01*
G01X1506920Y-66348D02*
X1507166Y-66013D01*
G01X1510529Y-65343D02*
X1510365Y-65594D01*
G01X1507412Y-66348D02*
X1507248Y-66599D01*
G01X1509709Y-67186D02*
X1509545Y-67521D01*
G01X1509053D02*
X1509217Y-67186D01*
G01X1504788Y-66181D02*
X1504870Y-66013D01*
G01X1503475Y-66181D02*
X1503557Y-66013D01*
G01X1501097Y-66181D02*
X1501179Y-66013D01*
G01X1499784Y-66181D02*
X1499866Y-66013D01*
G01X1506756Y-66767D02*
X1506920Y-66348D01*
G01X1503229Y-65762D02*
X1503065Y-66181D01*
G01X1499538Y-65762D02*
X1499374Y-66181D01*
G01X1507248Y-66599D02*
X1507166Y-66851D01*
G01X1516025Y-68191D02*
Y-64254D01*
G01X1515532Y-66348D02*
Y-68191D01*
G01Y-64254D02*
Y-65845D01*
G01X1513236D02*
Y-64254D01*
G01Y-68191D02*
Y-66348D01*
G01X1512744Y-64254D02*
Y-68191D01*
G01X1509709Y-64254D02*
Y-66432D01*
G01X1509299Y-66013D02*
Y-64673D01*
G01X1507166Y-66851D02*
Y-67018D01*
G01X1506920Y-64673D02*
Y-64254D01*
G01X1506756Y-67102D02*
Y-66767D01*
G01X1506100Y-68191D02*
Y-65510D01*
G01X1505690Y-66097D02*
Y-68191D01*
G01Y-65510D02*
Y-65762D01*
G01X1504788Y-68191D02*
Y-66181D01*
G01X1504378D02*
Y-68191D01*
G01X1503475D02*
Y-66181D01*
G01X1503065D02*
Y-68191D01*
G01X1502409D02*
Y-65510D01*
G01X1501999Y-66097D02*
Y-68191D01*
G01Y-65510D02*
Y-65762D01*
G01X1501097Y-68191D02*
Y-66181D01*
G01X1500687D02*
Y-68191D01*
G01X1499784D02*
Y-66181D01*
G01X1499374D02*
Y-68191D01*
G01X1507166Y-67018D02*
X1507248Y-67270D01*
G01X1504870Y-66013D02*
X1504952Y-65929D01*
G01X1504706Y-65594D02*
X1504460Y-65845D01*
G01X1503557Y-66013D02*
X1503639Y-65929D01*
G01X1503393Y-65594D02*
X1503229Y-65762D01*
G01X1501179Y-66013D02*
X1501261Y-65929D01*
G01X1501015Y-65594D02*
X1500769Y-65845D01*
G01X1499866Y-66013D02*
X1499948Y-65929D01*
G01X1499702Y-65594D02*
X1499538Y-65762D01*
G01X1506920Y-67521D02*
X1506756Y-67102D01*
G01X1504296Y-66013D02*
X1504378Y-66181D01*
G01X1500605Y-66013D02*
X1500687Y-66181D01*
G01X1509299Y-67856D02*
X1508889Y-68107D01*
G01X1508807Y-67688D02*
X1509053Y-67521D01*
G01X1507658Y-66181D02*
X1507412Y-66348D01*
G01X1510365Y-66767D02*
X1510529Y-67018D01*
G01X1507248Y-67270D02*
X1507412Y-67521D01*
G01X1507166Y-67856D02*
X1506920Y-67521D01*
G01X1511513Y-66181D02*
X1510365Y-66767D01*
G01X1504952Y-65929D02*
X1505116Y-65845D01*
G01X1503639Y-65929D02*
X1503803Y-65845D01*
G01X1501261Y-65929D02*
X1501425Y-65845D01*
G01X1499948Y-65929D02*
X1500112Y-65845D01*
G01X1510529Y-67018D02*
X1512088Y-66181D01*
G01X1507166Y-66013D02*
X1507576Y-65762D01*
G01X1505690D02*
X1505526Y-65594D01*
G01Y-65929D02*
X1505690Y-66097D01*
G01X1504460Y-65845D02*
X1504214Y-65594D01*
G01Y-65929D02*
X1504296Y-66013D01*
G01X1504952Y-65510D02*
X1504706Y-65594D01*
G01X1503639Y-65510D02*
X1503393Y-65594D01*
G01X1501261Y-65510D02*
X1501015Y-65594D01*
G01X1499948Y-65510D02*
X1499702Y-65594D01*
G01X1501999Y-65762D02*
X1501835Y-65594D01*
G01Y-65929D02*
X1501999Y-66097D01*
G01X1500769Y-65845D02*
X1500523Y-65594D01*
G01Y-65929D02*
X1500605Y-66013D01*
G01X1509135Y-66432D02*
X1508807Y-66181D01*
G01X1507412Y-67521D02*
X1507658Y-67688D01*
G01X1508889Y-65762D02*
X1509299Y-66013D01*
G01X1507576Y-68107D02*
X1507166Y-67856D01*
G01X1512088Y-66181D02*
X1510529Y-65343D01*
G01X1510365Y-65594D02*
X1511513Y-66181D01*
G01X1504049Y-65845D02*
X1504214Y-65929D01*
G01X1500359Y-65845D02*
X1500523Y-65929D01*
G01X1505526Y-65594D02*
X1505280Y-65510D01*
G01Y-65845D02*
X1505526Y-65929D01*
G01X1504214Y-65594D02*
X1503967Y-65510D01*
G01X1501835Y-65594D02*
X1501589Y-65510D01*
G01Y-65845D02*
X1501835Y-65929D01*
G01X1500523Y-65594D02*
X1500277Y-65510D01*
G01X1508807Y-66181D02*
X1508479Y-66097D01*
G01X1507658Y-67688D02*
X1507986Y-67772D01*
G01X1508479Y-65678D02*
X1508889Y-65762D01*
G01X1507986Y-68191D02*
X1507576Y-68107D01*
G01X1506920Y-64254D02*
X1509709D01*
G01X1513236D02*
X1512744D01*
G01X1516025D02*
X1515532D01*
G01X1509299Y-64673D02*
X1506920D01*
G01X1500277Y-65510D02*
X1499948D01*
G01X1501589D02*
X1501261D01*
G01X1502409D02*
X1501999D01*
G01X1503967D02*
X1503639D01*
G01X1505280D02*
X1504952D01*
G01X1506100D02*
X1505690D01*
G01X1507986Y-65678D02*
X1508479D01*
G01X1505116Y-65845D02*
X1505280D01*
G01X1503803D02*
X1504049D01*
G01X1501425D02*
X1501589D01*
G01X1500112D02*
X1500359D01*
G01X1515532D02*
X1513236D01*
G01X1508479Y-66097D02*
X1507986D01*
G01X1513236Y-66348D02*
X1515532D01*
G01X1509709Y-66432D02*
X1509135D01*
G01X1509217Y-67186D02*
X1509709D01*
G01X1507986Y-67772D02*
X1508479D01*
G01X1515532Y-68191D02*
X1516025D01*
G01X1512744D02*
X1513236D01*
G01X1504378D02*
X1504788D01*
G01X1505690D02*
X1506100D01*
G01X1503065D02*
X1503475D01*
G01X1501999D02*
X1502409D01*
G01X1500687D02*
X1501097D01*
G01X1499374D02*
X1499784D01*
G01X1508479D02*
X1507986D01*
G01X1507576Y-65762D02*
X1507986Y-65678D01*
G01X1508889Y-68107D02*
X1508479Y-68191D01*
G01X1507986Y-66097D02*
X1507658Y-66181D01*
G01X1508479Y-67772D02*
X1508807Y-67688D01*
G01X1479225Y13817D02*
Y2006D01*
G01X1468645D02*
Y11807D01*
G01X1479225Y2006D02*
X1480702D01*
G01X1472090Y6278D02*
X1472582Y5524D01*
G01X1470121Y10047D02*
Y12058D01*
G01D02*
X1468645Y13817D01*
G01Y11807D02*
X1470121Y10047D01*
G01X1472582Y10550D02*
X1472090Y9796D01*
G01X1477257Y8037D02*
X1472582Y10550D01*
G01X1472090Y9796D02*
X1475534Y8037D01*
G01X1472582Y5524D02*
X1477257Y8037D01*
G01X1475534D02*
X1472090Y6278D01*
G01X1480702Y13817D02*
X1479225D01*
G01X1529918Y-50083D02*
X1529836Y-49580D01*
G01X1527785Y-50669D02*
X1527867Y-51172D01*
G01X1530328Y-49999D02*
X1530246Y-49580D01*
G01X1530000Y-51758D02*
X1530164Y-51423D01*
G01X1527703Y-48994D02*
X1527539Y-49329D01*
G01X1530164Y-51423D02*
X1530246Y-51172D01*
G01X1527539Y-49329D02*
X1527457Y-49580D01*
G01X1530246Y-51172D02*
X1530328Y-50753D01*
G01X1527457Y-49580D02*
X1527375Y-49999D01*
G01X1529836Y-51172D02*
X1529918Y-50669D01*
G01X1527867Y-49580D02*
X1527785Y-50083D01*
G01X1530328Y-50753D02*
Y-49999D01*
G01X1529918Y-50669D02*
Y-50083D01*
G01X1527785D02*
Y-50669D01*
G01X1527375Y-49999D02*
Y-50753D01*
G01X1526719Y-50669D02*
Y-51004D01*
G01Y-49664D02*
Y-49999D01*
G01X1525406D02*
Y-49664D01*
G01Y-51004D02*
Y-50669D01*
G01X1524750Y-48407D02*
Y-52344D01*
G01X1524258Y-49999D02*
Y-48407D01*
G01Y-52344D02*
Y-50502D01*
G01X1521962D02*
Y-52344D01*
G01Y-48407D02*
Y-49999D01*
G01X1521469Y-52344D02*
Y-48407D01*
G01X1527375Y-50753D02*
X1527457Y-51172D01*
G01X1530246Y-49580D02*
X1530164Y-49329D01*
G01X1527457Y-51172D02*
X1527539Y-51423D01*
G01X1529508Y-51674D02*
X1529836Y-51172D01*
G01X1528195Y-49078D02*
X1527867Y-49580D01*
G01X1516936Y-11908D02*
X1516935Y-15888D01*
G01X1516942Y11001D02*
Y-15868D01*
G01X1530164Y-49329D02*
X1530000Y-48994D01*
G01X1527539Y-51423D02*
X1527703Y-51758D01*
G01X1484511Y42911D02*
X1515241Y-11908D01*
G01X1484497Y42911D02*
X1515239Y-11921D01*
G01X1484501Y42911D02*
X1515237Y-11892D01*
G01X1529754Y-52009D02*
X1530000Y-51758D01*
G01X1527949Y-48743D02*
X1527703Y-48994D01*
G01X1489068Y2006D02*
Y13817D01*
G01X1487591Y7534D02*
Y2006D01*
G01X1480702D02*
Y7534D01*
G01X1529836Y-49580D02*
X1529508Y-49078D01*
G01X1527867Y-51172D02*
X1528195Y-51674D01*
G01X1529261Y-51842D02*
X1529508Y-51674D01*
G01X1528441Y-48910D02*
X1528195Y-49078D01*
G01X1530000Y-48994D02*
X1529754Y-48743D01*
G01X1527703Y-51758D02*
X1527949Y-52009D01*
G01X1529343Y-52261D02*
X1529754Y-52009D01*
G01X1528359Y-48491D02*
X1527949Y-48743D01*
G01X1529508Y-49078D02*
X1529261Y-48910D01*
G01X1528195Y-51674D02*
X1528441Y-51842D01*
G01X1529754Y-48743D02*
X1529343Y-48491D01*
G01X1527949Y-52009D02*
X1528359Y-52261D01*
G01X1529261Y-48910D02*
X1528851Y-48826D01*
G01X1528441Y-51842D02*
X1528851Y-51926D01*
G01X1529343Y-48491D02*
X1528851Y-48407D01*
G01X1487591Y2006D02*
X1489068D01*
G01X1528359Y-52261D02*
X1528851Y-52344D01*
G01X1515241Y-11908D02*
X1516936D01*
G01X1515237Y-11892D02*
X1516942D01*
G01X1515239Y-11921D02*
X1516942D01*
G01X1524258Y-48407D02*
X1524750D01*
G01X1521469D02*
X1521962D01*
G01X1525406Y-49664D02*
X1526719D01*
G01X1521962Y-49999D02*
X1524258D01*
G01X1526719D02*
X1525406D01*
G01X1524258Y-50502D02*
X1521962D01*
G01X1525406Y-50669D02*
X1526719D01*
G01Y-51004D02*
X1525406D01*
G01X1521962Y-52344D02*
X1521469D01*
G01X1524750D02*
X1524258D01*
G01X1528851Y-48407D02*
X1528359Y-48491D01*
G01X1528851Y-52344D02*
X1529343Y-52261D01*
G01X1528851Y-48826D02*
X1528441Y-48910D01*
G01X1528851Y-51926D02*
X1529261Y-51842D01*
G01X1538123Y33502D02*
G03I-18701J0D01*
G01X1517050Y10989D02*
G03X1535170Y17239I2373J22513D01*
G01Y49767D02*
G03X1516942Y11001I-15746J-16265D01*
G01X1487591Y13817D02*
Y9042D01*
G01X1480702D02*
Y13817D01*
G01X1489068D02*
X1487591D01*
G01Y9042D02*
X1480702D01*
G01Y7534D02*
X1487591D01*
G01X1469293Y79325D02*
X1469621Y78487D01*
G01X1468801D02*
X1468637Y78823D01*
G01X1468965Y79660D02*
X1469293Y79325D01*
G01X1468637Y78823D02*
X1468473Y78990D01*
G01X1469621Y78487D02*
Y74467D01*
G01X1468801D02*
Y78487D01*
G01X1468473Y78990D02*
X1468145Y79158D01*
G01X1468473Y79828D02*
X1468965Y79660D01*
G01X1469621Y74467D02*
X1468801D01*
G01X1523359Y33502D02*
X1548121D01*
G01X1519422Y37568D02*
Y78859D01*
G01X1539107Y64663D02*
G03X1535170Y60726I0J-3937D01*
G01X1539107Y64663D02*
G03X1535170Y60726I0J-3937D01*
G01X1526322Y33502D02*
G03I-6900J0D01*
G01X1535170Y60726D02*
Y49767D01*
G01X1588320Y64663D02*
X1539107D01*
G01X1588320D02*
X1539107D01*
G01X1514829Y95641D02*
X1515485D01*
G01X1513517Y94755D02*
X1514829Y95641D01*
G01X1509580Y102285D02*
Y98741D01*
G01X1516798Y92098D02*
X1516141Y91655D01*
G01X1517454Y92983D02*
X1516798Y92098D01*
G01X1517454Y93869D02*
Y92983D01*
G01X1516798Y94755D02*
X1517454Y93869D01*
G01X1515485Y95641D02*
X1516798Y94755D01*
G01X1512860Y93869D02*
X1513517Y94755D01*
G01X1512204D02*
X1512860Y93869D01*
G01X1511548Y95198D02*
X1512204Y94755D01*
G01X1510892Y95198D02*
X1511548D01*
G01X1510236Y94755D02*
X1510892Y95198D01*
G01X1509580Y93869D02*
X1510236Y94755D01*
G01X1509580Y92983D02*
Y93869D01*
G01X1510236Y92098D02*
X1509580Y92983D01*
G01X1512860D02*
Y93869D01*
G01X1509580Y86340D02*
X1517454D01*
G01X1516798Y122659D02*
X1517454Y121773D01*
G01X1516141Y123102D02*
X1516798Y122659D01*
G01X1514829Y123544D02*
X1516141Y123102D01*
G01X1512204Y123544D02*
X1514829D01*
G01X1510892Y123102D02*
X1512204Y123544D01*
G01X1510236Y122659D02*
X1510892Y123102D01*
G01X1509580Y121773D02*
X1510236Y122659D01*
G01Y120887D02*
X1509580Y121773D01*
G01X1510892Y120444D02*
X1510236Y120887D01*
G01X1512204Y120001D02*
X1510892Y120444D01*
G01X1514829Y120001D02*
X1512204D01*
G01X1516141Y120444D02*
X1514829Y120001D01*
G01X1516798Y120887D02*
X1516141Y120444D01*
G01X1517454Y121773D02*
X1516798Y120887D01*
G01X1514173Y100956D02*
X1512204Y101399D01*
G01X1517454Y100513D02*
X1514173Y100956D01*
G01X1512204Y101399D02*
X1509580Y102285D01*
G01X1516798Y113800D02*
X1516141Y113357D01*
G01X1517454Y114686D02*
X1516798Y113800D01*
G01Y115572D02*
X1517454Y114686D01*
G01X1516141Y116015D02*
X1516798Y115572D01*
G01X1514829Y116458D02*
X1516141Y116015D01*
G01X1512204Y116458D02*
X1514829D01*
G01X1510892Y116015D02*
X1512204Y116458D01*
G01X1510236Y115572D02*
X1510892Y116015D01*
G01X1509580Y114686D02*
X1510236Y115572D01*
G01Y113800D02*
X1509580Y114686D01*
G01X1510892Y113357D02*
X1510236Y113800D01*
G01X1512204Y112914D02*
X1510892Y113357D01*
G01X1513517D02*
X1512204Y112914D01*
G01X1514173Y114686D02*
X1513517Y113357D01*
G01Y116015D02*
X1514173Y114686D01*
G01X1512204Y116458D02*
X1513517Y116015D01*
G01X1516798Y107157D02*
X1517454Y107600D01*
G01Y107157D02*
X1516798D01*
G01X1517454Y107600D02*
Y107157D01*
G01X1532331Y218366D02*
Y222751D01*
G01X1525835Y221776D02*
X1532331Y218366D01*
G01X1534496Y221776D02*
X1525835D01*
G01X1510861Y227539D02*
X1511583Y228514D01*
G01X1510139D02*
X1510861Y227539D01*
G01X1509417Y229001D02*
X1510139Y228514D01*
G01X1507974D02*
X1508696Y229001D01*
G01X1507252Y227539D02*
X1507974Y228514D01*
G01X1507252Y226565D02*
Y227539D01*
G01X1507974Y225590D02*
X1507252Y226565D01*
G01X1515192Y225590D02*
X1514470Y225103D01*
G01X1515913Y226565D02*
X1515192Y225590D01*
G01X1515913Y227539D02*
Y226565D01*
G01X1515192Y228514D02*
X1515913Y227539D01*
G01X1514470Y229001D02*
X1515192Y228514D01*
G01X1511583D02*
X1513026Y229488D01*
G01X1510861Y226565D02*
Y227539D01*
G01X1525835Y228110D02*
X1534496D01*
G01X1507252Y219257D02*
X1515913D01*
G01X1525835Y212519D02*
X1534496D01*
G01X1507252Y236796D02*
Y232898D01*
G01X1508696Y236309D02*
X1507252Y236796D01*
G01X1510139Y235822D02*
X1508696Y236309D01*
G01X1512304Y235334D02*
X1510139Y235822D01*
G01X1515913Y234847D02*
X1512304Y235334D01*
G01X1533774Y242726D02*
X1533053Y242239D01*
G01X1534496Y243700D02*
X1533774Y242726D01*
G01Y244675D02*
X1534496Y243700D01*
G01X1533053Y245162D02*
X1533774Y244675D01*
G01X1531609Y245649D02*
X1533053Y245162D01*
G01X1528722Y245649D02*
X1531609D01*
G01X1527278Y245162D02*
X1528722Y245649D01*
G01X1526556Y244675D02*
X1527278Y245162D01*
G01X1525835Y243700D02*
X1526556Y244675D01*
G01Y242726D02*
X1525835Y243700D01*
G01X1527278Y242239D02*
X1526556Y242726D01*
G01X1528722Y241752D02*
X1527278Y242239D01*
G01X1530165D02*
X1528722Y241752D01*
G01X1530887Y243700D02*
X1530165Y242239D01*
G01Y245162D02*
X1530887Y243700D01*
G01X1528722Y245649D02*
X1530165Y245162D01*
G01X1508696Y229001D02*
X1509417D01*
G01X1510861Y258720D02*
X1511583Y259695D01*
G01X1510861Y257746D02*
Y258720D01*
G01X1511583Y256771D02*
X1510861Y257746D01*
G01X1515913Y258720D02*
Y257746D01*
G01X1515192Y259695D02*
X1515913Y258720D01*
G01X1515192Y242155D02*
X1515913Y242642D01*
G01Y242155D02*
X1515192D01*
G01X1515913Y242642D02*
Y242155D01*
G01X1533774Y235418D02*
X1534496Y235905D01*
G01Y235418D02*
X1533774D01*
G01X1534496Y235905D02*
Y235418D01*
G01X1510139Y259695D02*
X1510861Y258720D01*
G01X1509417Y260182D02*
X1510139Y259695D01*
G01X1507974D02*
X1508696Y260182D01*
G01X1507252Y258720D02*
X1507974Y259695D01*
G01X1507252Y257746D02*
Y258720D01*
G01X1507974Y256771D02*
X1507252Y257746D01*
G01X1508696Y256284D02*
X1507974Y256771D01*
G01X1509417Y256284D02*
X1508696D01*
G01X1510139Y256771D02*
X1509417Y256284D01*
G01X1510861Y257746D02*
X1510139Y256771D01*
G01X1513748Y260669D02*
X1515192Y259695D01*
G01X1511583D02*
X1513026Y260669D01*
G01Y255797D02*
X1511583Y256771D01*
G01X1513748Y255797D02*
X1513026D01*
G01X1515192Y256771D02*
X1513748Y255797D01*
G01X1533774Y252470D02*
X1534496Y251496D01*
G01X1533053Y252957D02*
X1533774Y252470D01*
G01X1531609Y253445D02*
X1533053Y252957D01*
G01X1528722Y253445D02*
X1531609D01*
G01X1527278Y252957D02*
X1528722Y253445D01*
G01X1526556Y252470D02*
X1527278Y252957D01*
G01X1525835Y251496D02*
X1526556Y252470D01*
G01Y250521D02*
X1525835Y251496D01*
G01X1527278Y250034D02*
X1526556Y250521D01*
G01X1528722Y249547D02*
X1527278Y250034D01*
G01X1531609Y249547D02*
X1528722D01*
G01X1533053Y250034D02*
X1531609Y249547D01*
G01X1533774Y250521D02*
X1533053Y250034D01*
G01X1534496Y251496D02*
X1533774Y250521D01*
G01X1513748Y229488D02*
X1514470Y229001D01*
G01X1513026Y229488D02*
X1513748D01*
G01X1515913Y257746D02*
X1515192Y256771D01*
G01X1507252Y250438D02*
X1515913D01*
G01X1481465Y314827D02*
Y304591D01*
G01X1480480Y314827D02*
Y304591D01*
G01X1478315Y314827D02*
Y304591D01*
G01X1477331Y314827D02*
Y304591D01*
G01X1475165Y314827D02*
Y304591D01*
G01X1474181Y314827D02*
Y304591D01*
G01X1472016Y314827D02*
Y304591D01*
G01X1471031Y314827D02*
Y304591D01*
G01X1468866Y314827D02*
Y304591D01*
G01X1467882Y314827D02*
Y304591D01*
G01X1471031D02*
X1468866D01*
G01X1474181D02*
X1472016D01*
G01X1477331D02*
X1475165D01*
G01X1480480D02*
X1478315D01*
G01X1483630D02*
X1481465D01*
G01X1471031Y314827D02*
X1468866D01*
G01X1474181D02*
X1472016D01*
G01X1477331D02*
X1475165D01*
G01X1480480D02*
X1478315D01*
G01X1483630D02*
X1481465D01*
G01X1536661Y379568D02*
Y259724D01*
G01X1518079Y299785D02*
Y266461D01*
G01X1520047Y300654D02*
X1569096D01*
G01X1508696Y260182D02*
X1509417D01*
G01X1513026Y260669D02*
X1513748D01*
G01X1516110Y300654D02*
X1518079Y302622D01*
G01X1516110Y300654D02*
X1518079Y302622D01*
G01D02*
Y370063D01*
G01Y302622D02*
Y370063D01*
G01X1515126Y314827D02*
Y304591D01*
G01X1512961Y314827D02*
Y304591D01*
G01X1511976Y314827D02*
Y304591D01*
G01X1509811Y314827D02*
Y304591D01*
G01X1508827Y314827D02*
Y304591D01*
G01X1506661Y314827D02*
Y304591D01*
G01X1505677Y314827D02*
Y304591D01*
G01X1503512Y314827D02*
Y304591D01*
G01X1502528Y314827D02*
Y304591D01*
G01X1500362Y314827D02*
Y304591D01*
G01X1499378Y314827D02*
Y304591D01*
G01X1497213Y314827D02*
Y304591D01*
G01X1496228Y314827D02*
Y304591D01*
G01X1494063Y314827D02*
Y304591D01*
G01X1493079Y314827D02*
Y304591D01*
G01X1490913Y314827D02*
Y304591D01*
G01X1489929Y314827D02*
Y304591D01*
G01X1487764Y314827D02*
Y304591D01*
G01X1486780Y314827D02*
Y304591D01*
G01X1484614Y314827D02*
Y304591D01*
G01X1483630Y314827D02*
Y304591D01*
G01X1486780D02*
X1484614D01*
G01X1489929D02*
X1487764D01*
G01X1493079D02*
X1490913D01*
G01X1496228D02*
X1494063D01*
G01X1499378D02*
X1497213D01*
G01X1502528D02*
X1500362D01*
G01X1505677D02*
X1503512D01*
G01X1508827D02*
X1506661D01*
G01X1511976D02*
X1509811D01*
G01X1515126D02*
X1512961D01*
G01X1486780Y314827D02*
X1484614D01*
G01X1489929D02*
X1487764D01*
G01X1493079D02*
X1490913D01*
G01X1496228D02*
X1494063D01*
G01X1499378D02*
X1497213D01*
G01X1502528D02*
X1500362D01*
G01X1505677D02*
X1503512D01*
G01X1508827D02*
X1506661D01*
G01X1511976D02*
X1509811D01*
G01X1515126D02*
X1512961D01*
G01X1503586Y337202D02*
X1503099Y335759D01*
G01Y338646D02*
X1503586Y337202D01*
G01X1510894Y338646D02*
X1511868Y337202D01*
G01X1509920Y339367D02*
X1510894Y338646D01*
G01Y340089D02*
X1509920Y339367D01*
G01X1507971Y335037D02*
X1507484Y335759D01*
G01X1508945Y334315D02*
X1507971Y335037D01*
G01X1509920Y334315D02*
X1508945D01*
G01X1510894Y335037D02*
X1509920Y334315D01*
G01X1511868Y336480D02*
X1510894Y335037D01*
G01X1511868Y337202D02*
Y336480D01*
G01X1508945Y339367D02*
X1509920D01*
G01X1478251Y342976D02*
Y334315D01*
G01X1493355Y335037D02*
X1493842Y334315D01*
G01X1493355D02*
Y335037D01*
G01X1493842Y334315D02*
X1493355D01*
G01X1487021Y335037D02*
X1486047Y334315D01*
G01X1487508Y335759D02*
X1487021Y335037D01*
G01X1487995Y337202D02*
X1487508Y335759D01*
G01X1487995Y340089D02*
Y337202D01*
G01X1484098D02*
Y340089D01*
G01X1484585Y335759D02*
X1484098Y337202D01*
G01X1485072Y335037D02*
X1484585Y335759D01*
G01X1486047Y334315D02*
X1485072Y335037D01*
G01X1499688Y337202D02*
Y340089D01*
G01X1500176Y335759D02*
X1499688Y337202D01*
G01X1500663Y335037D02*
X1500176Y335759D01*
G01X1501637Y334315D02*
X1500663Y335037D01*
G01X1502612D02*
X1501637Y334315D01*
G01X1503099Y335759D02*
X1502612Y335037D01*
G01X1501637Y339367D02*
X1503099Y338646D01*
G01X1500176D02*
X1501637Y339367D01*
G01X1499688Y337202D02*
X1500176Y338646D01*
G01X1511381Y340811D02*
X1510894Y340089D01*
G01X1511381Y341533D02*
Y340811D01*
G01X1510894Y342255D02*
X1511381Y341533D01*
G01X1509920Y342976D02*
X1510894Y342255D01*
G01X1508945Y342976D02*
X1509920D01*
G01X1507971Y342255D02*
X1508945Y342976D01*
G01X1527157Y374000D02*
G03X1529941Y375153I0J3937D01*
G01X1522016Y374000D02*
G03X1518079Y370063I0J-3937D01*
G01X1522016Y374000D02*
G03X1518079Y370063I0J-3937D01*
G01X1527157Y374000D02*
G03X1529941Y375153I0J3937D01*
G01X1514662Y473291D02*
Y370063D01*
G01X1522016Y374000D02*
X1527157D01*
G01D02*
X1522016D01*
G01X1487508Y341533D02*
X1487995Y340089D01*
G01X1487021Y342255D02*
X1487508Y341533D01*
G01X1486047Y342976D02*
X1487021Y342255D01*
G01X1485072D02*
X1486047Y342976D01*
G01X1484585Y341533D02*
X1485072Y342255D01*
G01X1484098Y340089D02*
X1484585Y341533D01*
G01X1502612Y342255D02*
X1503099Y341533D01*
G01X1501637Y342976D02*
X1502612Y342255D01*
G01X1500663D02*
X1501637Y342976D01*
G01X1500176Y341533D02*
X1500663Y342255D01*
G01X1499688Y340089D02*
X1500176Y341533D01*
G01X1535508Y380721D02*
G03X1536661Y383505I-2784J2784D01*
G01X1535508Y380721D02*
G03X1536661Y383505I-2784J2784D01*
G01D02*
Y529374D01*
G01D02*
Y383505D01*
G01X1529941Y375153D02*
X1535508Y380721D01*
G01D02*
X1529941Y375153D01*
G01X1533939Y414315D02*
X1533868Y414170D01*
G01X1528458Y413225D02*
X1528529Y413443D01*
G01D02*
X1528601Y413806D01*
G01X1526109Y414824D02*
X1526038Y414461D01*
G01X1528174Y413443D02*
X1528245Y413879D01*
G01X1526465Y414824D02*
X1526394Y414388D01*
G01X1535007Y414170D02*
Y412425D01*
G01X1534651D02*
Y414170D01*
G01X1533868D02*
Y412425D01*
G01X1533512D02*
Y414170D01*
G01X1532729Y414242D02*
Y412425D01*
G01Y414751D02*
Y414533D01*
G01X1532373Y412425D02*
Y414751D01*
G01X1531804Y414170D02*
Y412425D01*
G01X1531448D02*
Y414170D01*
G01X1530665D02*
Y412425D01*
G01X1530309D02*
Y414170D01*
G01X1529526Y414242D02*
Y412425D01*
G01Y414751D02*
Y414533D01*
G01X1529170Y412425D02*
Y414751D01*
G01X1528245Y414388D02*
X1528174Y414824D01*
G01X1526394Y413879D02*
X1526465Y413443D01*
G01X1528601Y414461D02*
X1528529Y414824D01*
G01X1526038Y413806D02*
X1526109Y413443D01*
G01X1527889Y413007D02*
X1528174Y413443D01*
G01X1526750Y415260D02*
X1526465Y414824D01*
G01X1530736Y414315D02*
X1530665Y414170D01*
G01X1528316Y412934D02*
X1528458Y413225D01*
G01X1526323Y415333D02*
X1526181Y415042D01*
G01D02*
X1526109Y414824D01*
G01X1528601Y413806D02*
Y414461D01*
G01X1528245Y413879D02*
Y414388D01*
G01X1526394D02*
Y413879D01*
G01X1526038Y414461D02*
Y413806D01*
G01X1525469Y413879D02*
Y413588D01*
G01Y414751D02*
Y414461D01*
G01X1524330D02*
Y414751D01*
G01Y413588D02*
Y413879D01*
G01X1523760Y415842D02*
Y412425D01*
G01X1523333Y414461D02*
Y415842D01*
G01Y412425D02*
Y414024D01*
G01X1521340D02*
Y412425D01*
G01Y415842D02*
Y414461D01*
G01X1520913Y412425D02*
Y415842D01*
G01X1528529Y414824D02*
X1528458Y415042D01*
G01X1526109Y413443D02*
X1526181Y413225D01*
G01X1534864Y414533D02*
X1535007Y414170D01*
G01X1531661Y414533D02*
X1531804Y414170D01*
G01X1534651D02*
X1534579Y414315D01*
G01X1533512Y414170D02*
X1533441Y414315D01*
G01X1531448Y414170D02*
X1531376Y414315D01*
G01X1530309Y414170D02*
X1530238Y414315D01*
G01X1528458Y415042D02*
X1528316Y415333D01*
G01X1526181Y413225D02*
X1526323Y412934D01*
G01X1534010Y414388D02*
X1533939Y414315D01*
G01X1533797Y414461D02*
X1534010Y414679D01*
G01X1532871Y414388D02*
X1532729Y414242D01*
G01Y414533D02*
X1532871Y414679D01*
G01X1530807Y414388D02*
X1530736Y414315D01*
G01X1530594Y414461D02*
X1530807Y414679D01*
G01X1528102Y412716D02*
X1528316Y412934D01*
G01X1529668Y414388D02*
X1529526Y414242D01*
G01Y414533D02*
X1529668Y414679D01*
G01X1526536Y415551D02*
X1526323Y415333D01*
G01X1528174Y414824D02*
X1527889Y415260D01*
G01X1526465Y413443D02*
X1526750Y413007D01*
G01X1527746Y412498D02*
X1528102Y412716D01*
G01X1526892Y415769D02*
X1526536Y415551D01*
G01X1527675Y412861D02*
X1527889Y413007D01*
G01X1526963Y415406D02*
X1526750Y415260D01*
G01X1534722Y414679D02*
X1534864Y414533D01*
G01X1534579Y414315D02*
X1534508Y414388D01*
G01X1533583Y414679D02*
X1533797Y414461D01*
G01X1533441Y414315D02*
X1533369Y414388D01*
G01X1531519Y414679D02*
X1531661Y414533D01*
G01X1531376Y414315D02*
X1531305Y414388D01*
G01X1530380Y414679D02*
X1530594Y414461D01*
G01X1530238Y414315D02*
X1530166Y414388D01*
G01X1528316Y415333D02*
X1528102Y415551D01*
G01X1526323Y412934D02*
X1526536Y412716D01*
G01X1534152Y414461D02*
X1534010Y414388D01*
G01X1530949Y414461D02*
X1530807Y414388D01*
G01X1534010Y414679D02*
X1534224Y414751D01*
G01X1533085Y414461D02*
X1532871Y414388D01*
G01Y414679D02*
X1533085Y414751D01*
G01X1530807Y414679D02*
X1531021Y414751D01*
G01X1529882Y414461D02*
X1529668Y414388D01*
G01Y414679D02*
X1529882Y414751D01*
G01X1527889Y415260D02*
X1527675Y415406D01*
G01X1526750Y413007D02*
X1526963Y412861D01*
G01X1528102Y415551D02*
X1527746Y415769D01*
G01X1526536Y412716D02*
X1526892Y412498D01*
G01X1534508Y414388D02*
X1534366Y414461D01*
G01X1533369Y414388D02*
X1533227Y414461D01*
G01X1531305Y414388D02*
X1531163Y414461D01*
G01X1530166Y414388D02*
X1530024Y414461D01*
G01X1534508Y414751D02*
X1534722Y414679D01*
G01X1533369Y414751D02*
X1533583Y414679D01*
G01X1531305Y414751D02*
X1531519Y414679D01*
G01X1530166Y414751D02*
X1530380Y414679D01*
G01X1527675Y415406D02*
X1527319Y415478D01*
G01X1526963Y412861D02*
X1527319Y412789D01*
G01X1527746Y415769D02*
X1527319Y415842D01*
G01X1526892Y412498D02*
X1527319Y412425D01*
G01X1523333Y415842D02*
X1523760D01*
G01X1520913D02*
X1521340D01*
G01X1534224Y414751D02*
X1534508D01*
G01X1533085D02*
X1533369D01*
G01X1532373D02*
X1532729D01*
G01X1531021D02*
X1531305D01*
G01X1529882D02*
X1530166D01*
G01X1529170D02*
X1529526D01*
G01X1524330D02*
X1525469D01*
G01X1521340Y414461D02*
X1523333D01*
G01X1525469D02*
X1524330D01*
G01X1530024D02*
X1529882D01*
G01X1531163D02*
X1530949D01*
G01X1533227D02*
X1533085D01*
G01X1534366D02*
X1534152D01*
G01X1523333Y414024D02*
X1521340D01*
G01X1524330Y413879D02*
X1525469D01*
G01Y413588D02*
X1524330D01*
G01X1521340Y412425D02*
X1520913D01*
G01X1523760D02*
X1523333D01*
G01X1529526D02*
X1529170D01*
G01X1530665D02*
X1530309D01*
G01X1532729D02*
X1532373D01*
G01X1531804D02*
X1531448D01*
G01X1533868D02*
X1533512D01*
G01X1535007D02*
X1534651D01*
G01X1527319Y415842D02*
X1526892Y415769D01*
G01X1527319Y412425D02*
X1527746Y412498D01*
G01X1527319Y415478D02*
X1526963Y415406D01*
G01X1527319Y412789D02*
X1527675Y412861D01*
G01X1527813Y502150D02*
G03I-6900J0D01*
G01D02*
G03I-6900J0D01*
G01X1540598D02*
G03I-19685J0D01*
G01X1536661Y527127D02*
G03Y477172I-15748J-24978D01*
G01X1473760Y520548D02*
X1473891Y520015D01*
G01X1476108Y521480D02*
X1478064Y515886D01*
G01X1477542Y515220D02*
X1475717Y520148D01*
G01X1481194Y521480D02*
Y515220D01*
G01X1480411D02*
Y520148D01*
G01X1473108Y520015D02*
X1472847Y520415D01*
G01X1473239Y521081D02*
X1473760Y520548D01*
G01X1475717Y520148D02*
Y515220D01*
G01X1474934D02*
Y521480D01*
G01X1473891Y515886D02*
Y515220D01*
G01Y520015D02*
Y519749D01*
G01X1473108D02*
Y520015D01*
G01X1469196Y515220D02*
Y515886D01*
G01X1468153D02*
Y515220D01*
G01X1472847Y520415D02*
X1472456Y520681D01*
G01X1472717Y521347D02*
X1473239Y521081D01*
G01X1480411Y520148D02*
X1478586Y515220D01*
G01X1478064Y515886D02*
X1480020Y521480D01*
G01X1473891Y519749D02*
X1473760Y519216D01*
G01X1469326Y520015D02*
X1469457Y520548D01*
G01X1473760Y519216D02*
X1473500Y518817D01*
G01X1470239Y520415D02*
X1469978Y520015D01*
G01X1472847Y519216D02*
X1473108Y519749D01*
G01X1472456Y520681D02*
X1471804Y520814D01*
G01X1471935Y521480D02*
X1472717Y521347D01*
G01X1480020Y521480D02*
X1481194D01*
G01X1474934D02*
X1476108D01*
G01X1471413D02*
X1471935D01*
G01X1471804Y520814D02*
X1471282D01*
G01X1469978Y520015D02*
X1469326D01*
G01X1470239Y515886D02*
X1473891D01*
G01Y515220D02*
X1469196D01*
G01X1475717D02*
X1474934D01*
G01X1478586D02*
X1477542D01*
G01X1481194D02*
X1480411D01*
G01X1473500Y518817D02*
X1470239Y515886D01*
G01X1469196D02*
X1472847Y519216D01*
G01X1469457Y520548D02*
X1469978Y521081D01*
G01X1470500Y521347D02*
X1471413Y521480D01*
G01X1470630Y520681D02*
X1470239Y520415D01*
G01X1471282Y520814D02*
X1470630Y520681D01*
G01X1469978Y521081D02*
X1470500Y521347D01*
G01X1540598Y533311D02*
G03X1536661Y529374I0J-3937D01*
G01X1540598Y533311D02*
G03X1536661Y529374I0J-3937D01*
G01X1532278Y512109D02*
X1532213Y512511D01*
G01X1530572Y511639D02*
X1530638Y511237D01*
G01X1532606Y512176D02*
X1532541Y512511D01*
G01X1530244Y511572D02*
X1530310Y511237D01*
G01X1532541Y512511D02*
X1532475Y512712D01*
G01X1530310Y511237D02*
X1530375Y511036D01*
G01X1532475Y512712D02*
X1532344Y512980D01*
G01X1530375Y511036D02*
X1530507Y510768D01*
G01X1532606Y511572D02*
Y512176D01*
G01X1532278Y511639D02*
Y512109D01*
G01X1530572D02*
Y511639D01*
G01X1530244Y512176D02*
Y511572D01*
G01X1529719Y511639D02*
Y511371D01*
G01Y512444D02*
Y512176D01*
G01X1508574Y520711D02*
X1508492Y521213D01*
G01X1506442Y520124D02*
X1506524Y519622D01*
G01X1508984Y520794D02*
X1508902Y521213D01*
G01X1506031Y520040D02*
X1506114Y519622D01*
G01X1508902Y521213D02*
X1508820Y521464D01*
G01X1506114Y519622D02*
X1506196Y519370D01*
G01X1508820Y521464D02*
X1508656Y521799D01*
G01X1506196Y519370D02*
X1506360Y519035D01*
G01X1532213Y512511D02*
X1531950Y512913D01*
G01X1530638Y511237D02*
X1530900Y510835D01*
G01X1508492Y521213D02*
X1508164Y521716D01*
G01X1506524Y519622D02*
X1506852Y519119D01*
G01X1532344Y512980D02*
X1532147Y513181D01*
G01X1532475Y511036D02*
X1532541Y511237D01*
G01D02*
X1532606Y511572D01*
G01X1530310Y512511D02*
X1530244Y512176D01*
G01X1532213Y511237D02*
X1532278Y511639D01*
G01X1530638Y512511D02*
X1530572Y512109D01*
G01X1528669Y512176D02*
Y512444D01*
G01Y511371D02*
Y511639D01*
G01X1528144Y513449D02*
Y510299D01*
G01X1527751Y512176D02*
Y513449D01*
G01Y510299D02*
Y511774D01*
G01X1525913D02*
Y510299D01*
G01Y513449D02*
Y512176D01*
G01X1525520Y510299D02*
Y513449D01*
G01X1508984Y520040D02*
Y520794D01*
G01X1508574Y520124D02*
Y520711D01*
G01X1506442D02*
Y520124D01*
G01X1506031Y520794D02*
Y520040D01*
G01X1505375Y520124D02*
Y519789D01*
G01Y521129D02*
Y520794D01*
G01X1483411Y521480D02*
X1485367Y515886D01*
G01X1484845Y515220D02*
X1483020Y520148D01*
G01X1530507Y510768D02*
X1530703Y510567D01*
G01X1508656Y521799D02*
X1508410Y522051D01*
G01X1506360Y519035D02*
X1506606Y518784D01*
G01X1532344Y510768D02*
X1532475Y511036D01*
G01X1530507Y512980D02*
X1530375Y512712D01*
G01D02*
X1530310Y512511D01*
G01X1508820Y519370D02*
X1508902Y519622D01*
G01D02*
X1508984Y520040D01*
G01X1506114Y521213D02*
X1506031Y520794D01*
G01X1508492Y519622D02*
X1508574Y520124D01*
G01X1506524Y521213D02*
X1506442Y520711D01*
G01X1504063Y520794D02*
Y521129D01*
G01Y519789D02*
Y520124D01*
G01X1503407Y522386D02*
Y518449D01*
G01X1502915Y520794D02*
Y522386D01*
G01Y518449D02*
Y520292D01*
G01X1500618D02*
Y518449D01*
G01Y522386D02*
Y520794D01*
G01X1500126Y518449D02*
Y522386D01*
G01X1498433Y528409D02*
Y521294D01*
G01X1488497Y521480D02*
Y515220D01*
G01X1487715D02*
Y520148D01*
G01X1483020D02*
Y515220D01*
G01X1482237D02*
Y521480D01*
G01X1531950Y512913D02*
X1531753Y513047D01*
G01X1530900Y510835D02*
X1531097Y510701D01*
G01X1508164Y521716D02*
X1507918Y521883D01*
G01X1506852Y519119D02*
X1507098Y518951D01*
G01X1532147Y513181D02*
X1531819Y513382D01*
G01X1530703Y510567D02*
X1531031Y510366D01*
G01X1508410Y522051D02*
X1508000Y522302D01*
G01X1506606Y518784D02*
X1507016Y518533D01*
G01X1531950Y510835D02*
X1532213Y511237D01*
G01X1530900Y512913D02*
X1530638Y512511D01*
G01X1508656Y519035D02*
X1508820Y519370D01*
G01X1506360Y521799D02*
X1506196Y521464D01*
G01X1485367Y515886D02*
X1487323Y521480D01*
G01X1506196Y521464D02*
X1506114Y521213D01*
G01X1532147Y510567D02*
X1532344Y510768D01*
G01X1508164Y519119D02*
X1508492Y519622D01*
G01X1506852Y521716D02*
X1506524Y521213D01*
G01X1487715Y520148D02*
X1485889Y515220D01*
G01X1507918Y521883D02*
X1507508Y521967D01*
G01X1530703Y513181D02*
X1530507Y512980D01*
G01X1508410Y518784D02*
X1508656Y519035D01*
G01X1507098Y518951D02*
X1507508Y518868D01*
G01X1531753Y513047D02*
X1531425Y513114D01*
G01X1531097Y510701D02*
X1531425Y510634D01*
G01X1508000Y522302D02*
X1507508Y522386D01*
G01X1507016Y518533D02*
X1507508Y518449D01*
G01X1531819Y513382D02*
X1531425Y513449D01*
G01X1531031Y510366D02*
X1531425Y510299D01*
G01X1531753Y510701D02*
X1531950Y510835D01*
G01X1531097Y513047D02*
X1530900Y512913D01*
G01X1506606Y522051D02*
X1506360Y521799D01*
G01X1589811Y533311D02*
X1540598D01*
G01X1589811D02*
X1540598D01*
G01X1502915Y522386D02*
X1503407D01*
G01X1500126D02*
X1500618D01*
G01X1487323Y521480D02*
X1488497D01*
G01X1482237D02*
X1483411D01*
G01X1504063Y521129D02*
X1505375D01*
G01X1500618Y520794D02*
X1502915D01*
G01X1505375D02*
X1504063D01*
G01X1502915Y520292D02*
X1500618D01*
G01X1504063Y520124D02*
X1505375D01*
G01Y519789D02*
X1504063D01*
G01X1500618Y518449D02*
X1500126D01*
G01X1503407D02*
X1502915D01*
G01X1483020Y515220D02*
X1482237D01*
G01X1485889D02*
X1484845D01*
G01X1488497D02*
X1487715D01*
G01X1527751Y513449D02*
X1528144D01*
G01X1525520D02*
X1525913D01*
G01X1528669Y512444D02*
X1529719D01*
G01X1525913Y512176D02*
X1527751D01*
G01X1529719D02*
X1528669D01*
G01X1527751Y511774D02*
X1525913D01*
G01X1528669Y511639D02*
X1529719D01*
G01Y511371D02*
X1528669D01*
G01X1531819Y510366D02*
X1532147Y510567D01*
G01X1531031Y513382D02*
X1530703Y513181D01*
G01X1508000Y518533D02*
X1508410Y518784D01*
G01X1507918Y518951D02*
X1508164Y519119D01*
G01X1507098Y521883D02*
X1506852Y521716D01*
G01X1525913Y510299D02*
X1525520D01*
G01X1528144D02*
X1527751D01*
G01X1507508Y522386D02*
X1507016Y522302D01*
G01D02*
X1506606Y522051D01*
G01X1507508Y518449D02*
X1508000Y518533D01*
G01X1531425Y513449D02*
X1531031Y513382D01*
G01X1531425Y510299D02*
X1531819Y510366D01*
G01X1507508Y521967D02*
X1507098Y521883D01*
G01X1507508Y518868D02*
X1507918Y518951D01*
G01X1531425Y513114D02*
X1531097Y513047D01*
G01X1531425Y510634D02*
X1531753Y510701D01*
G01X1546504Y577957D02*
G03X1545913Y578547I-590J0D01*
G01X1546504Y561421D02*
G03X1545913Y562012I-591J0D01*
G01Y566500D02*
G03X1546504Y567091I0J591D01*
G01Y588173D02*
Y556874D01*
G01X1544929Y566500D02*
Y562012D01*
G01Y583035D02*
Y578547D01*
G01X1544535Y588173D02*
Y556874D01*
G01X1543354Y553626D02*
Y592996D01*
G01X1540992Y566500D02*
Y562012D01*
G01Y583035D02*
Y578547D01*
G01X1540205Y565634D02*
Y562878D01*
G01Y582169D02*
Y579413D01*
G01X1537843D02*
Y582169D01*
G01Y562878D02*
Y565634D01*
G01X1537055Y578547D02*
Y583035D01*
G01Y562012D02*
Y566500D01*
G01X1523276D02*
Y562012D01*
G01Y583035D02*
Y578547D01*
G01X1519339Y566500D02*
Y562012D01*
G01Y583035D02*
Y578547D01*
G01X1518551Y565634D02*
Y562878D01*
G01Y582169D02*
Y579413D01*
G01X1516189D02*
Y582169D01*
G01Y562878D02*
Y565634D01*
G01X1515402Y578547D02*
Y583035D01*
G01Y562012D02*
Y566500D01*
G01X1540205Y579413D02*
X1540992Y579298D01*
G01X1519339D02*
X1518551Y579413D01*
G01X1537055Y565749D02*
X1537843Y565634D01*
G01X1540205Y562878D02*
X1540992Y562762D01*
G01X1515402Y565749D02*
X1516189Y565634D01*
G01X1519339Y562762D02*
X1518551Y562878D01*
G01Y579413D02*
X1516189D01*
G01X1540205D02*
X1537843D01*
G01X1515402Y578547D02*
X1545913D01*
G01X1515402Y566500D02*
X1545913D01*
G01X1537843Y565634D02*
X1540205D01*
G01X1516189D02*
X1518551D01*
G01Y562878D02*
X1516189D01*
G01X1540205D02*
X1537843D01*
G01X1515402Y562012D02*
X1545913D01*
G01X1593748Y556874D02*
X1543354D01*
G01Y555201D02*
X1593748D01*
G01Y553626D02*
X1543354D01*
G01X1516189Y579413D02*
X1515402Y579298D01*
G01X1537843Y579413D02*
X1537055Y579298D01*
G01X1518551Y565634D02*
X1519339Y565749D01*
G01X1516189Y562878D02*
X1515402Y562762D01*
G01X1540205Y565634D02*
X1540992Y565749D01*
G01X1537843Y562878D02*
X1537055Y562762D01*
G01X1474612Y599807D02*
X1476568Y594213D01*
G01X1483349Y593547D02*
X1481524Y598475D01*
G01X1476046Y593547D02*
X1474220Y598475D01*
G01X1471612Y598342D02*
X1471351Y598742D01*
G01X1471743Y599408D02*
X1472264Y598875D01*
G01X1471351Y598742D02*
X1470960Y599008D01*
G01X1471221Y599674D02*
X1471743Y599408D01*
G01X1472264Y598875D02*
X1472395Y598342D01*
G01X1481524Y598475D02*
Y593547D01*
G01X1480741D02*
Y599807D01*
G01X1470960Y599008D02*
X1470308Y599141D01*
G01X1470438Y599807D02*
X1471221Y599674D01*
G01X1479698Y599807D02*
Y593547D01*
G01X1478915D02*
Y598475D01*
G01X1474220D02*
Y593547D01*
G01X1473438D02*
Y599807D01*
G01X1472395Y594213D02*
Y593547D01*
G01Y598342D02*
Y598076D01*
G01X1471612D02*
Y598342D01*
G01X1480741Y599807D02*
X1481915D01*
G01X1478524D02*
X1479698D01*
G01X1473438D02*
X1474612D01*
G01X1469917D02*
X1470438D01*
G01X1470308Y599141D02*
X1469786D01*
G01X1468482Y598342D02*
X1467830D01*
G01X1468743Y594213D02*
X1472395D01*
G01X1474220Y593547D02*
X1473438D01*
G01X1477090D02*
X1476046D01*
G01X1479698D02*
X1478915D01*
G01X1481524D02*
X1480741D01*
G01X1472395Y598076D02*
X1472264Y597543D01*
G01X1469004Y599674D02*
X1469917Y599807D01*
G01X1469786Y599141D02*
X1469134Y599008D01*
G01X1478915Y598475D02*
X1477090Y593547D01*
G01X1476568Y594213D02*
X1478524Y599807D01*
G01X1467830Y598342D02*
X1467961Y598875D01*
G01X1471351Y597543D02*
X1471612Y598076D01*
G01X1472264Y597543D02*
X1472003Y597143D01*
G01X1468743Y598742D02*
X1468482Y598342D01*
G01X1472003Y597143D02*
X1468743Y594213D01*
G01X1467961Y598875D02*
X1468482Y599408D01*
G01X1469134Y599008D02*
X1468743Y598742D01*
G01X1468482Y599408D02*
X1469004Y599674D01*
G01X1545913Y583035D02*
G03X1546504Y583626I0J591D01*
G01X1481915Y599807D02*
X1483871Y594213D01*
G01X1498433Y608311D02*
Y586264D01*
G01X1487001Y599807D02*
Y593547D01*
G01X1486218D02*
Y598475D01*
G01X1537055Y582285D02*
X1537843Y582169D01*
G01X1515402Y582285D02*
X1516189Y582169D01*
G01X1485827Y599807D02*
X1487001D01*
G01X1484393Y593547D02*
X1483349D01*
G01X1487001D02*
X1486218D01*
G01X1543354Y592996D02*
X1593748D01*
G01Y591421D02*
X1543354D01*
G01X1593748Y589846D02*
X1543354D01*
G01X1593748Y588173D02*
X1543354D01*
G01X1515402Y583035D02*
X1545913D01*
G01X1537843Y582169D02*
X1540205D01*
G01X1516189D02*
X1518551D01*
G01X1486218Y598475D02*
X1484393Y593547D01*
G01X1483871Y594213D02*
X1485827Y599807D01*
G01X1518551Y582169D02*
X1519339Y582285D01*
G01X1540205Y582169D02*
X1540992Y582285D01*
G01X1538261Y586973D02*
X1538379Y586883D01*
G01X1538291Y586762D02*
X1538232Y586823D01*
G01X1538379Y586883D02*
X1538468Y586762D01*
G01X1538320Y586672D02*
X1538291Y586762D01*
G01X1538468D02*
X1538497Y586672D01*
G01X1537405Y585586D02*
Y587004D01*
G01X1537582Y586853D02*
Y586400D01*
G01Y586220D02*
Y585586D01*
G01X1538320Y586581D02*
Y586672D01*
G01X1538497D02*
Y586551D01*
G01X1538291Y586491D02*
X1538320Y586581D01*
G01X1538497Y586551D02*
X1538468Y586461D01*
G01X1538232Y586823D02*
X1538143Y586853D01*
G01X1538114Y587004D02*
X1538261Y586973D01*
G01X1538468Y586461D02*
X1538379Y586340D01*
G01X1537582Y585586D02*
X1537405D01*
G01X1538114Y586220D02*
X1537582D01*
G01Y586400D02*
X1538143D01*
G01Y586853D02*
X1537582D01*
G01X1537405Y587004D02*
X1538114D01*
G01X1538232Y586431D02*
X1538291Y586491D01*
G01X1538261Y586250D02*
X1538114Y586220D01*
G01X1538379Y586340D02*
X1538261Y586250D01*
G01X1538143Y586400D02*
X1538232Y586431D01*
G01X1539359Y586762D02*
X1539182Y586551D01*
G01Y586793D02*
X1539359Y587004D01*
G01D02*
X1539536D01*
G01Y585586D02*
X1539359D01*
G01X1539536Y587004D02*
Y585586D01*
G01X1539359D02*
Y586762D01*
G01X1539182Y586551D02*
Y586793D01*
G01X1500672Y782204D02*
Y764881D01*
G01X1594636Y-589495D02*
Y-583195D01*
X1593696Y-584455D01*
G01Y-589495D02*
X1595576D01*
G01X1600936D02*
Y-583195D01*
X1599996Y-584455D01*
G01Y-589495D02*
X1601876D01*
G01X1556930Y39408D02*
X1557815Y38095D01*
G01X1556044Y40064D02*
X1556930Y39408D01*
G01Y40720D02*
X1556044Y40064D01*
G01X1557373Y41376D02*
X1556930Y40720D01*
G01X1557373Y42032D02*
Y41376D01*
G01X1556930Y42688D02*
X1557373Y42032D01*
G01X1556044Y43344D02*
X1556930Y42688D01*
G01X1555158Y43344D02*
X1556044D01*
G01X1554272Y42688D02*
X1555158Y43344D01*
G01X1554272Y36127D02*
X1553829Y36783D01*
G01X1555158Y35470D02*
X1554272Y36127D01*
G01X1556044Y35470D02*
X1555158D01*
G01X1556930Y36127D02*
X1556044Y35470D01*
G01X1557815Y37439D02*
X1556930Y36127D01*
G01X1557815Y38095D02*
Y37439D01*
G01X1555158Y40064D02*
X1556044D01*
G01X1569331Y36127D02*
X1569774Y35470D01*
G01X1569331D02*
Y36127D01*
G01X1569774Y35470D02*
X1569331D01*
G01X1582619Y36127D02*
X1582176Y36783D01*
G01X1583504Y35470D02*
X1582619Y36127D01*
G01X1584390Y35470D02*
X1583504D01*
G01X1585276Y36127D02*
X1584390Y35470D01*
G01X1585719Y36783D02*
X1585276Y36127D01*
G01X1586162Y38095D02*
X1585719Y36783D01*
G01Y39408D02*
X1586162Y38095D01*
G01X1585276Y40064D02*
X1585719Y39408D01*
G01X1584390Y40720D02*
X1585276Y40064D01*
G01X1583504Y40720D02*
X1584390D01*
G01X1582619Y40064D02*
X1583504Y40720D01*
G01X1583061Y43344D02*
X1582619Y40064D01*
G01X1585719Y43344D02*
X1583061D01*
G01X1575532Y36127D02*
X1575089Y36783D01*
G01X1576418Y35470D02*
X1575532Y36127D01*
G01X1577304Y35470D02*
X1576418D01*
G01X1578189Y36127D02*
X1577304Y35470D01*
G01X1578632Y36783D02*
X1578189Y36127D01*
G01X1579075Y38095D02*
X1578632Y36783D01*
G01Y39408D02*
X1579075Y38095D01*
G01X1578189Y40064D02*
X1578632Y39408D01*
G01X1577304Y40720D02*
X1578189Y40064D01*
G01X1576418Y40720D02*
X1577304D01*
G01X1575532Y40064D02*
X1576418Y40720D01*
G01X1575975Y43344D02*
X1575532Y40064D01*
G01X1578632Y43344D02*
X1575975D01*
G01X1564016Y40064D02*
X1562245Y38751D01*
G01X1564459Y40720D02*
X1564016Y40064D01*
G01X1564459Y42032D02*
Y40720D01*
G01X1564016Y42688D02*
X1564459Y42032D01*
G01X1563130Y43344D02*
X1564016Y42688D01*
G01X1562245Y43344D02*
X1563130D01*
G01X1561359Y42688D02*
X1562245Y43344D01*
G01X1560916Y42032D02*
X1561359Y42688D01*
G01X1560916Y35470D02*
X1564459D01*
G01X1561359Y37439D02*
X1560916Y35470D01*
G01X1562245Y38751D02*
X1561359Y37439D01*
G01X1588320Y64663D02*
G03X1592257Y68600I0J3937D01*
G01X1588320Y64663D02*
G03X1592257Y68600I0J3937D01*
G01X1585735Y72644D02*
X1585899Y72225D01*
G01X1582044Y72644D02*
X1582208Y72225D01*
G01X1578435Y73146D02*
X1578271Y73565D01*
G01X1578517Y71471D02*
X1578353Y71890D01*
G01X1585488Y72225D02*
X1585406Y72392D01*
G01X1584176Y72225D02*
X1584094Y72392D01*
G01X1581798Y72225D02*
X1581716Y72392D01*
G01X1592257Y133899D02*
Y68600D01*
G01Y133899D02*
Y68600D01*
G01X1575564Y71220D02*
X1575728Y70801D01*
G01X1580485Y72225D02*
X1580403Y72392D01*
G01X1575646Y72895D02*
X1575810Y72560D01*
G01X1578025Y73146D02*
X1577861Y73398D01*
G01X1576056Y72979D02*
X1576220Y72728D01*
G01X1578107Y71471D02*
X1577861Y71806D01*
G01X1575974Y71220D02*
X1576220Y70885D01*
G01X1585899Y72225D02*
Y70215D01*
G01X1585488D02*
Y72225D01*
G01X1584586D02*
Y70215D01*
G01X1584176D02*
Y72225D01*
G01X1583274Y72309D02*
Y70215D01*
G01Y72895D02*
Y72644D01*
G01X1582864Y70215D02*
Y72895D01*
G01X1582208Y72225D02*
Y70215D01*
G01X1581798D02*
Y72225D01*
G01X1580895D02*
Y70215D01*
G01X1580485D02*
Y72225D01*
G01X1579583Y72309D02*
Y70215D01*
G01Y72895D02*
Y72644D01*
G01X1579173Y70215D02*
Y72895D01*
G01X1578517Y71220D02*
Y71471D01*
G01X1578435Y72895D02*
Y73146D01*
G01X1578107Y71220D02*
Y71471D01*
G01X1578025Y72979D02*
Y73146D01*
G01X1576056D02*
Y72979D01*
G01X1575974Y71471D02*
Y71220D01*
G01X1575646Y73146D02*
Y72895D01*
G01X1575564Y71471D02*
Y71220D01*
G01X1574908Y71890D02*
Y71555D01*
G01Y72895D02*
Y72560D01*
G01X1573595D02*
Y72895D01*
G01Y71555D02*
Y71890D01*
G01X1572939Y74152D02*
Y70215D01*
G01X1572447Y72560D02*
Y74152D01*
G01Y70215D02*
Y72057D01*
G01X1570151D02*
Y70215D01*
G01Y74152D02*
Y72560D01*
G01X1569658Y70215D02*
Y74152D01*
G01X1585570Y72811D02*
X1585735Y72644D01*
G01X1585406Y72392D02*
X1585324Y72476D01*
G01X1584258Y72811D02*
X1584504Y72560D01*
G01X1584094Y72392D02*
X1584012Y72476D01*
G01X1581880Y72811D02*
X1582044Y72644D01*
G01X1581716Y72392D02*
X1581633Y72476D01*
G01X1580567Y72811D02*
X1580813Y72560D01*
G01X1580403Y72392D02*
X1580321Y72476D01*
G01X1578271Y73565D02*
X1578025Y73817D01*
G01X1575810Y72560D02*
X1576056Y72309D01*
G01X1575728Y70801D02*
X1575974Y70550D01*
G01X1563753Y88285D02*
Y64663D01*
G01X1577861Y73398D02*
X1577532Y73649D01*
G01X1578353Y71890D02*
X1578025Y72141D01*
G01X1576220Y72728D02*
X1576548Y72476D01*
G01X1584668Y72392D02*
X1584586Y72225D01*
G01X1578353Y70801D02*
X1578517Y71220D01*
G01X1575728Y71890D02*
X1575564Y71471D01*
G01X1575810Y73565D02*
X1575646Y73146D01*
G01X1578025Y73817D02*
X1577614Y74068D01*
G01X1575974Y70550D02*
X1576384Y70298D01*
G01X1580977Y72392D02*
X1580895Y72225D01*
G01X1578271Y72560D02*
X1578435Y72895D01*
G01X1585324Y72476D02*
X1585160Y72560D01*
G01X1584012Y72476D02*
X1583848Y72560D01*
G01X1581633Y72476D02*
X1581469Y72560D01*
G01X1580321Y72476D02*
X1580157Y72560D01*
G01X1578025Y72141D02*
X1577861Y72225D01*
G01Y71806D02*
X1577532Y71974D01*
G01X1576056Y72309D02*
X1576220Y72225D01*
G01Y70885D02*
X1576548Y70717D01*
G01X1577861Y70885D02*
X1578107Y71220D01*
G01X1577861Y72728D02*
X1578025Y72979D01*
G01X1576220Y73398D02*
X1576056Y73146D01*
G01X1585324Y72895D02*
X1585570Y72811D01*
G01X1584012Y72895D02*
X1584258Y72811D01*
G01X1581633Y72895D02*
X1581880Y72811D01*
G01X1580321Y72895D02*
X1580567Y72811D01*
G01X1576220Y71806D02*
X1575974Y71471D01*
G01X1577532Y73649D02*
X1577204Y73733D01*
G01X1576548Y72476D02*
X1576876Y72392D01*
G01X1577532Y71974D02*
X1577204Y72057D01*
G01X1576548Y70717D02*
X1576876Y70633D01*
G01X1584750Y72476D02*
X1584668Y72392D01*
G01X1584504Y72560D02*
X1584750Y72811D01*
G01X1583438Y72476D02*
X1583274Y72309D01*
G01Y72644D02*
X1583438Y72811D01*
G01X1581059Y72476D02*
X1580977Y72392D01*
G01X1580813Y72560D02*
X1581059Y72811D01*
G01X1578107Y70550D02*
X1578353Y70801D01*
G01X1579747Y72476D02*
X1579583Y72309D01*
G01Y72644D02*
X1579747Y72811D01*
G01X1578025Y72309D02*
X1578271Y72560D01*
G01X1576056Y73817D02*
X1575810Y73565D01*
G01X1577614Y74068D02*
X1577204Y74152D01*
G01X1576384Y70298D02*
X1576794Y70215D01*
G01X1577532Y72476D02*
X1577861Y72728D01*
G01X1576056Y72141D02*
X1575728Y71890D01*
G01X1576548Y73649D02*
X1576220Y73398D01*
G01X1572447Y74152D02*
X1572939D01*
G01X1569658D02*
X1570151D01*
G01X1577204D02*
X1576876D01*
G01X1577204Y73733D02*
X1576876D01*
G01X1584996Y72895D02*
X1585324D01*
G01X1583684D02*
X1584012D01*
G01X1582864D02*
X1583274D01*
G01X1581305D02*
X1581633D01*
G01X1579993D02*
X1580321D01*
G01X1579173D02*
X1579583D01*
G01X1573595D02*
X1574908D01*
G01X1570151Y72560D02*
X1572447D01*
G01X1574908D02*
X1573595D01*
G01X1580157D02*
X1579993D01*
G01X1581469D02*
X1581223D01*
G01X1583848D02*
X1583684D01*
G01X1585160D02*
X1584914D01*
G01X1576876Y72392D02*
X1577204D01*
G01X1572447Y72057D02*
X1570151D01*
G01X1577204D02*
X1576876D01*
G01X1573595Y71890D02*
X1574908D01*
G01Y71555D02*
X1573595D01*
G01X1576876Y70633D02*
X1577204D01*
G01X1576794Y70215D02*
X1577286D01*
G01X1570151D02*
X1569658D01*
G01X1572939D02*
X1572447D01*
G01X1579583D02*
X1579173D01*
G01X1580895D02*
X1580485D01*
G01X1583274D02*
X1582864D01*
G01X1582208D02*
X1581798D01*
G01X1584586D02*
X1584176D01*
G01X1585899D02*
X1585488D01*
G01X1577696Y70298D02*
X1578107Y70550D01*
G01X1576466Y74068D02*
X1576056Y73817D01*
G01X1584914Y72560D02*
X1584750Y72476D01*
G01X1581223Y72560D02*
X1581059Y72476D01*
G01X1577532Y70717D02*
X1577861Y70885D01*
G01Y72225D02*
X1578025Y72309D01*
G01X1576548Y71974D02*
X1576220Y71806D01*
G01Y72225D02*
X1576056Y72141D01*
G01X1576876Y74152D02*
X1576466Y74068D01*
G01X1577286Y70215D02*
X1577696Y70298D01*
G01X1576876Y73733D02*
X1576548Y73649D01*
G01X1577204Y72392D02*
X1577532Y72476D01*
G01X1576876Y72057D02*
X1576548Y71974D01*
G01X1577204Y70633D02*
X1577532Y70717D01*
G01X1584750Y72811D02*
X1584996Y72895D01*
G01X1583684Y72560D02*
X1583438Y72476D01*
G01Y72811D02*
X1583684Y72895D01*
G01X1581059Y72811D02*
X1581305Y72895D01*
G01X1579993Y72560D02*
X1579747Y72476D01*
G01Y72811D02*
X1579993Y72895D01*
G01X1592257Y88285D02*
X1563753D01*
G01X1581599Y146187D02*
G03X1578815Y147341I-2785J-2783D01*
G01X1592257Y133899D02*
G03X1591104Y136683I-3937J0D01*
G01X1581599Y146187D02*
G03X1578815Y147341I-2785J-2783D01*
G01X1592257Y133899D02*
G03X1591104Y136683I-3937J0D01*
G01D02*
X1581599Y146187D01*
G01X1591104Y136683D02*
X1581599Y146187D01*
G01X1592428Y303541D02*
X1592915Y302819D01*
G01X1592428D02*
Y303541D01*
G01X1592915Y302819D02*
X1592428D01*
G01X1586581Y308593D02*
X1585607Y307871D01*
G01X1587069Y309315D02*
X1586581Y308593D01*
G01X1587069Y310037D02*
Y309315D01*
G01X1583171D02*
Y310037D01*
G01X1583658Y308593D02*
X1583171Y309315D01*
G01X1584633Y307871D02*
X1583658Y308593D01*
G01X1582684Y305706D02*
X1583658Y307150D01*
G01X1582684Y304984D02*
Y305706D01*
G01X1583658Y303541D02*
X1582684Y304984D01*
G01X1587556D02*
X1586581Y303541D01*
G01X1587556Y305706D02*
Y304984D01*
G01X1587069Y306428D02*
X1587556Y305706D01*
G01X1586581Y307150D02*
X1587069Y306428D01*
G01X1585607Y307871D02*
X1586581Y307150D01*
G01X1584633Y307871D02*
X1585607D01*
G01X1583658Y307150D02*
X1584633Y307871D01*
G01X1585607Y302819D02*
X1584633D01*
G01X1586581Y303541D02*
X1585607Y302819D01*
G01X1598761Y308593D02*
X1599249Y310037D01*
G01X1598761Y305706D02*
Y308593D01*
G01X1599249Y304262D02*
X1598761Y305706D01*
G01X1599736Y303541D02*
X1599249Y304262D01*
G01X1600710Y302819D02*
X1599736Y303541D01*
G01X1601685D02*
X1600710Y302819D01*
G01X1602172Y304262D02*
X1601685Y303541D01*
G01X1602659Y305706D02*
X1602172Y304262D01*
G01Y307150D02*
X1602659Y305706D01*
G01X1600710Y307871D02*
X1602172Y307150D01*
G01X1599249D02*
X1600710Y307871D01*
G01X1598761Y305706D02*
X1599249Y307150D01*
G01X1577324Y311480D02*
Y302819D01*
G01X1584633D02*
X1583658Y303541D01*
G01X1586581Y310759D02*
X1587069Y310037D01*
G01X1585607Y311480D02*
X1586581Y310759D01*
G01X1584633Y311480D02*
X1585607D01*
G01X1583658Y310759D02*
X1584633Y311480D01*
G01X1583171Y310037D02*
X1583658Y310759D01*
G01X1601685D02*
X1602172Y310037D01*
G01X1600710Y311480D02*
X1601685Y310759D01*
G01X1599736D02*
X1600710Y311480D01*
G01X1599249Y310037D02*
X1599736Y310759D01*
G01X1609967Y307150D02*
X1610942Y305706D01*
G01X1608993Y307871D02*
X1609967Y307150D01*
G01Y308593D02*
X1608993Y307871D01*
G01X1610454Y309315D02*
X1609967Y308593D01*
G01X1610454Y310037D02*
Y309315D01*
G01X1607044Y303541D02*
X1606557Y304262D01*
G01X1608018Y302819D02*
X1607044Y303541D01*
G01X1608993Y302819D02*
X1608018D01*
G01X1609967Y303541D02*
X1608993Y302819D01*
G01X1610942Y304984D02*
X1609967Y303541D01*
G01X1610942Y305706D02*
Y304984D01*
G01X1608018Y307871D02*
X1608993D01*
G01X1609967Y310759D02*
X1610454Y310037D01*
G01X1608993Y311480D02*
X1609967Y310759D01*
G01X1608018Y311480D02*
X1608993D01*
G01X1607044Y310759D02*
X1608018Y311480D01*
G01X1558545Y562012D02*
G03X1558089Y561797I0J-591D01*
G01Y566715D02*
G03X1558545Y566500I456J376D01*
G01Y578547D02*
G03X1558089Y578332I0J-591D01*
G01X1557528Y567397D02*
X1558089Y566715D01*
G01X1557528Y571638D02*
Y556874D01*
G01Y588173D02*
Y573409D01*
G01X1558089Y561797D02*
X1557528Y561115D01*
G01X1577510Y578547D02*
X1558545D01*
G01X1593354Y577346D02*
X1557528D01*
G01Y573409D02*
X1593354D01*
G01Y571638D02*
X1557528D01*
G01X1593354Y567701D02*
X1557528D01*
G01X1558545Y566500D02*
X1577510D01*
G01Y562012D02*
X1558545D01*
G01X1593354Y560811D02*
X1557528D01*
G01X1558089Y578332D02*
X1557528Y577650D01*
G01X1593748Y533311D02*
X1608802D01*
G01X1625800Y536198D02*
X1624825Y535476D01*
G01X1626287Y536920D02*
X1625800Y536198D01*
G01X1626774Y538363D02*
X1626287Y536920D01*
G01X1626774Y541251D02*
Y538363D01*
G01X1626287Y542694D02*
X1626774Y541251D01*
G01X1625800Y543416D02*
X1626287Y542694D01*
G01X1624825Y544138D02*
X1625800Y543416D01*
G01X1623851D02*
X1624825Y544138D01*
G01X1623364Y542694D02*
X1623851Y543416D01*
G01X1622876Y541251D02*
X1623364Y542694D01*
G01X1622876Y538363D02*
Y541251D01*
G01X1623364Y536920D02*
X1622876Y538363D01*
G01X1623851Y536198D02*
X1623364Y536920D01*
G01X1624825Y535476D02*
X1623851Y536198D01*
G01X1615081Y537642D02*
X1619466D01*
G01X1618492Y544138D02*
X1615081Y537642D01*
G01X1618492Y535476D02*
Y544138D01*
G01X1589811Y533311D02*
G03X1593748Y537248I0J3937D01*
G01X1589811Y533311D02*
G03X1593748Y537248I0J3937D01*
G01D02*
Y602546D01*
G01D02*
Y537248D01*
G01X1580746Y579594D02*
G03X1581150Y580154I-187J560D01*
G01Y564893D02*
G03X1580746Y565454I-591J0D01*
G01Y563058D02*
G03X1581150Y563619I-187J560D01*
G01X1577510Y578547D02*
G03X1577697Y578578I-2J590D01*
G01Y566470D02*
G03X1577510Y566500I-186J-561D01*
G01Y562012D02*
G03X1577697Y562042I1J591D01*
G01X1593354Y573409D02*
X1593748Y573016D01*
G01X1593354Y556874D02*
X1593748Y556480D01*
G01X1593354Y571638D02*
Y556874D01*
G01Y588173D02*
Y573409D01*
G01X1586324Y565880D02*
Y579266D01*
G01X1581543D02*
Y565880D01*
G01X1581206Y579266D02*
Y565880D01*
G01X1581150Y564893D02*
Y563619D01*
G01X1577606Y566492D02*
Y562020D01*
G01Y583028D02*
Y578555D01*
G01X1593354Y577346D02*
X1593748Y577183D01*
G01Y560648D02*
X1593354Y560811D01*
G01X1577697Y566470D02*
X1580746Y565454D01*
G01X1593748Y579266D02*
X1581206D01*
G01Y565880D02*
X1593748D01*
G01X1593354Y571638D02*
X1593748Y572032D01*
G01X1593354Y567701D02*
X1593748Y567864D01*
G01X1580746Y563058D02*
X1577697Y562042D01*
G01X1580746Y579594D02*
X1577697Y578578D01*
G01X1558089Y583250D02*
G03X1558545Y583035I456J376D01*
G01X1557528Y583932D02*
X1558089Y583250D01*
G01X1593354Y584236D02*
X1557528D01*
G01X1558545Y583035D02*
X1577510D01*
G01X1581150Y581429D02*
G03X1580746Y581989I-591J0D01*
G01X1577697Y583005D02*
G03X1577510Y583035I-186J-560D01*
G01X1581150Y581429D02*
Y580154D01*
G01X1577697Y583005D02*
X1580746Y581989D01*
G01X1593748Y588567D02*
X1593354Y588173D01*
G01Y584236D02*
X1593748Y584399D01*
G01Y606483D02*
Y666030D01*
G01Y602546D02*
G03X1592595Y605330I-3937J0D01*
G01X1583090Y614835D02*
G03X1580306Y615988I-2784J-2784D01*
G01X1583090Y614835D02*
G03X1580306Y615988I-2784J-2784D01*
G01X1593748Y602546D02*
G03X1592595Y605330I-3937J0D01*
G01D02*
X1583090Y614835D01*
G01D02*
X1592595Y605330D01*
G01X1589417Y703490D02*
Y707875D01*
G01X1582921Y706901D02*
X1589417Y703490D01*
G01X1591583Y706901D02*
X1582921D01*
G01X1590861Y680592D02*
X1590139Y680104D01*
G01X1591583Y681566D02*
X1590861Y680592D01*
G01X1591583Y682540D02*
Y681566D01*
G01X1590861Y683515D02*
X1591583Y682540D01*
G01X1590139Y684002D02*
X1590861Y683515D01*
G01X1588696Y684489D02*
X1590139Y684002D01*
G01X1587252D02*
X1588696Y684489D01*
G01X1586530Y683515D02*
X1587252Y684002D01*
G01X1585808Y682540D02*
X1586530Y683515D01*
G01X1585808Y681566D02*
Y682540D01*
G01X1586530Y680592D02*
X1585808Y681566D01*
G01X1582921Y681079D02*
X1586530Y680592D01*
G01X1582921Y684002D02*
Y681079D01*
G01X1590861Y697157D02*
X1591583Y697644D01*
G01Y697157D02*
X1590861D01*
G01X1591583Y697644D02*
Y697157D01*
G01X1583643Y690823D02*
X1584365Y691310D01*
G01X1582921Y689848D02*
X1583643Y690823D01*
G01Y688874D02*
X1582921Y689848D01*
G01X1584365Y688387D02*
X1583643Y688874D01*
G01X1585808Y687900D02*
X1584365Y688387D01*
G01X1588696Y687900D02*
X1585808D01*
G01X1590139Y688387D02*
X1588696Y687900D01*
G01X1590861Y688874D02*
X1590139Y688387D01*
G01X1591583Y689848D02*
X1590861Y688874D01*
G01Y690823D02*
X1591583Y689848D01*
G01X1590139Y691310D02*
X1590861Y690823D01*
G01X1588696Y691797D02*
X1590139Y691310D01*
G01X1587252D02*
X1588696Y691797D01*
G01X1586530Y689848D02*
X1587252Y691310D01*
G01Y688387D02*
X1586530Y689848D01*
G01X1588696Y687900D02*
X1587252Y688387D01*
G01X1582921Y674258D02*
X1591583D01*
G01X1583643Y712260D02*
X1582921Y713234D01*
G01X1584365Y711773D02*
X1583643Y712260D01*
G01X1585808Y711285D02*
X1584365Y711773D01*
G01X1588696Y711285D02*
X1585808D01*
G01X1590139Y711773D02*
X1588696Y711285D01*
G01X1590861Y712260D02*
X1590139Y711773D01*
G01X1591583Y713234D02*
X1590861Y712260D01*
G01Y714209D02*
X1591583Y713234D01*
G01X1590139Y714696D02*
X1590861Y714209D01*
G01X1588696Y715183D02*
X1590139Y714696D01*
G01X1585808Y715183D02*
X1588696D01*
G01X1584365Y714696D02*
X1585808Y715183D01*
G01X1583643Y714209D02*
X1584365Y714696D01*
G01X1582921Y713234D02*
X1583643Y714209D01*
G01X1594636Y771135D02*
Y777435D01*
X1593696Y776175D01*
G01Y771135D02*
X1595576D01*
G01X1600936D02*
Y777435D01*
X1599996Y776175D01*
G01Y771135D02*
X1601876D01*
G01X1703822Y-562678D02*
Y-306893D01*
G01X1632133Y536198D02*
X1632621Y535476D01*
G01X1632133D02*
Y536198D01*
G01X1632621Y535476D02*
X1632133D01*
G01X1638467Y537642D02*
X1642852D01*
G01X1641877Y544138D02*
X1638467Y537642D01*
G01X1641877Y535476D02*
Y544138D01*
G01X1649185Y541251D02*
X1650160Y544138D01*
G01X1648698Y539085D02*
X1649185Y541251D01*
G01X1648211Y535476D02*
X1648698Y539085D01*
G01X1650160Y544138D02*
X1646262D01*
G01X1719570Y764881D02*
Y-578426D01*
G01X1736892Y782204D02*
Y-595749D01*
G01X1724093Y-519417D02*
Y-513117D01*
X1727069D01*
G01X1725973Y-516162D02*
X1724093D01*
G01X1719570Y-398899D02*
X1736892D01*
G01X1727148Y-283196D02*
X1724014D01*
Y-276896D01*
X1727148D01*
G01X1725894Y-279941D02*
X1724014D01*
G01X1719570Y-162678D02*
X1736892D01*
G01X1723858Y-46976D02*
Y-40676D01*
X1725424D01*
X1726051Y-40991D01*
X1726521Y-41411D01*
X1726913Y-42041D01*
X1727226Y-42776D01*
X1727304Y-43826D01*
X1727226Y-44876D01*
X1726913Y-45611D01*
X1726521Y-46241D01*
X1726051Y-46661D01*
X1725424Y-46976D01*
X1723858D01*
G01X1719570Y73542D02*
X1736892D01*
G01X1727304Y195020D02*
X1726834Y195335D01*
X1726286Y195545D01*
X1725659D01*
X1724954Y195230D01*
X1724406Y194705D01*
X1724014Y194075D01*
X1723701Y193025D01*
X1723623Y192080D01*
X1723779Y191135D01*
X1724014Y190505D01*
X1724484Y189875D01*
X1725033Y189455D01*
X1725581Y189245D01*
X1726129D01*
X1726678Y189455D01*
X1727148Y189770D01*
X1727539Y190190D01*
G01X1719570Y309763D02*
X1736892D01*
G01X1726208Y428825D02*
X1726521Y429140D01*
X1726756Y429665D01*
X1726913Y430400D01*
X1726756Y431030D01*
X1726443Y431450D01*
X1725894Y431765D01*
X1723779D01*
Y425465D01*
X1726364D01*
X1726913Y425885D01*
X1727226Y426515D01*
X1727383Y427250D01*
X1727226Y427985D01*
X1726756Y428615D01*
X1726208Y428825D01*
X1723779D01*
G01X1719570Y545983D02*
X1736892D01*
G01X1723623Y661686D02*
X1725581Y667986D01*
X1727539Y661686D01*
G01X1726834Y663891D02*
X1724328D01*
M02*
